G04 ================== begin FILE IDENTIFICATION RECORD ==================*
G04 Layout Name:  13130-1b.brd*
G04 Film Name:    L12*
G04 File Format:  Gerber RS274X*
G04 File Origin:  Cadence Allegro 16.5-S037*
G04 Origin Date:  Thu Nov 13 17:27:23 2014*
G04 *
G04 Layer:  VIA CLASS/BOTTOM*
G04 Layer:  PIN/BOTTOM*
G04 Layer:  ETCH/BOTTOM*
G04 Layer:  DRAWING FORMAT/LAYER_PCB_STORY*
G04 Layer:  DRAWING FORMAT/LAYER_L12*
G04 *
G04 Offset:    (0.00 0.00)*
G04 Mirror:    No*
G04 Mode:      Positive*
G04 Rotation:  0*
G04 FullContactRelief:  No*
G04 UndefLineWidth:     6.00*
G04 ================== end FILE IDENTIFICATION RECORD ====================*
%FSLAX35Y35*MOIN*%
%IR0*IPPOS*OFA0.00000B0.00000*MIA0B0*SFA1.00000B1.00000*%
%AMMACRO31*
4,1,40,.008,.009,
-.008,.009,
-.008347,.00897,
-.008684,.008879,
-.009,.008732,
-.009286,.008532,
-.009532,.008286,
-.009732,.008,
-.009879,.007684,
-.00997,.007347,
-.01,.007,
-.01,-.007,
-.00997,-.007347,
-.009879,-.007684,
-.009732,-.008,
-.009532,-.008286,
-.009286,-.008532,
-.009,-.008732,
-.008684,-.008879,
-.008347,-.00897,
-.008,-.009,
.008,-.009,
.008347,-.00897,
.008684,-.008879,
.009,-.008732,
.009286,-.008532,
.009532,-.008286,
.009732,-.008,
.009879,-.007684,
.00997,-.007347,
.01,-.007,
.01,.007,
.00997,.007347,
.009879,.007684,
.009732,.008,
.009532,.008286,
.009286,.008532,
.009,.008732,
.008684,.008879,
.008347,.00897,
.008,.009,
0.0*
%
%ADD31MACRO31*%
%ADD10C,.01*%
%ADD15C,.02*%
%ADD70R,.102X.076*%
%ADD48C,.022*%
%AMMACRO19*
4,1,40,-.009,.01,
.009,.01,
.009347,.00997,
.009684,.009879,
.01,.009732,
.010286,.009532,
.010532,.009286,
.010732,.009,
.010879,.008684,
.01097,.008347,
.011,.008,
.011,-.008,
.01097,-.008347,
.010879,-.008684,
.010732,-.009,
.010532,-.009286,
.010286,-.009532,
.01,-.009732,
.009684,-.009879,
.009347,-.00997,
.009,-.01,
-.009,-.01,
-.009347,-.00997,
-.009684,-.009879,
-.01,-.009732,
-.010286,-.009532,
-.010532,-.009286,
-.010732,-.009,
-.010879,-.008684,
-.01097,-.008347,
-.011,-.008,
-.011,.008,
-.01097,.008347,
-.010879,.008684,
-.010732,.009,
-.010532,.009286,
-.010286,.009532,
-.01,.009732,
-.009684,.009879,
-.009347,.00997,
-.009,.01,
0.0*
%
%ADD19MACRO19*%
%ADD11C,.04*%
%ADD52R,.126X.091*%
%ADD37C,.032*%
%AMMACRO20*
4,1,40,.01,.009,
.01,-.009,
.00997,-.009347,
.009879,-.009684,
.009732,-.01,
.009532,-.010286,
.009286,-.010532,
.009,-.010732,
.008684,-.010879,
.008347,-.01097,
.008,-.011,
-.008,-.011,
-.008347,-.01097,
-.008684,-.010879,
-.009,-.010732,
-.009286,-.010532,
-.009532,-.010286,
-.009732,-.01,
-.009879,-.009684,
-.00997,-.009347,
-.01,-.009,
-.01,.009,
-.00997,.009347,
-.009879,.009684,
-.009732,.01,
-.009532,.010286,
-.009286,.010532,
-.009,.010732,
-.008684,.010879,
-.008347,.01097,
-.008,.011,
.008,.011,
.008347,.01097,
.008684,.010879,
.009,.010732,
.009286,.010532,
.009532,.010286,
.009732,.01,
.009879,.009684,
.00997,.009347,
.01,.009,
0.0*
%
%ADD20MACRO20*%
%ADD93R,.047X.108*%
%ADD92C,.06*%
%ADD59C,.024*%
%ADD27R,.028X.126*%
%ADD24R,.108X.047*%
%ADD46R,.008X.035*%
%ADD44R,.035X.008*%
%ADD61C,.017*%
%ADD45R,.008X.027*%
%ADD43R,.027X.008*%
%AMMACRO34*
4,1,40,-.0155,-.016,
-.0155,.016,
-.015439,.016695,
-.015259,.017368,
-.014964,.018,
-.014564,.018571,
-.014071,.019064,
-.0135,.019464,
-.012868,.019759,
-.012195,.019939,
-.0115,.02,
.0115,.02,
.012195,.019939,
.012868,.019759,
.0135,.019464,
.014071,.019064,
.014564,.018571,
.014964,.018,
.015259,.017368,
.015439,.016695,
.0155,.016,
.0155,-.016,
.015439,-.016695,
.015259,-.017368,
.014964,-.018,
.014564,-.018571,
.014071,-.019064,
.0135,-.019464,
.012868,-.019759,
.012195,-.019939,
.0115,-.02,
-.0115,-.02,
-.012195,-.019939,
-.012868,-.019759,
-.0135,-.019464,
-.014071,-.019064,
-.014564,-.018571,
-.014964,-.018,
-.015259,-.017368,
-.015439,-.016695,
-.0155,-.016,
0.0*
%
%ADD34MACRO34*%
%AMMACRO33*
4,1,40,-.016,.0155,
.016,.0155,
.016695,.015439,
.017368,.015259,
.018,.014964,
.018571,.014564,
.019064,.014071,
.019464,.0135,
.019759,.012868,
.019939,.012195,
.02,.0115,
.02,-.0115,
.019939,-.012195,
.019759,-.012868,
.019464,-.0135,
.019064,-.014071,
.018571,-.014564,
.018,-.014964,
.017368,-.015259,
.016695,-.015439,
.016,-.0155,
-.016,-.0155,
-.016695,-.015439,
-.017368,-.015259,
-.018,-.014964,
-.018571,-.014564,
-.019064,-.014071,
-.019464,-.0135,
-.019759,-.012868,
-.019939,-.012195,
-.02,-.0115,
-.02,.0115,
-.019939,.012195,
-.019759,.012868,
-.019464,.0135,
-.019064,.014071,
-.018571,.014564,
-.018,.014964,
-.017368,.015259,
-.016695,.015439,
-.016,.0155,
0.0*
%
%ADD33MACRO33*%
%ADD26R,.028X.165*%
%ADD12C,.028*%
%ADD58C,.056*%
%AMMACRO64*
4,1,40,.002,-.016,
.003389,-.015878,
.004736,-.015518,
.006,-.014928,
.007142,-.014128,
.008128,-.013142,
.008928,-.012,
.009518,-.010736,
.009878,-.009389,
.01,-.008,
.01,.008,
.009878,.009389,
.009518,.010736,
.008928,.012,
.008128,.013142,
.007142,.014128,
.006,.014928,
.004736,.015518,
.003389,.015878,
.002,.016,
-.002,.016,
-.003389,.015878,
-.004736,.015518,
-.006,.014928,
-.007142,.014128,
-.008128,.013142,
-.008928,.012,
-.009518,.010736,
-.009878,.009389,
-.01,.008,
-.01,-.008,
-.009878,-.009389,
-.009518,-.010736,
-.008928,-.012,
-.008128,-.013142,
-.007142,-.014128,
-.006,-.014928,
-.004736,-.015518,
-.003389,-.015878,
-.002,-.016,
.002,-.016,
0.0*
%
%ADD64MACRO64*%
%AMMACRO91*
4,1,40,.0155,.016,
.0155,-.016,
.015439,-.016695,
.015259,-.017368,
.014964,-.018,
.014564,-.018571,
.014071,-.019064,
.0135,-.019464,
.012868,-.019759,
.012195,-.019939,
.0115,-.02,
-.0115,-.02,
-.012195,-.019939,
-.012868,-.019759,
-.0135,-.019464,
-.014071,-.019064,
-.014564,-.018571,
-.014964,-.018,
-.015259,-.017368,
-.015439,-.016695,
-.0155,-.016,
-.0155,.016,
-.015439,.016695,
-.015259,.017368,
-.014964,.018,
-.014564,.018571,
-.014071,.019064,
-.0135,.019464,
-.012868,.019759,
-.012195,.019939,
-.0115,.02,
.0115,.02,
.012195,.019939,
.012868,.019759,
.0135,.019464,
.014071,.019064,
.014564,.018571,
.014964,.018,
.015259,.017368,
.015439,.016695,
.0155,.016,
0.0*
%
%ADD91MACRO91*%
%AMMACRO35*
4,1,40,-.008,-.009,
.008,-.009,
.008347,-.00897,
.008684,-.008879,
.009,-.008732,
.009286,-.008532,
.009532,-.008286,
.009732,-.008,
.009879,-.007684,
.00997,-.007347,
.01,-.007,
.01,.007,
.00997,.007347,
.009879,.007684,
.009732,.008,
.009532,.008286,
.009286,.008532,
.009,.008732,
.008684,.008879,
.008347,.00897,
.008,.009,
-.008,.009,
-.008347,.00897,
-.008684,.008879,
-.009,.008732,
-.009286,.008532,
-.009532,.008286,
-.009732,.008,
-.009879,.007684,
-.00997,.007347,
-.01,.007,
-.01,-.007,
-.00997,-.007347,
-.009879,-.007684,
-.009732,-.008,
-.009532,-.008286,
-.009286,-.008532,
-.009,-.008732,
-.008684,-.008879,
-.008347,-.00897,
-.008,-.009,
0.0*
%
%ADD35MACRO35*%
%AMMACRO25*
4,1,40,.009,-.008,
.009,.008,
.00897,.008347,
.008879,.008684,
.008732,.009,
.008532,.009286,
.008286,.009532,
.008,.009732,
.007684,.009879,
.007347,.00997,
.007,.01,
-.007,.01,
-.007347,.00997,
-.007684,.009879,
-.008,.009732,
-.008286,.009532,
-.008532,.009286,
-.008732,.009,
-.008879,.008684,
-.00897,.008347,
-.009,.008,
-.009,-.008,
-.00897,-.008347,
-.008879,-.008684,
-.008732,-.009,
-.008532,-.009286,
-.008286,-.009532,
-.008,-.009732,
-.007684,-.009879,
-.007347,-.00997,
-.007,-.01,
.007,-.01,
.007347,-.00997,
.007684,-.009879,
.008,-.009732,
.008286,-.009532,
.008532,-.009286,
.008732,-.009,
.008879,-.008684,
.00897,-.008347,
.009,-.008,
0.0*
%
%ADD25MACRO25*%
%AMMACRO32*
4,1,40,.0055,-.0145,
.006889,-.014378,
.008236,-.014018,
.0095,-.013428,
.010642,-.012628,
.011628,-.011642,
.012428,-.0105,
.013018,-.009236,
.013378,-.007889,
.0135,-.0065,
.0135,.0065,
.013378,.007889,
.013018,.009236,
.012428,.0105,
.011628,.011642,
.010642,.012628,
.0095,.013428,
.008236,.014018,
.006889,.014378,
.0055,.0145,
-.0055,.0145,
-.006889,.014378,
-.008236,.014018,
-.0095,.013428,
-.010642,.012628,
-.011628,.011642,
-.012428,.0105,
-.013018,.009236,
-.013378,.007889,
-.0135,.0065,
-.0135,-.0065,
-.013378,-.007889,
-.013018,-.009236,
-.012428,-.0105,
-.011628,-.011642,
-.010642,-.012628,
-.0095,-.013428,
-.008236,-.014018,
-.006889,-.014378,
-.0055,-.0145,
.0055,-.0145,
0.0*
%
%ADD32MACRO32*%
%AMMACRO72*
4,1,6,.0135,.025,
-.0065,.005,
-.0135,.005,
-.0135,-.005,
-.0065,-.005,
.0135,-.025,
.0135,.025,
0.0*
%
%ADD72MACRO72*%
%AMMACRO55*
4,1,6,-.005,.0135,
-.005,.0065,
-.025,-.0135,
.025,-.0135,
.005,.0065,
.005,.0135,
-.005,.0135,
0.0*
%
%ADD55MACRO55*%
%AMMACRO90*
4,1,40,.0155,.016,
.0155,-.016,
.015439,-.016695,
.015259,-.017368,
.014964,-.018,
.014564,-.018571,
.014071,-.019064,
.0135,-.019464,
.012868,-.019759,
.012195,-.019939,
.0115,-.02,
-.0115,-.02,
-.012195,-.019939,
-.012868,-.019759,
-.0135,-.019464,
-.014071,-.019064,
-.014564,-.018571,
-.014964,-.018,
-.015259,-.017368,
-.015439,-.016695,
-.0155,-.016,
-.0155,.016,
-.015439,.016695,
-.015259,.017368,
-.014964,.018,
-.014564,.018571,
-.014071,.019064,
-.0135,.019464,
-.012868,.019759,
-.012195,.019939,
-.0115,.02,
.0115,.02,
.012195,.019939,
.012868,.019759,
.0135,.019464,
.014071,.019064,
.014564,.018571,
.014964,.018,
.015259,.017368,
.015439,.016695,
.0155,.016,
0.0*
%
%ADD90MACRO90*%
%AMMACRO36*
4,1,40,-.008,-.009,
.008,-.009,
.008347,-.00897,
.008684,-.008879,
.009,-.008732,
.009286,-.008532,
.009532,-.008286,
.009732,-.008,
.009879,-.007684,
.00997,-.007347,
.01,-.007,
.01,.007,
.00997,.007347,
.009879,.007684,
.009732,.008,
.009532,.008286,
.009286,.008532,
.009,.008732,
.008684,.008879,
.008347,.00897,
.008,.009,
-.008,.009,
-.008347,.00897,
-.008684,.008879,
-.009,.008732,
-.009286,.008532,
-.009532,.008286,
-.009732,.008,
-.009879,.007684,
-.00997,.007347,
-.01,.007,
-.01,-.007,
-.00997,-.007347,
-.009879,-.007684,
-.009732,-.008,
-.009532,-.008286,
-.009286,-.008532,
-.009,-.008732,
-.008684,-.008879,
-.008347,-.00897,
-.008,-.009,
0.0*
%
%ADD36MACRO36*%
%AMMACRO17*
4,1,40,.009,-.008,
.009,.008,
.00897,.008347,
.008879,.008684,
.008732,.009,
.008532,.009286,
.008286,.009532,
.008,.009732,
.007684,.009879,
.007347,.00997,
.007,.01,
-.007,.01,
-.007347,.00997,
-.007684,.009879,
-.008,.009732,
-.008286,.009532,
-.008532,.009286,
-.008732,.009,
-.008879,.008684,
-.00897,.008347,
-.009,.008,
-.009,-.008,
-.00897,-.008347,
-.008879,-.008684,
-.008732,-.009,
-.008532,-.009286,
-.008286,-.009532,
-.008,-.009732,
-.007684,-.009879,
-.007347,-.00997,
-.007,-.01,
.007,-.01,
.007347,-.00997,
.007684,-.009879,
.008,-.009732,
.008286,-.009532,
.008532,-.009286,
.008732,-.009,
.008879,-.008684,
.00897,-.008347,
.009,-.008,
0.0*
%
%ADD17MACRO17*%
%ADD57R,.03X.014*%
%ADD51R,.014X.03*%
%ADD87R,.022X.032*%
%ADD39R,.014X.032*%
%ADD38R,.032X.014*%
%ADD23R,.061X.012*%
%ADD89R,.032X.042*%
%ADD67R,.025X.012*%
%ADD63R,.014X.032*%
%ADD62R,.032X.014*%
%ADD54R,.034X.012*%
%ADD53R,.012X.034*%
%ADD69R,.012X.026*%
%ADD68R,.026X.012*%
%ADD14R,.042X.032*%
%ADD75R,.061X.024*%
%AMMACRO18*
4,1,40,.009,-.01,
-.009,-.01,
-.009347,-.00997,
-.009684,-.009879,
-.01,-.009732,
-.010286,-.009532,
-.010532,-.009286,
-.010732,-.009,
-.010879,-.008684,
-.01097,-.008347,
-.011,-.008,
-.011,.008,
-.01097,.008347,
-.010879,.008684,
-.010732,.009,
-.010532,.009286,
-.010286,.009532,
-.01,.009732,
-.009684,.009879,
-.009347,.00997,
-.009,.01,
.009,.01,
.009347,.00997,
.009684,.009879,
.01,.009732,
.010286,.009532,
.010532,.009286,
.010732,.009,
.010879,.008684,
.01097,.008347,
.011,.008,
.011,-.008,
.01097,-.008347,
.010879,-.008684,
.010732,-.009,
.010532,-.009286,
.010286,-.009532,
.01,-.009732,
.009684,-.009879,
.009347,-.00997,
.009,-.01,
0.0*
%
%ADD18MACRO18*%
%AMMACRO16*
4,1,40,-.01,-.009,
-.01,.009,
-.00997,.009347,
-.009879,.009684,
-.009732,.01,
-.009532,.010286,
-.009286,.010532,
-.009,.010732,
-.008684,.010879,
-.008347,.01097,
-.008,.011,
.008,.011,
.008347,.01097,
.008684,.010879,
.009,.010732,
.009286,.010532,
.009532,.010286,
.009732,.01,
.009879,.009684,
.00997,.009347,
.01,.009,
.01,-.009,
.00997,-.009347,
.009879,-.009684,
.009732,-.01,
.009532,-.010286,
.009286,-.010532,
.009,-.010732,
.008684,-.010879,
.008347,-.01097,
.008,-.011,
-.008,-.011,
-.008347,-.01097,
-.008684,-.010879,
-.009,-.010732,
-.009286,-.010532,
-.009532,-.010286,
-.009732,-.01,
-.009879,-.009684,
-.00997,-.009347,
-.01,-.009,
0.0*
%
%ADD16MACRO16*%
%ADD65R,.04X.073*%
%ADD42R,.012X.055*%
%ADD66R,.073X.04*%
%AMMACRO49*
4,1,40,.0155,.016,
.0155,-.016,
.015439,-.016695,
.015259,-.017368,
.014964,-.018,
.014564,-.018571,
.014071,-.019064,
.0135,-.019464,
.012868,-.019759,
.012195,-.019939,
.0115,-.02,
-.0115,-.02,
-.012195,-.019939,
-.012868,-.019759,
-.0135,-.019464,
-.014071,-.019064,
-.014564,-.018571,
-.014964,-.018,
-.015259,-.017368,
-.015439,-.016695,
-.0155,-.016,
-.0155,.016,
-.015439,.016695,
-.015259,.017368,
-.014964,.018,
-.014564,.018571,
-.014071,.019064,
-.0135,.019464,
-.012868,.019759,
-.012195,.019939,
-.0115,.02,
.0115,.02,
.012195,.019939,
.012868,.019759,
.0135,.019464,
.014071,.019064,
.014564,.018571,
.014964,.018,
.015259,.017368,
.015439,.016695,
.0155,.016,
0.0*
%
%ADD49MACRO49*%
%AMMACRO29*
4,1,40,.016,-.0155,
-.016,-.0155,
-.016695,-.015439,
-.017368,-.015259,
-.018,-.014964,
-.018571,-.014564,
-.019064,-.014071,
-.019464,-.0135,
-.019759,-.012868,
-.019939,-.012195,
-.02,-.0115,
-.02,.0115,
-.019939,.012195,
-.019759,.012868,
-.019464,.0135,
-.019064,.014071,
-.018571,.014564,
-.018,.014964,
-.017368,.015259,
-.016695,.015439,
-.016,.0155,
.016,.0155,
.016695,.015439,
.017368,.015259,
.018,.014964,
.018571,.014564,
.019064,.014071,
.019464,.0135,
.019759,.012868,
.019939,.012195,
.02,.0115,
.02,-.0115,
.019939,-.012195,
.019759,-.012868,
.019464,-.0135,
.019064,-.014071,
.018571,-.014564,
.018,-.014964,
.017368,-.015259,
.016695,-.015439,
.016,-.0155,
0.0*
%
%ADD29MACRO29*%
%ADD13R,.037X.061*%
%ADD77R,.138X.181*%
%ADD28R,.061X.037*%
%ADD73R,.071X.047*%
%AMMACRO86*
4,1,40,-.002,.016,
-.003389,.015878,
-.004736,.015518,
-.006,.014928,
-.007142,.014128,
-.008128,.013142,
-.008928,.012,
-.009518,.010736,
-.009878,.009389,
-.01,.008,
-.01,-.008,
-.009878,-.009389,
-.009518,-.010736,
-.008928,-.012,
-.008128,-.013142,
-.007142,-.014128,
-.006,-.014928,
-.004736,-.015518,
-.003389,-.015878,
-.002,-.016,
.002,-.016,
.003389,-.015878,
.004736,-.015518,
.006,-.014928,
.007142,-.014128,
.008128,-.013142,
.008928,-.012,
.009518,-.010736,
.009878,-.009389,
.01,-.008,
.01,.008,
.009878,.009389,
.009518,.010736,
.008928,.012,
.008128,.013142,
.007142,.014128,
.006,.014928,
.004736,.015518,
.003389,.015878,
.002,.016,
-.002,.016,
0.0*
%
%ADD86MACRO86*%
%AMMACRO60*
4,1,40,-.016,-.002,
-.015878,-.003389,
-.015518,-.004736,
-.014928,-.006,
-.014128,-.007142,
-.013142,-.008128,
-.012,-.008928,
-.010736,-.009518,
-.009389,-.009878,
-.008,-.01,
.008,-.01,
.009389,-.009878,
.010736,-.009518,
.012,-.008928,
.013142,-.008128,
.014128,-.007142,
.014928,-.006,
.015518,-.004736,
.015878,-.003389,
.016,-.002,
.016,.002,
.015878,.003389,
.015518,.004736,
.014928,.006,
.014128,.007142,
.013142,.008128,
.012,.008928,
.010736,.009518,
.009389,.009878,
.008,.01,
-.008,.01,
-.009389,.009878,
-.010736,.009518,
-.012,.008928,
-.013142,.008128,
-.014128,.007142,
-.014928,.006,
-.015518,.004736,
-.015878,.003389,
-.016,.002,
-.016,-.002,
0.0*
%
%ADD60MACRO60*%
%ADD50R,.079X.022*%
%ADD76R,.177X.181*%
%ADD74R,.075X.095*%
%ADD40R,.128X.128*%
%ADD41R,.089X.076*%
%ADD47R,.169X.169*%
%AMMACRO88*
4,1,40,-.0145,-.0055,
-.014378,-.006889,
-.014018,-.008236,
-.013428,-.0095,
-.012628,-.010642,
-.011642,-.011628,
-.0105,-.012428,
-.009236,-.013018,
-.007889,-.013378,
-.0065,-.0135,
.0065,-.0135,
.007889,-.013378,
.009236,-.013018,
.0105,-.012428,
.011642,-.011628,
.012628,-.010642,
.013428,-.0095,
.014018,-.008236,
.014378,-.006889,
.0145,-.0055,
.0145,.0055,
.014378,.006889,
.014018,.008236,
.013428,.0095,
.012628,.010642,
.011642,.011628,
.0105,.012428,
.009236,.013018,
.007889,.013378,
.0065,.0135,
-.0065,.0135,
-.007889,.013378,
-.009236,.013018,
-.0105,.012428,
-.011642,.011628,
-.012628,.010642,
-.013428,.0095,
-.014018,.008236,
-.014378,.006889,
-.0145,.0055,
-.0145,-.0055,
0.0*
%
%ADD88MACRO88*%
%AMMACRO21*
4,1,40,-.009,.008,
-.009,-.008,
-.00897,-.008347,
-.008879,-.008684,
-.008732,-.009,
-.008532,-.009286,
-.008286,-.009532,
-.008,-.009732,
-.007684,-.009879,
-.007347,-.00997,
-.007,-.01,
.007,-.01,
.007347,-.00997,
.007684,-.009879,
.008,-.009732,
.008286,-.009532,
.008532,-.009286,
.008732,-.009,
.008879,-.008684,
.00897,-.008347,
.009,-.008,
.009,.008,
.00897,.008347,
.008879,.008684,
.008732,.009,
.008532,.009286,
.008286,.009532,
.008,.009732,
.007684,.009879,
.007347,.00997,
.007,.01,
-.007,.01,
-.007347,.00997,
-.007684,.009879,
-.008,.009732,
-.008286,.009532,
-.008532,.009286,
-.008732,.009,
-.008879,.008684,
-.00897,.008347,
-.009,.008,
0.0*
%
%ADD21MACRO21*%
%AMMACRO30*
4,1,40,.008,.009,
-.008,.009,
-.008347,.00897,
-.008684,.008879,
-.009,.008732,
-.009286,.008532,
-.009532,.008286,
-.009732,.008,
-.009879,.007684,
-.00997,.007347,
-.01,.007,
-.01,-.007,
-.00997,-.007347,
-.009879,-.007684,
-.009732,-.008,
-.009532,-.008286,
-.009286,-.008532,
-.009,-.008732,
-.008684,-.008879,
-.008347,-.00897,
-.008,-.009,
.008,-.009,
.008347,-.00897,
.008684,-.008879,
.009,-.008732,
.009286,-.008532,
.009532,-.008286,
.009732,-.008,
.009879,-.007684,
.00997,-.007347,
.01,-.007,
.01,.007,
.00997,.007347,
.009879,.007684,
.009732,.008,
.009532,.008286,
.009286,.008532,
.009,.008732,
.008684,.008879,
.008347,.00897,
.008,.009,
0.0*
%
%ADD30MACRO30*%
%AMMACRO56*
4,1,6,-.025,.0135,
-.005,-.0065,
-.005,-.0135,
.005,-.0135,
.005,-.0065,
.025,.0135,
-.025,.0135,
0.0*
%
%ADD56MACRO56*%
%AMMACRO71*
4,1,6,.0135,.005,
.0065,.005,
-.0135,.025,
-.0135,-.025,
.0065,-.005,
.0135,-.005,
.0135,.005,
0.0*
%
%ADD71MACRO71*%
%AMMACRO22*
4,1,40,-.009,.008,
-.009,-.008,
-.00897,-.008347,
-.008879,-.008684,
-.008732,-.009,
-.008532,-.009286,
-.008286,-.009532,
-.008,-.009732,
-.007684,-.009879,
-.007347,-.00997,
-.007,-.01,
.007,-.01,
.007347,-.00997,
.007684,-.009879,
.008,-.009732,
.008286,-.009532,
.008532,-.009286,
.008732,-.009,
.008879,-.008684,
.00897,-.008347,
.009,-.008,
.009,.008,
.00897,.008347,
.008879,.008684,
.008732,.009,
.008532,.009286,
.008286,.009532,
.008,.009732,
.007684,.009879,
.007347,.00997,
.007,.01,
-.007,.01,
-.007347,.00997,
-.007684,.009879,
-.008,.009732,
-.008286,.009532,
-.008532,.009286,
-.008732,.009,
-.008879,.008684,
-.00897,.008347,
-.009,.008,
0.0*
%
%ADD22MACRO22*%
%ADD94C,.012*%
%ADD95C,.014*%
%ADD96C,.015*%
%ADD97C,.025*%
%ADD98C,.018*%
%ADD99C,.004*%
%ADD100C,.006*%
%ADD101C,.005*%
%ADD102C,.007*%
%ADD103C,.008*%
%ADD104C,.009*%
%ADD105C,.0045*%
%ADD106C,.0055*%
%ADD107C,.0085*%
%ADD108C,.0095*%
%ADD115C,.05204*%
%ADD114C,.04404*%
%ADD118C,.02704*%
%ADD125C,.03804*%
%ADD111C,.09204*%
%ADD121C,.08404*%
%ADD124C,.06804*%
%ADD120C,.09176*%
%ADD109R,.01X.01*%
%ADD116R,.01X.02*%
%ADD113R,.02X.01*%
%ADD117R,.01X.021*%
%ADD122R,.01X.022*%
%ADD123R,.023X.01*%
%ADD119R,.01X.025*%
%ADD110R,.025X.01*%
%ADD112C,.11004*%
G75*
%LPD*%
G75*
G36*
G01X22843Y75004D02*
G03X13957I-4443J1196D01*
G02X13571Y74500I-386J-104D01*
G01X4500D01*
X3000Y76000D01*
Y286500D01*
X4000Y287500D01*
X33000D01*
X33500Y287000D01*
Y280000D01*
X31500Y278000D01*
Y270000D01*
X30500Y269000D01*
X20000D01*
X18500Y270500D01*
X16973D01*
G03X16827I-73J-1500D01*
G01X12000D01*
X8000Y266500D01*
X6500D01*
X5500Y265500D01*
Y236000D01*
X6500Y235000D01*
X10000D01*
X11000Y234000D01*
Y216000D01*
X6500Y211500D01*
Y187500D01*
X14000Y180000D01*
Y170500D01*
X17740Y166760D01*
X17755Y166724D01*
G03X20224Y164255I4245J1776D01*
G01X20260Y164240D01*
X21500Y163000D01*
Y142000D01*
X23923Y139577D01*
X23910Y139480D01*
G03X23898Y139300I1390J-183D01*
G01Y137700D01*
G03X23987Y137209I1402J1D01*
G01X24000Y137175D01*
Y137000D01*
X23500Y136500D01*
X22500D01*
X20000Y134000D01*
Y132361D01*
G03X19998Y132300I1399J-76D01*
G01Y130700D01*
G03X20000Y130639I1401J15D01*
G01Y128917D01*
G03X21806Y125145I2300J-1217D01*
G01X21866Y125134D01*
X25500Y121500D01*
X34000D01*
X35500Y120000D01*
X47000D01*
X50000Y117000D01*
X67000D01*
X82750Y132750D01*
X87250D01*
X95000Y140500D01*
X105500D01*
X107000Y139000D01*
X113500D01*
X115000Y140500D01*
X121000D01*
X122000Y139500D01*
Y138500D01*
X121500Y138000D01*
X119500D01*
X113300Y131800D01*
Y129800D01*
X112000Y128500D01*
X100500D01*
X98000Y126000D01*
Y108000D01*
X106500Y99500D01*
Y91500D01*
X105000Y90000D01*
X96500D01*
X93500Y93000D01*
Y110500D01*
X88000Y116000D01*
X79500D01*
X62000Y98500D01*
Y95825D01*
X61987Y95791D01*
G03X61898Y95300I1313J-492D01*
G01Y93898D01*
X61500Y93500D01*
X52000D01*
X46600Y98900D01*
Y101400D01*
X46500Y101500D01*
Y111500D01*
X42000Y116000D01*
X22000D01*
X20500Y114500D01*
Y101500D01*
X22000Y100000D01*
X32500D01*
X32898Y99602D01*
Y98202D01*
X30900D01*
G03X29686Y97500I0J-1401D01*
G01X29000D01*
X27318Y95818D01*
X27291Y95804D01*
G03X26196Y94709I1209J-2304D01*
G01X26182Y94682D01*
X26000Y94500D01*
Y94222D01*
X25993Y94196D01*
G03Y92804I2507J-696D01*
G01X26000Y92778D01*
Y79500D01*
X26500Y79000D01*
Y75500D01*
X25500Y74500D01*
X23229D01*
G02X22843Y75004I0J400D01*
G37*
G36*
G01X31299Y196201D02*
X31298Y196117D01*
G03X32000Y194488I2202J-17D01*
G01Y189100D01*
X31000Y188100D01*
X19470D01*
G02X19167Y188761I0J400D01*
G03X16153Y188458I-1667J1439D01*
G01X16230Y188398D01*
Y188100D01*
X15900D01*
X12500Y191500D01*
Y198200D01*
X13500Y199200D01*
X17000D01*
X17500Y198700D01*
X25300D01*
X27000Y197000D01*
X30500D01*
X31299Y196201D01*
G37*
G36*
G01X25500Y103000D02*
X23000Y105500D01*
Y114500D01*
X23298Y114798D01*
X40702D01*
X44000Y111500D01*
Y104500D01*
X42500Y103000D01*
X41590D01*
G03X41410I-90J-2200D01*
G01X25500D01*
G37*
G36*
G01X33500Y165000D02*
X35500Y163000D01*
Y144000D01*
X35000Y143500D01*
X24000D01*
X23000Y144500D01*
Y163500D01*
X23740Y164240D01*
X23776Y164255D01*
G03X24987Y165000I-1777J4245D01*
G01X33500D01*
G37*
G36*
G01X52500Y137500D02*
X37500D01*
X37000Y138000D01*
Y161500D01*
X38500Y163000D01*
X52000D01*
X53000Y162000D01*
Y138000D01*
X52500Y137500D01*
G37*
G36*
G01X66000Y42000D02*
X62500D01*
X61500Y43000D01*
Y60000D01*
X62500Y61000D01*
X68500D01*
X75000Y54500D01*
Y47500D01*
X74000Y46500D01*
X70500D01*
X66000Y42000D01*
G37*
G36*
G01X59300Y188898D02*
G03X59791Y188987I-1J1402D01*
G01X59825Y189000D01*
X60175D01*
X60209Y188987D01*
G03X60700Y188898I492J1313D01*
G01X62300D01*
G03X62791Y188987I-1J1402D01*
G01X62825Y189000D01*
X63175D01*
X63209Y188987D01*
G03X63700Y188898I492J1313D01*
G01X65300D01*
G03X65791Y188987I-1J1402D01*
G01X65825Y189000D01*
X66175D01*
X66209Y188987D01*
G03X66700Y188898I492J1313D01*
G01X68300D01*
G03X68480Y188910I-3J1402D01*
G01X68577Y188923D01*
X69000Y188500D01*
Y183000D01*
X72500Y179500D01*
Y173500D01*
X72000Y173000D01*
X70000D01*
X61500Y181500D01*
Y185500D01*
X61000Y186000D01*
X55500D01*
X55345Y185845D01*
X55296Y185831D01*
G03X54269Y184804I424J-1451D01*
G01X54255Y184755D01*
X53376Y183876D01*
X53012D01*
X51694Y185194D01*
X53500Y187000D01*
Y193500D01*
X53868Y193868D01*
X55132D01*
X55500Y193500D01*
Y190000D01*
X56500Y189000D01*
X57175D01*
X57209Y188987D01*
G03X57700Y188898I492J1313D01*
G01X59300D01*
G37*
G36*
G01X68835Y201000D02*
X70928Y198907D01*
X70917Y198810D01*
G03X71898Y196449I2583J-311D01*
G01Y193192D01*
X70898Y192192D01*
Y191398D01*
X69500Y190000D01*
X69199D01*
X68998Y190202D01*
X57299D01*
X57000Y190500D01*
Y194000D01*
X56000Y195000D01*
X55699D01*
X55498Y195202D01*
X53502D01*
X53301Y195000D01*
X49500D01*
X48800Y195700D01*
Y199600D01*
X48900Y199700D01*
X56200D01*
X57500Y201000D01*
X68835D01*
G37*
G36*
G01X104408Y235602D02*
X101810Y233004D01*
X101717Y233012D01*
G03X98899Y230194I-226J-2592D01*
G01X98907Y230101D01*
X95804Y226998D01*
Y224804D01*
X94500Y223500D01*
X94125D01*
X94091Y223513D01*
G03X93600Y223602I-492J-1313D01*
G01X92000D01*
G03X90599Y222200I0J-1401D01*
G02X90399Y222000I-200J0D01*
G01X84500D01*
X78000Y215500D01*
Y212000D01*
X74500Y208500D01*
X71500D01*
X67500Y212500D01*
X58668D01*
G03X57338Y212901I-1268J-1800D01*
G02X56926Y213301I-12J400D01*
G01Y214774D01*
X62991D01*
X63217Y215000D01*
X65500D01*
X66500Y216000D01*
Y217139D01*
G03X66502Y217200I-1399J76D01*
G01Y218800D01*
G03X66500Y218861I-1401J-15D01*
G01Y219000D01*
X67000Y219500D01*
X73000D01*
X73500Y219000D01*
X74093D01*
X74112Y218996D01*
G03X75110I499J2554D01*
G01X75129Y219000D01*
X75500D01*
X75675Y219175D01*
X75708Y219190D01*
G03X76971Y220453I-1097J2360D01*
G01X76986Y220486D01*
X77500Y221000D01*
Y230000D01*
X80000Y232500D01*
Y235000D01*
X80423Y235423D01*
X80520Y235410D01*
G03X80700Y235398I183J1390D01*
G01X82300D01*
G03X82791Y235487I-1J1402D01*
G01X82825Y235500D01*
X83000D01*
X83500Y236000D01*
Y236074D01*
X83525Y236119D01*
G03X83702Y236800I-1225J682D01*
G01Y238200D01*
G03X83525Y238881I-1402J-1D01*
G01X83500Y238926D01*
Y239333D01*
X83550Y239389D01*
G03X83941Y239976I-1950J1723D01*
G03X84400Y239898I461J1324D01*
G01X86000D01*
G03X86491Y239987I-1J1402D01*
G01X86525Y240000D01*
X86875D01*
X86909Y239987D01*
G03X87400Y239898I492J1313D01*
G01X89000D01*
G03X90301Y240778I0J1402D01*
G01X90316Y240816D01*
X90500Y241000D01*
Y245187D01*
G03Y248213I-1600J1513D01*
G01Y248978D01*
X90507Y249004D01*
G03Y250396I-2507J696D01*
G01X90500Y250422D01*
Y255000D01*
X90000Y255500D01*
X89325D01*
X89291Y255513D01*
G03X88800Y255602I-492J-1313D01*
G01X87398D01*
X87000Y256000D01*
Y267435D01*
X91413Y271848D01*
X116235D01*
X116387Y272000D01*
X116500D01*
X118500Y274000D01*
X137000D01*
X153000Y258000D01*
Y257861D01*
G03X152998Y257800I1399J-76D01*
G01Y256200D01*
G03X153000Y256139I1401J15D01*
G01Y251500D01*
X154000Y250500D01*
X167500D01*
X168500Y251500D01*
Y264500D01*
X169500Y265500D01*
X249000D01*
X254000Y260500D01*
Y249000D01*
X252000Y247000D01*
X225000D01*
X222500Y244500D01*
Y234000D01*
X223119Y233381D01*
G03X223881Y232619I2181J1419D01*
G01X242250Y214250D01*
Y195750D01*
X239658Y193158D01*
X239602Y193145D01*
G03X237992Y190365I498J-2145D01*
G01X238000Y190337D01*
Y185000D01*
X237526Y184526D01*
X236562D01*
X230000Y191088D01*
Y198500D01*
X235000Y203500D01*
Y209000D01*
X223101Y220899D01*
X223102Y220982D01*
G03X220482Y223602I-2602J18D01*
G01X220399Y223601D01*
X217500Y226500D01*
X212500D01*
X206000Y220000D01*
X205000D01*
X204000Y221000D01*
Y222000D01*
X208500Y226500D01*
Y235000D01*
X206500Y237000D01*
X191000D01*
X188750Y234750D01*
Y226250D01*
X183000Y220500D01*
X140500D01*
X139000Y222000D01*
X119000D01*
X114882Y226118D01*
X114867Y226159D01*
G03X110606Y225208I-2067J-759D01*
G01X110615Y225115D01*
X110000Y224500D01*
X99500D01*
X99008Y224992D01*
Y225672D01*
X101172Y227836D01*
X101265Y227828D01*
G03X104083Y230646I226J2592D01*
G01X104075Y230739D01*
X105734Y232398D01*
X109437D01*
X110498Y231338D01*
X110502Y231262D01*
G03X112838Y233598I2198J138D01*
G01X112762Y233602D01*
X110763Y235602D01*
X104408D01*
G37*
G36*
G01X63500Y238500D02*
X63000Y239000D01*
Y250138D01*
X63013Y250210D01*
G03X63102Y250700I-1313J492D01*
G01Y252300D01*
G03X63013Y252791I-1402J-1D01*
G01X63000Y252825D01*
Y253138D01*
X63013Y253210D01*
G03X63102Y253700I-1313J492D01*
G01Y255300D01*
G03X63013Y255791I-1402J-1D01*
G01X63000Y255825D01*
Y257378D01*
X63007Y257404D01*
G03Y258796I-2507J696D01*
G01X63000Y258822D01*
Y260338D01*
X63013Y260410D01*
G03X63102Y260900I-1313J492D01*
G01Y262500D01*
G03X63013Y262991I-1402J-1D01*
G01X63000Y263025D01*
Y263438D01*
X63013Y263510D01*
G03X63102Y264000I-1313J492D01*
G01Y265600D01*
G03X63013Y266091I-1402J-1D01*
G01X63000Y266125D01*
Y266500D01*
X62000Y267500D01*
X60500D01*
X60000Y268000D01*
Y269500D01*
X60500Y270000D01*
X60644D01*
G03X60700Y269998I78J1399D01*
G01X62300D01*
G03X62356Y270000I-22J1401D01*
G01X65500D01*
X69000Y266500D01*
Y257221D01*
X68993Y257195D01*
G03Y255805I2507J-695D01*
G01X69000Y255779D01*
Y251765D01*
X65148Y247913D01*
Y247148D01*
X65000Y247000D01*
Y243860D01*
X64398Y243258D01*
Y238500D01*
X63500D01*
G37*
G36*
G01X58815Y250500D02*
G03X58367Y251160I-2016J-886D01*
G02X58521Y251819I284J281D01*
G03X56233Y252353I-721J2081D01*
G02X56079Y251694I-284J-281D01*
G03X54842Y250620I722J-2080D01*
G01X48980D01*
X48600Y251000D01*
Y256700D01*
X48759Y256860D01*
X55926D01*
Y257926D01*
X56000Y258000D01*
Y263500D01*
X55926Y263575D01*
Y264400D01*
X48700D01*
X48650Y264450D01*
Y270597D01*
X49553Y271500D01*
X54500D01*
X54550Y271450D01*
X57550D01*
X58900Y270100D01*
X58798Y269998D01*
Y267502D01*
X60002Y266298D01*
X60202D01*
X60500Y266000D01*
X61500D01*
X61798Y265701D01*
Y250798D01*
X61500Y250500D01*
X58815D01*
G37*
G36*
G01X100000Y189000D02*
X103000D01*
X104500Y190500D01*
Y192500D01*
X104898Y192898D01*
X106300D01*
G03X106791Y192987I-1J1402D01*
G01X106825Y193000D01*
X107000D01*
X108636Y194636D01*
X113318D01*
Y195318D01*
X113600Y195600D01*
Y197400D01*
X113900Y197700D01*
X125700D01*
X126000Y197400D01*
Y194900D01*
X126202Y194698D01*
Y194636D01*
X126264D01*
X126400Y194500D01*
X132000D01*
X132923Y193577D01*
X132910Y193480D01*
G03X132898Y193300I1390J-183D01*
G01Y191700D01*
G03X133598Y190487I1401J0D01*
G01Y189995D01*
X133600Y189994D01*
Y188702D01*
X131900D01*
G03X131176Y188500I1J-1402D01*
G01X126500D01*
X126200Y188200D01*
Y185600D01*
X125800Y185200D01*
X125700D01*
X125500Y185000D01*
X114000D01*
X113500Y185500D01*
Y187500D01*
X113318Y187682D01*
Y188202D01*
X107716D01*
Y188000D01*
X107500D01*
X106000Y186500D01*
X101000D01*
X100252Y185752D01*
X100248D01*
Y185748D01*
X99500Y185000D01*
Y170500D01*
X100248Y169752D01*
Y169748D01*
X100252D01*
X101500Y168500D01*
X105500D01*
X105600Y168400D01*
X105700Y168500D01*
X120000D01*
X120400Y168100D01*
Y166612D01*
X120389Y166580D01*
G03X120298Y166050I1511J-532D01*
G01Y163750D01*
G03X120432Y163111I1602J2D01*
G01X120486Y162986D01*
X119500Y162000D01*
X102632D01*
X92316Y172316D01*
X89105Y175526D01*
X86474D01*
X85000Y177000D01*
Y180500D01*
X91000Y186500D01*
X97500D01*
X98502Y187502D01*
G03X98798Y187798I-1402J1698D01*
G01X100000Y189000D01*
G37*
G36*
G01X108000Y100000D02*
X100000Y108000D01*
Y125500D01*
X101500Y127000D01*
X111500D01*
X115000Y123500D01*
X117579D01*
G03X119421I921J2000D01*
G01X122000D01*
X122500Y123000D01*
Y119500D01*
X126000Y116000D01*
Y105500D01*
X129000Y102500D01*
Y100500D01*
X128577Y100077D01*
X128480Y100090D01*
G03X128300Y100102I-183J-1390D01*
G01X126700D01*
G03X126209Y100013I1J-1402D01*
G01X126175Y100000D01*
X108000D01*
G37*
G36*
G01X122500Y168000D02*
X121252Y169248D01*
Y169252D01*
X121248D01*
X119500Y171000D01*
X102000D01*
X101500Y171500D01*
Y184000D01*
X102500Y185000D01*
X107000D01*
X108798Y186798D01*
X111202D01*
X111500Y186500D01*
Y184000D01*
X112000Y183500D01*
X119500D01*
X120000Y183000D01*
Y177500D01*
X121500Y176000D01*
X123000D01*
X123398Y175602D01*
Y174200D01*
G03X123487Y173709I1402J1D01*
G01X123500Y173675D01*
Y173500D01*
X124000Y173000D01*
X124074D01*
X124119Y172975D01*
G03X124800Y172798I682J1225D01*
G01X126200D01*
G03X126881Y172975I-1J1402D01*
G01X126926Y173000D01*
X127174D01*
X127219Y172975D01*
G03X127900Y172798I682J1225D01*
G01X129702D01*
X129898Y172602D01*
Y171200D01*
G03X129987Y170709I1402J1D01*
G01X130000Y170675D01*
Y170325D01*
X129987Y170291D01*
G03X129898Y169800I1313J-492D01*
G01Y168000D01*
X122500D01*
G37*
G36*
G01X99000Y190500D02*
X98500Y191000D01*
Y197000D01*
X102573Y201073D01*
X102622Y201088D01*
G03X104112Y202578I-622J2112D01*
G01X104127Y202627D01*
X107500Y206000D01*
X111000D01*
X112500Y204500D01*
X119000D01*
X120418Y203082D01*
Y199418D01*
X120100Y199100D01*
X112200D01*
X112000Y198900D01*
Y196500D01*
X111702Y196202D01*
X108502D01*
X108180Y195880D01*
X107716D01*
Y195415D01*
X106502Y194202D01*
X104502D01*
X104362Y194061D01*
X104312Y194047D01*
G03X104209Y194013I388J-1347D01*
G01X104175Y194000D01*
X104000D01*
X103000Y193000D01*
Y191000D01*
X102500Y190500D01*
X99000D01*
G37*
G36*
G01X123500Y160500D02*
X121600Y162400D01*
X121702Y162502D01*
Y164598D01*
X121602Y164698D01*
Y166602D01*
X121900Y166900D01*
X122002Y166798D01*
X129702D01*
X130000Y166500D01*
Y161500D01*
X129000Y160500D01*
X128470D01*
X128420Y160533D01*
G03X125932Y160500I-1220J-1833D01*
G01X123500D01*
G37*
G36*
G01X162325Y151075D02*
X161375Y152025D01*
Y153375D01*
X162000Y154000D01*
X169000D01*
X173000Y158000D01*
Y161500D01*
X172602Y161898D01*
Y165500D01*
X176675D01*
X176709Y165487D01*
G03X177200Y165398I492J1313D01*
G01X178800D01*
G03X179291Y165487I-1J1402D01*
G01X179325Y165500D01*
X180078D01*
X180116Y165483D01*
G03X181884I884J2017D01*
G01X181922Y165500D01*
X182500D01*
X183000Y165000D01*
X186500D01*
X187000Y164500D01*
Y159000D01*
X182000Y154000D01*
X175000D01*
X172075Y151075D01*
X162325D01*
G37*
G36*
G01X209898Y76200D02*
G03X209987Y75709I1402J1D01*
G01X210000Y75675D01*
Y75325D01*
X209987Y75291D01*
G03X209898Y74800I1313J-492D01*
G01Y73200D01*
G03X209987Y72709I1402J1D01*
G01X210000Y72675D01*
Y72325D01*
X209987Y72291D01*
G03X209898Y71800I1313J-492D01*
G01Y70200D01*
G03X209987Y69709I1402J1D01*
G01X210000Y69675D01*
Y69325D01*
X209987Y69291D01*
G03X209898Y68800I1313J-492D01*
G01Y67200D01*
G03X209987Y66709I1402J1D01*
G01X210000Y66675D01*
Y66500D01*
X212000Y64500D01*
Y56500D01*
X211500Y56000D01*
X210000D01*
X209000Y57000D01*
X204500D01*
X203500Y56000D01*
Y52952D01*
G03Y48848I1600J-2052D01*
G01Y45000D01*
X202500Y44000D01*
X188500D01*
X184202Y48298D01*
Y49200D01*
G03X184025Y49881I-1402J-1D01*
G01X184000Y49926D01*
Y50074D01*
X184025Y50119D01*
G03X184202Y50800I-1225J682D01*
G01Y52201D01*
X184500Y52500D01*
X190500D01*
X191000Y53000D01*
X193000D01*
X194000Y52000D01*
X198500D01*
X200000Y53500D01*
Y55000D01*
X198500Y56500D01*
X192500D01*
X192102Y56899D01*
Y58300D01*
G03X192013Y58791I-1402J-1D01*
G01X192000Y58825D01*
Y59500D01*
X192500Y60000D01*
X197000D01*
X197369Y60369D01*
X197419Y60383D01*
G03X199008Y63251I-619J2217D01*
G01X199000Y63278D01*
Y64000D01*
X196000Y67000D01*
Y69000D01*
X196500Y69500D01*
X197500D01*
X198000Y69000D01*
Y68000D01*
X199500Y66500D01*
X206000D01*
X207000Y67500D01*
Y68752D01*
X207002Y68754D01*
Y77996D01*
X207506Y78500D01*
X209500D01*
X209923Y78077D01*
X209910Y77980D01*
G03X209898Y77800I1390J-183D01*
G01Y76200D01*
G37*
G36*
G01X223500Y73500D02*
X217715Y67715D01*
G02X217049Y67881I-283J282D01*
G03X212744Y67376I-2107J-639D01*
G02X212345Y67000I-399J24D01*
G01X211500D01*
X211202Y67298D01*
Y77702D01*
X212500Y79000D01*
X223000D01*
X223500Y78500D01*
Y73500D01*
G37*
G36*
G01X225799Y139801D02*
X225798Y139717D01*
G03X228017Y137498I2202J-17D01*
G01X228101Y137499D01*
X229500Y136100D01*
Y127000D01*
X226500Y124000D01*
X225500D01*
X225000Y124500D01*
Y133900D01*
X224400Y134500D01*
X218000D01*
X210826Y141674D01*
Y142072D01*
X208600Y144298D01*
Y158400D01*
X210500Y160300D01*
Y170000D01*
X211051Y170551D01*
X211174Y170501D01*
G03X211700Y170398I527J1299D01*
G01X213300D01*
G03X214451Y171000I0J1401D01*
G01X222412D01*
X222750Y170661D01*
Y168836D01*
X214350D01*
Y167850D01*
X214300Y167800D01*
Y145300D01*
X219300Y140300D01*
X225300D01*
X225799Y139801D01*
G37*
G36*
G01X263701Y67798D02*
X264000Y67500D01*
Y63000D01*
X263500Y62500D01*
X257500D01*
X257000Y63000D01*
Y67500D01*
X257500Y68000D01*
X262176D01*
G03X262900Y67798I725J1200D01*
G01X263701D01*
G37*
G36*
G01X267750Y79798D02*
G03X269075Y80500I0J1601D01*
G01X273000D01*
X273500Y80000D01*
Y78000D01*
X273000Y77500D01*
X270500D01*
X270000Y77000D01*
Y72300D01*
X270900Y71400D01*
X274900D01*
X275500Y70800D01*
Y66000D01*
X277500Y64000D01*
Y58500D01*
X277000Y58000D01*
X274090D01*
G03X274075Y58001I-154J-2196D01*
G01X273997Y58003D01*
X271000Y61000D01*
X268000D01*
X266000Y63000D01*
Y68675D01*
X266013Y68709D01*
G03X266102Y69200I-1313J492D01*
G01Y70800D01*
G03X266013Y71291I-1402J-1D01*
G01X266000Y71325D01*
Y71486D01*
X266058Y71544D01*
G03X266000Y74712I-1558J1556D01*
G01Y78195D01*
G03X266327Y79391I-1875J1155D01*
G02X266726Y79798I400J7D01*
G01X267750D01*
G37*
G36*
G01X302000Y74099D02*
Y62500D01*
X301000Y61500D01*
X295500D01*
X294000Y63000D01*
X289000D01*
X284000Y58000D01*
X280000D01*
X279500Y58500D01*
Y64400D01*
X277400Y66500D01*
Y75300D01*
X277600Y75500D01*
X280400D01*
X280500Y75400D01*
Y71500D01*
X280900Y71100D01*
X284300D01*
X284900Y71700D01*
Y78400D01*
X285100Y78600D01*
X288700D01*
X289600Y77700D01*
X293600D01*
X296300Y75000D01*
X298086D01*
G03X299250Y74498I1165J1100D01*
G01X301550D01*
G03X301590Y74499I-20J1601D01*
G02X302000Y74099I10J-400D01*
G37*
G36*
G01X296952Y84500D02*
Y84752D01*
X294749D01*
X294500Y85000D01*
Y89000D01*
X294000Y89500D01*
X292985D01*
G03X292050Y89802I-936J-1300D01*
G01X290802D01*
Y91400D01*
G03X290500Y92268I-1402J-1D01*
G01Y93537D01*
X290508Y93565D01*
G03X290585Y94475I-2108J637D01*
G01X290572Y94572D01*
X291000Y95000D01*
X298000D01*
X300174Y92826D01*
X300189Y92784D01*
G03X302003Y91853I1411J516D01*
G01X302116Y91884D01*
X306000Y88000D01*
Y84476D01*
G02X305533Y84082I-400J0D01*
G03X305300Y84102I-236J-1382D01*
G01X304005D01*
X301997Y86109D01*
X301990Y86179D01*
G03X297785Y85061I-2190J-229D01*
G02X297419Y84500I-366J-161D01*
G01X296952D01*
G37*
G36*
G01X284596Y87096D02*
X286000Y88500D01*
X287075D01*
X287109Y88487D01*
G03X287600Y88398I492J1313D01*
G01X289400D01*
G03X289891Y88487I-1J1402D01*
G01X289925Y88500D01*
X290301D01*
X290502Y88298D01*
X292201D01*
X292500Y88000D01*
Y84400D01*
X292950Y83950D01*
X293741D01*
G03X294206Y83582I1209J1050D01*
G01X294233Y83567D01*
X294502Y83298D01*
X296000D01*
Y80000D01*
X295500Y79500D01*
X289500D01*
X289050Y79950D01*
X284950D01*
X284700Y80200D01*
Y81500D01*
X284500Y81700D01*
X280200D01*
X279400Y82500D01*
Y85900D01*
X279404Y85904D01*
X282320D01*
X282416Y86000D01*
X283500D01*
X284004Y86504D01*
X284059Y86517D01*
G03X284583Y87041I-159J683D01*
G01X284596Y87096D01*
G37*
G36*
G01X309700Y62602D02*
G03X308481Y61891I1J-1402D01*
G01X308467Y61867D01*
X307500Y60900D01*
X305000D01*
X304000Y61900D01*
Y79400D01*
X304098Y79498D01*
X305300D01*
G03X306126Y79768I-1J1402D01*
G01X308498Y77395D01*
Y74595D01*
X308500Y74594D01*
Y72900D01*
X309300Y72100D01*
X315800D01*
X316000Y71900D01*
Y65400D01*
X316280Y65120D01*
Y64042D01*
X317358D01*
X317500Y63900D01*
X319000D01*
X319422Y63478D01*
Y60321D01*
X319000Y59900D01*
X315500D01*
X313000Y62400D01*
X312024D01*
G03X311300Y62602I-725J-1200D01*
G01X309700D01*
G37*
G36*
G01X332000Y53500D02*
X329000Y56500D01*
X322000D01*
X321500Y57000D01*
Y58500D01*
X320666Y59334D01*
Y59866D01*
X320702Y59902D01*
Y63701D01*
X321000Y64000D01*
X326500D01*
X327000Y63500D01*
Y59500D01*
X327500Y59000D01*
X330000D01*
X332500Y56500D01*
X332675D01*
X332709Y56487D01*
G03X333200Y56398I492J1313D01*
G01X334800D01*
G03X336191Y57631I0J1401D01*
G01X336200Y57700D01*
X336500Y58000D01*
X350500D01*
X353000Y60500D01*
Y63500D01*
X353399Y63898D01*
X354800D01*
G03X355291Y63987I-1J1402D01*
G01X355325Y64000D01*
X357000D01*
X360000Y61000D01*
X377128D01*
X377154Y60993D01*
G03X378546I696J2507D01*
G01X378572Y61000D01*
X379000D01*
X379441Y61441D01*
X379451Y61449D01*
G03X379901Y61899I-1601J2051D01*
G01X379909Y61909D01*
X384262Y66262D01*
X384412D01*
X389557Y71406D01*
G03X386443Y74520I-1557J1557D01*
G01X383424Y71500D01*
X379000D01*
X378500Y72000D01*
Y78000D01*
X378875Y78375D01*
X380625D01*
X381500Y77500D01*
X389000D01*
X390000Y76500D01*
X399000D01*
X400500Y75000D01*
X429000D01*
X431000Y77000D01*
Y103000D01*
X433000Y105000D01*
Y107500D01*
X434000Y108500D01*
X441500D01*
X443000Y110000D01*
Y116500D01*
X445500Y119000D01*
Y123827D01*
X445512Y123861D01*
G03X444394Y125667I-1270J463D01*
G01X444325Y125675D01*
X442500Y127500D01*
X442402D01*
Y127863D01*
G03X441700Y128564I-701J0D01*
G01X439900D01*
G03X439574Y128484I-1J-701D01*
G02X439026Y128670I-185J355D01*
G03X436457Y127946I-1226J-570D01*
G02X436059Y127500I-397J-46D01*
G01X436000D01*
X435752Y127252D01*
X435462D01*
X433574Y125364D01*
X432200D01*
G03X431637Y125081I0J-702D01*
G01X431577Y125000D01*
X429795D01*
G02X429443Y125591I0J400D01*
G03X428491Y127567I-1188J645D01*
G02X428329Y127801I35J197D01*
G03X426764Y126719I-1329J249D01*
G02X426926Y126485I-35J-197D01*
G03X427067Y125591I1329J-249D01*
G02X426715Y125000I-352J-191D01*
G01X423803D01*
G02X423460Y125605I0J400D01*
G03X423640Y126479I-1160J694D01*
G02X423914Y126913I396J53D01*
G03X422160Y128021I-414J1287D01*
G02X421886Y127587I-396J-53D01*
G03X421140Y125605I414J-1287D01*
G02X420797Y125000I-343J-205D01*
G01X416500D01*
X415497Y126003D01*
G02X415625Y126654I283J282D01*
G03X414560Y129139I-525J1246D01*
G02X414000Y129506I-160J367D01*
G01Y129754D01*
G02X414537Y130130I400J0D01*
G03X413650Y131335I463J1270D01*
G02X412967Y131033I-400J-20D01*
G01X412941Y131059D01*
X412884Y131089D01*
G03X412300Y131402I-584J-388D01*
G01X410700D01*
G03X410222Y131214I0J-702D01*
G02X409723Y131177I-273J293D01*
G03X407980Y131000I-767J-1113D01*
G01X407500D01*
X406500Y130000D01*
X405186D01*
G03X403614I-786J-1100D01*
G01X402500D01*
X402000Y130500D01*
Y131500D01*
X402500Y132000D01*
X406000D01*
X407000Y133000D01*
Y141000D01*
X405500Y142500D01*
X399000D01*
X398500Y143000D01*
Y144000D01*
X399000Y144500D01*
X402000D01*
X403000Y145500D01*
X404000D01*
X405000Y146500D01*
Y147500D01*
X405500Y148000D01*
X407154D01*
G02X407530Y147463I0J-400D01*
G03X409417Y145797I1270J-463D01*
G02X409995Y145505I183J-356D01*
G01X412188Y143312D01*
X412140Y143191D01*
G03X414716Y143009I1260J-491D01*
G02X415106Y143500I390J91D01*
G01X416354D01*
G02X416730Y142963I0J-400D01*
G03X419159Y143197I1270J-463D01*
G02X419330Y143500I171J103D01*
G01X419500D01*
X423500Y147500D01*
X425148D01*
G02X425548Y147100I0J-400D01*
G03X428252I1352J0D01*
G02X428652Y147500I400J0D01*
G01X437500D01*
X438000Y147000D01*
Y142000D01*
X439000Y141000D01*
X442500D01*
X446000Y137500D01*
X462000D01*
X463000Y138500D01*
Y180297D01*
G02X463605Y180640I400J0D01*
G03Y182960I695J1160D01*
G02X463000Y183303I-205J343D01*
G01Y187738D01*
X463110Y187793D01*
G03Y190207I-610J1207D01*
G01X463000Y190262D01*
Y197500D01*
X460600Y199900D01*
X460676Y200032D01*
G03X458168Y200468I-1176J668D01*
G02X457774Y200000I-394J-68D01*
G01X454226D01*
G02X453832Y200468I0J400D01*
G03X451168I-1332J232D01*
G02X450774Y200000I-394J-68D01*
G01X450000D01*
X448200Y198200D01*
Y186000D01*
X450000Y184200D01*
Y180500D01*
X449500Y180000D01*
X437000D01*
X436000Y179000D01*
Y174563D01*
X432468Y171032D01*
X432500Y171000D01*
Y169000D01*
X431472Y167972D01*
X431369Y167991D01*
G03X430235Y167673I-238J-1331D01*
G02X429575Y167913I-265J300D01*
G03X429232Y168625I-1336J-205D01*
G02X429276Y169209I294J272D01*
G03X429240Y171347I-845J1055D01*
G02X429256Y171999I240J320D01*
G03X427313Y173767I-756J1121D01*
G02X426611Y173765I-352J191D01*
G03X424643Y172012I-1184J-652D01*
G02X424637Y171356I-232J-326D01*
G03X424288Y171009I763J-1116D01*
G02X423589Y171086I-329J228D01*
G03X423449Y169806I-1252J-511D01*
G02X424148Y169729I329J-228D01*
G03X426575Y169571I1252J511D01*
G02X427267Y169576I347J-198D01*
G03X427437Y169348I1163J690D01*
G02X427393Y168764I-294J-272D01*
G03X429133Y166696I845J-1055D01*
G02X429793Y166456I265J-300D01*
G03X431107Y165308I1337J204D01*
G02X431500Y164908I-7J-400D01*
G01Y164063D01*
X431000Y163563D01*
X429000D01*
X427000Y161563D01*
X424000D01*
X422000Y163563D01*
X421813D01*
X421754Y163621D01*
G03X419534Y163124I-950J-962D01*
G01X419519Y163082D01*
X418500Y162063D01*
X416547D01*
G02X416148Y162494I0J400D01*
G03X413666Y163336I-1348J106D01*
G02X412981Y163359I-336J217D01*
G03X412277Y163965I-1180J-659D01*
G02X412176Y164657I142J374D01*
G03X412621Y166208I-820J1075D01*
G02X412806Y166701I375J141D01*
G03X413182Y166976I-807J1498D01*
G02X413482Y166713I140J-143D01*
G03X414135Y167192I1089J-801D01*
G02X413624Y167691I-129J379D01*
G03X413623Y168714I-1624J510D01*
G02X413835Y169197I381J121D01*
G03X411920Y170287I-570J1226D01*
G02X411613Y169857I-398J-40D01*
G03X410473Y168952I387J-1657D01*
G01X410026D01*
X409566Y168492D01*
X409469Y168504D01*
G03X408577Y168305I-169J-1341D01*
G02X408075Y168366I-214J338D01*
G03X406271Y166361I-974J-937D01*
G01X406348Y166301D01*
Y165997D01*
X406290Y165939D01*
G03X409101Y165290I1202J-1205D01*
G02X409438Y165818I378J130D01*
G03X409553Y165835I-140J1345D01*
G02X410023Y165508I75J-393D01*
G03X410879Y164467I1333J224D01*
G02X410980Y163775I-142J-374D01*
G03X410460Y162517I820J-1075D01*
G02X410064Y162063I-396J-54D01*
G01X410000D01*
X409500Y161563D01*
X405500D01*
X403000Y164063D01*
X399000D01*
X398500Y164563D01*
Y166063D01*
X397500Y167063D01*
X380000D01*
X379500Y167563D01*
Y169063D01*
X380000Y169563D01*
X398000D01*
X398032Y169532D01*
X398968D01*
X400137Y168363D01*
X400142Y168286D01*
G03X400804Y167624I700J38D01*
G01X400881Y167619D01*
X400937Y167563D01*
X403000D01*
X403500Y168063D01*
Y170063D01*
X404000Y170563D01*
X406000D01*
X407000Y171563D01*
Y178500D01*
X408000Y179500D01*
X408500D01*
X409906Y178094D01*
X409910Y178018D01*
G03X409988Y177631I1350J71D01*
G01X410000Y177599D01*
Y174501D01*
G03X411900Y172864I620J-1201D01*
G01X411946Y173000D01*
X416437D01*
X418000Y174563D01*
Y176563D01*
X417000Y177563D01*
Y179063D01*
X420000Y182063D01*
X422000D01*
X422032Y182032D01*
X422359D01*
Y181802D01*
X422350Y181773D01*
G03X424979Y181573I1292J-399D01*
G02X425375Y182032I396J59D01*
G01X428631D01*
G02X429026Y181568I0J-400D01*
G03X431353Y182268I1334J-218D01*
G02X431364Y182822I294J271D01*
G01X434542Y186000D01*
Y186024D01*
X436009Y187491D01*
Y193516D01*
X436136Y193565D01*
G03X436365Y193682I-498J1257D01*
G02X436659Y193441I107J-169D01*
G03X437505Y194243I1262J-484D01*
G02X436985Y194669I-123J380D01*
G03X436128Y196086I-1343J155D01*
G01X436000Y196135D01*
Y199000D01*
X436500Y199500D01*
Y202000D01*
X436000Y202500D01*
Y207966D01*
X434042Y209924D01*
X428861D01*
X427000Y208063D01*
X418500D01*
X416500Y206063D01*
X416000D01*
X415937Y206000D01*
X414500D01*
X413000Y207500D01*
Y210000D01*
X413500Y210500D01*
X415000D01*
X419365Y214865D01*
X419460Y214855D01*
G03X420945Y216340I140J1345D01*
G01X420935Y216435D01*
X428000Y223500D01*
X440000D01*
X490000Y173500D01*
Y153000D01*
X479500Y142500D01*
Y127000D01*
X446000Y93500D01*
Y71000D01*
X442500Y67500D01*
X423000D01*
X420000Y70500D01*
X407825D01*
X407791Y70513D01*
G03X407300Y70602I-492J-1313D01*
G01X405700D01*
G03X405209Y70513I1J-1402D01*
G01X405175Y70500D01*
X405000D01*
X404500Y70000D01*
Y69926D01*
X404475Y69881D01*
G03X404298Y69200I1225J-682D01*
G01Y67800D01*
G03X404500Y67076I1402J1D01*
G01Y64000D01*
X404402Y63902D01*
X400118D01*
Y63500D01*
X393000D01*
X386000Y56500D01*
X365374D01*
G03X364300Y57002I-1075J-900D01*
G01X362700D01*
G03X361626Y56500I1J-1402D01*
G01X359000D01*
X356000Y53500D01*
X332000D01*
G37*
G36*
G01X327000Y94346D02*
Y99000D01*
X328106Y100106D01*
G02X328780Y99909I283J-283D01*
G03X329146Y99242I1320J291D01*
G02Y98958I-141J-142D01*
G03X331054I954J-958D01*
G02Y99242I141J142D01*
G03X331118Y101090I-954J958D01*
G02X331136Y101636I301J263D01*
G01X332000Y102500D01*
X332675D01*
X332717Y102480D01*
G03X333909I596J1213D01*
G01X333951Y102500D01*
X334824D01*
G03X337776I1476J1200D01*
G01X338500D01*
X339000Y103000D01*
X340494D01*
G03X341040Y102738I547J440D01*
G01X342640D01*
G03X343186Y103000I-1J702D01*
G01X343494D01*
G03X344040Y102738I547J440D01*
G01X345640D01*
G03X346186Y103000I-1J702D01*
G01X346500D01*
X347000Y103500D01*
Y109500D01*
X347500Y110000D01*
X349000D01*
X350500Y108500D01*
Y100000D01*
X350000Y99500D01*
X348500D01*
X348000Y99000D01*
Y94000D01*
X347500Y93500D01*
X346500D01*
X345500Y92500D01*
Y87000D01*
X343681Y85181D01*
X343665Y85170D01*
G03X342919Y84419I1434J-2171D01*
G01X342111Y83611D01*
X341997Y83644D01*
G03X341600Y83702I-399J-1344D01*
G01X339799D01*
X339602Y83898D01*
Y85300D01*
G03X339513Y85791I-1402J-1D01*
G01X339500Y85825D01*
Y89000D01*
X338500Y90000D01*
X329500D01*
X327000Y87500D01*
Y86325D01*
X326987Y86291D01*
G03X326898Y85800I1313J-492D01*
G01Y84200D01*
G03X327098Y83478I1403J0D01*
G01Y79499D01*
X326900Y79300D01*
X320800D01*
X320700Y79400D01*
Y83700D01*
X319601Y84799D01*
X319602Y84882D01*
G03X317650Y87419I-2602J18D01*
G01X317500Y87458D01*
Y89000D01*
X318247Y89747D01*
X318274Y89761D01*
G03X318597Y90000I-634J1194D01*
G01X323000D01*
X324205Y91205D01*
G02X324870Y91040I283J-283D01*
G03X327462Y91065I1292J398D01*
G02X327881Y91353I384J-110D01*
G03X329285Y92281I119J1347D01*
G02X329947Y92441I380J-124D01*
G03X329615Y93819I953J959D01*
G02X328953Y93659I-380J124D01*
G03X327537Y93970I-953J-959D01*
G02X327000Y94346I-137J376D01*
G37*
G36*
G01X332147Y65455D02*
G02X331484Y65755I-263J301D01*
G01Y72300D01*
X335890D01*
G03X338845Y73000I1110J1902D01*
G01X341500D01*
X341929Y72571D01*
X341940Y72510D01*
G03X345906Y69993I3149J579D01*
G01X345931Y70000D01*
X350500D01*
X351000Y69500D01*
Y60500D01*
X350000Y59500D01*
X335500D01*
X335252Y59252D01*
X335248D01*
Y59248D01*
X335000Y59000D01*
Y58500D01*
X334500Y58000D01*
X333000D01*
X330500Y60500D01*
X328500D01*
X328342Y60658D01*
Y63843D01*
X328500Y64000D01*
X330000D01*
X330041Y64042D01*
X331398D01*
Y63838D01*
G03X332147Y65455I2202J-38D01*
G37*
G36*
G01X339216Y249602D02*
X338000Y250817D01*
Y260000D01*
X332500Y265500D01*
Y274500D01*
X333500Y275500D01*
X344000D01*
X345000Y274500D01*
Y267500D01*
X341000Y263500D01*
Y250000D01*
X340577Y249577D01*
X340480Y249590D01*
G03X340300Y249602I-183J-1390D01*
G01X339216D01*
G37*
G36*
G01X372000Y81215D02*
X371990Y81185D01*
G03Y80015I1810J-585D01*
G01X372000Y79985D01*
Y67000D01*
X370000Y65000D01*
X357699D01*
X357498Y65202D01*
X353002D01*
X352900Y65100D01*
X352500Y65500D01*
Y80500D01*
X351500Y81500D01*
X351352D01*
Y81502D01*
X344998D01*
X344000Y82500D01*
Y84500D01*
X346500Y87000D01*
Y92500D01*
X346999Y92998D01*
X347708D01*
X347709Y93000D01*
X348000D01*
X349000Y94000D01*
Y98500D01*
X349499Y98998D01*
X350208D01*
X350209Y99000D01*
X351000D01*
X351500Y99500D01*
Y110438D01*
X351610Y110493D01*
G03X352077Y112517I-610J1207D01*
G02X352155Y113078I319J242D01*
G03X351125Y115492I-813J1080D01*
G01X351024Y115476D01*
X350502Y115998D01*
Y122932D01*
X350500Y122933D01*
Y124000D01*
X351500Y125000D01*
Y125465D01*
X351802Y125766D01*
Y128526D01*
X351502Y128826D01*
Y130200D01*
G03X351500Y130240I-701J-15D01*
G01Y131760D01*
G03X351502Y131800I-699J55D01*
G01Y133600D01*
G03X351500Y133640I-701J-15D01*
G01Y134000D01*
X350500Y135000D01*
Y136500D01*
X350955Y136955D01*
X351019Y136966D01*
G03X352080Y137864I-219J1334D01*
G01X352126Y138000D01*
X356000D01*
X356500Y137500D01*
Y136500D01*
X356201Y136202D01*
X355950D01*
G03X355344Y135853I0J-701D01*
G01X355331Y135831D01*
X355000Y135500D01*
Y130500D01*
X355500Y130000D01*
X357500D01*
X358500Y131000D01*
X359500D01*
X360500Y130000D01*
Y129000D01*
X361500Y128000D01*
X362500D01*
X363000Y127500D01*
Y120600D01*
X364500Y119100D01*
Y116110D01*
X364483Y116072D01*
G03Y114984I1238J-544D01*
G01X364500Y114946D01*
Y111500D01*
X367370Y108630D01*
X367369Y108545D01*
G03X368000Y107384I1352J-17D01*
G01Y98712D01*
G03Y96288I600J-1212D01*
G01Y95312D01*
G03Y92888I600J-1212D01*
G01Y91912D01*
G03X367994Y89491I600J-1212D01*
G01X368023Y89477D01*
X370903Y86597D01*
G02X370909Y86319I-141J-142D01*
G03X371813Y84051I991J-919D01*
G02X372000Y83852I-13J-200D01*
G01Y81215D01*
G37*
G36*
G01X371800Y130000D02*
X371000Y129200D01*
Y127700D01*
X370300Y127000D01*
X369500D01*
X368500Y126000D01*
Y125000D01*
X367500Y124000D01*
X366500D01*
X366000Y123500D01*
Y122817D01*
X365996Y122797D01*
G03Y122259I1325J-269D01*
G01X366000Y122239D01*
Y121500D01*
X367500Y120000D01*
Y112500D01*
X373000Y107000D01*
Y99500D01*
X372500Y99000D01*
X369500D01*
X369000Y99500D01*
Y107500D01*
X368502Y107998D01*
Y108208D01*
X365002Y111708D01*
Y119308D01*
X365000Y119309D01*
Y119700D01*
X363502Y121198D01*
Y127708D01*
X362708Y128502D01*
X361998D01*
X361002Y129498D01*
Y130208D01*
X361000Y130209D01*
Y130500D01*
X360000Y131500D01*
X359709D01*
X359708Y131502D01*
X358292D01*
X357292Y130502D01*
X355999D01*
X355502Y130999D01*
Y135292D01*
X355708Y135498D01*
X356208D01*
X356709Y136000D01*
X357000D01*
X357500Y136500D01*
Y138000D01*
X356500Y139000D01*
X352000D01*
X351000Y138000D01*
X350500D01*
X350000Y138500D01*
Y140000D01*
X351500Y141500D01*
X354000D01*
X354500Y142000D01*
Y142760D01*
G03X354502Y142800I-699J55D01*
G01Y144001D01*
X355000Y144500D01*
X355917D01*
X356019Y144398D01*
X356101D01*
X356500Y144000D01*
Y142000D01*
X357000Y141500D01*
X362000D01*
X362500Y141000D01*
Y140000D01*
X360500Y138000D01*
Y132500D01*
X363500Y129500D01*
X366500D01*
X369500Y132500D01*
X378500D01*
X379500Y133500D01*
Y134500D01*
X380000Y135000D01*
X381000D01*
X381500Y134500D01*
Y133500D01*
X378000Y130000D01*
X376983D01*
G03X376817I-83J-1900D01*
G01X371800D01*
G37*
G36*
G01X350998Y174499D02*
X350500Y174000D01*
X349000D01*
X348545Y174455D01*
X348534Y174519D01*
G03X348507Y174647I-1335J-215D01*
G01X348500Y174672D01*
Y177500D01*
X349500Y178500D01*
X352000D01*
X352500Y179000D01*
Y179360D01*
G03X352502Y179400I-699J55D01*
G01Y180501D01*
X353000Y181000D01*
X354000D01*
X354498Y180501D01*
Y179300D01*
G03X354500Y179260I701J15D01*
G01Y178500D01*
X358000Y175000D01*
X359500D01*
X362500Y172000D01*
Y171500D01*
X364500Y169500D01*
X368500D01*
X369000Y169000D01*
Y168000D01*
X368500Y167500D01*
X364500D01*
X363350Y166350D01*
Y165816D01*
X363337Y165782D01*
G03Y164818I1263J-482D01*
G01X363350Y164784D01*
Y164750D01*
X363377Y164723D01*
X363391Y164694D01*
G03X363994Y164091I1209J606D01*
G01X364023Y164077D01*
X364050Y164050D01*
X364084D01*
X364118Y164037D01*
G03X364854Y163972I482J1263D01*
G01X364958Y163992D01*
X365250Y163700D01*
Y162400D01*
X364800Y161950D01*
X363550D01*
X363100Y162400D01*
Y163150D01*
X362325Y163925D01*
X359925D01*
X359500Y163500D01*
Y161000D01*
X359037Y160537D01*
X358919Y160578D01*
G03X357893Y160520I-442J-1278D01*
G01X357853Y160500D01*
X355500D01*
X355000Y161000D01*
Y162500D01*
X355500Y163000D01*
X357000D01*
X357500Y163500D01*
Y165500D01*
X358500Y166500D01*
X361500D01*
X363000Y168000D01*
Y169000D01*
X362000Y170000D01*
X358000D01*
X357926Y169926D01*
G02X357337Y169951I-283J283D01*
G03X356800Y170202I-538J-451D01*
G01X355200D01*
G03X354498Y169500I0J-702D01*
G01Y167500D01*
X354000D01*
X353000Y166500D01*
X351000D01*
X350500Y167000D01*
Y168000D01*
X350922Y168422D01*
X351048Y168366D01*
G03X352934Y169381I552J1234D01*
G01X352945Y169445D01*
X354000Y170500D01*
Y173260D01*
G03X354002Y173300I-699J55D01*
G01Y174700D01*
G03X354000Y174740I-701J-15D01*
G01Y175500D01*
X353500Y176000D01*
X351500D01*
X351000Y175500D01*
Y174740D01*
G03X350998Y174700I699J-55D01*
G01Y174499D01*
G37*
G36*
G01X354950Y182000D02*
G02X354574Y182535I1J400D01*
G03X351952Y182921I-1272J458D01*
G02X351553Y182500I-399J-21D01*
G01X350000D01*
X349502Y182999D01*
Y184600D01*
G03X349500Y184640I-701J-15D01*
G01Y186000D01*
X349000Y186500D01*
Y188152D01*
G02X349187Y188351I200J-1D01*
G03X350360Y190191I-87J1349D01*
G01X350312Y190312D01*
X351000Y191000D01*
X352767D01*
G03X354483I858J1045D01*
G01X355000D01*
X356000Y192000D01*
X356328D01*
X356353Y191993D01*
G03X357047I347J1307D01*
G01X357072Y192000D01*
X357500D01*
X358500Y191000D01*
Y189500D01*
X359500Y188500D01*
X360344D01*
X360345Y188498D01*
X361878D01*
X362500Y187877D01*
Y186500D01*
X363331Y185669D01*
X363347Y185631D01*
G03X364093Y184885I1253J507D01*
G01X364131Y184869D01*
X364500Y184500D01*
Y179000D01*
X364000Y178500D01*
X362563D01*
X362541Y178674D01*
G03X361806Y179709I-1341J-174D01*
G01X361777Y179723D01*
X359500Y182000D01*
X354950D01*
G37*
G36*
G01X361000Y257700D02*
Y244000D01*
X360500Y243500D01*
X354000D01*
X353500Y244000D01*
Y267000D01*
X354000Y267500D01*
X369500D01*
X371000Y269000D01*
X373200D01*
X373500Y268700D01*
Y267400D01*
X373700Y267200D01*
X381500D01*
X381550Y267250D01*
X384450D01*
X385000Y266700D01*
Y260600D01*
X384300Y259900D01*
X373800D01*
X373600Y259700D01*
Y258000D01*
X373300Y257700D01*
X370800D01*
X369700Y258800D01*
X362100D01*
X361000Y257700D01*
G37*
G36*
G01X346000Y258000D02*
X345500Y258500D01*
Y266000D01*
X347000Y267500D01*
Y276000D01*
X350000Y279000D01*
X376500D01*
X377500Y278000D01*
Y271000D01*
X377300Y270800D01*
X373700D01*
X373600Y270700D01*
Y270000D01*
X373102Y269502D01*
X370792D01*
X370791Y269500D01*
X369000D01*
X368500Y269000D01*
X353000D01*
X352000Y268000D01*
Y266000D01*
X351500Y265500D01*
X351301D01*
X351247Y265542D01*
G03X348553I-1347J-1742D01*
G01X348522Y265518D01*
X348491Y265492D01*
G03X348208Y265209I1409J-1692D01*
G01X348202Y265202D01*
X348000Y265000D01*
Y264914D01*
X347975Y264869D01*
G03Y262731I1925J-1069D01*
G01X348000Y262686D01*
Y262500D01*
X348500Y262000D01*
Y258500D01*
X348000Y258000D01*
X346000D01*
G37*
G36*
G01X367343Y49157D02*
X366500Y50000D01*
Y53500D01*
X367000Y54000D01*
X380000D01*
X382000Y52000D01*
Y47000D01*
X386764Y42236D01*
X386763Y42153D01*
Y36000D01*
X379000D01*
X378000Y37000D01*
Y39000D01*
X376500Y40500D01*
X371000D01*
X369500Y42000D01*
Y47000D01*
X368512Y47988D01*
X368497Y48022D01*
G03X367377Y49142I-2013J-893D01*
G01X367343Y49157D01*
G37*
G36*
G01X363500Y130500D02*
X363365Y130635D01*
X363350Y130670D01*
G03X362653Y131367I-1239J-542D01*
G01X362618Y131382D01*
X361002Y132998D01*
Y137002D01*
X363500Y139500D01*
Y142000D01*
X363000Y142500D01*
X358000D01*
X357500Y143000D01*
Y144000D01*
X357899Y144398D01*
X359800D01*
G03X360123Y144477I-1J702D01*
G01X360167Y144500D01*
X368500D01*
X369000Y144000D01*
Y141500D01*
X369500Y141000D01*
X371500D01*
X372000Y140500D01*
Y138590D01*
G02X371503Y138202I-400J0D01*
G03Y135578I-327J-1312D01*
G02X372000Y135190I97J-388D01*
G01Y134000D01*
X371500Y133500D01*
X369000D01*
X366000Y130500D01*
X363500D01*
G37*
G36*
G01X371700Y144498D02*
G03X371740Y144500I-15J701D01*
G01X372500D01*
X373000Y145000D01*
Y147000D01*
X373500Y147500D01*
X375000D01*
X375500Y147000D01*
Y145000D01*
X376000Y144500D01*
X390000D01*
X390470Y144030D01*
Y142970D01*
X390000Y142500D01*
X389000D01*
X385000Y138500D01*
X383000D01*
X382500Y139000D01*
Y141000D01*
X381500Y142000D01*
X370000D01*
X369502Y142499D01*
Y144001D01*
X370000Y144500D01*
X370260D01*
G03X370300Y144498I55J699D01*
G01X371700D01*
G37*
G36*
G01X370900Y152728D02*
G03X371626Y150011I1600J-1028D01*
G01X371654Y149996D01*
X372050Y149600D01*
Y145500D01*
X371551Y145002D01*
X369792D01*
X369791Y145000D01*
X368709D01*
X368708Y145002D01*
X367499D01*
X367000Y145500D01*
Y147000D01*
X367500Y147500D01*
X369000D01*
X369500Y148000D01*
Y152500D01*
X369236Y152764D01*
X369224Y152822D01*
G03X368172Y153874I-1324J-272D01*
G01X368114Y153886D01*
X363350Y158650D01*
Y160450D01*
X363750Y160850D01*
X365150D01*
X365800Y161500D01*
Y162080D01*
G03X365804Y162150I-700J75D01*
G01Y163550D01*
G03X365800Y163620I-704J-5D01*
G01Y163750D01*
X365762Y163788D01*
G03X365752Y163814I-661J-239D01*
G01Y163908D01*
X365108Y164552D01*
X364258D01*
X364000Y164809D01*
Y166000D01*
X364500Y166500D01*
X368000D01*
X369000Y165500D01*
Y165078D01*
G03Y164922I1700J-78D01*
G01Y164500D01*
X369111Y164389D01*
X369126Y164352D01*
G03X371504Y163500I1574J648D01*
G01X374500D01*
X375500Y164500D01*
X376368D01*
G03X378752Y164730I1132J740D01*
G01X378767Y164767D01*
X380000Y166000D01*
X397000D01*
X397500Y165500D01*
Y164500D01*
X397000Y164000D01*
X380500D01*
X379000Y162500D01*
X376881D01*
X376850Y162511D01*
G03X375750I-550J-1611D01*
G01X375719Y162500D01*
X375500D01*
X375192Y162192D01*
X375186Y162187D01*
G03X375013Y162014I1114J-1287D01*
G01X375008Y162008D01*
X370985Y157985D01*
X370955Y157970D01*
G03X370900Y154938I745J-1530D01*
G01Y152728D01*
G37*
G36*
G01X365900Y186510D02*
Y187968D01*
G03X365931Y189471I-1108J775D01*
G01X365900Y189520D01*
Y190037D01*
G03X365945Y191793I-1005J904D01*
G01X365900Y191848D01*
Y192179D01*
X365951Y192236D01*
G03X365574Y194339I-1004J905D01*
G01X365547Y194353D01*
X365400Y194500D01*
Y195385D01*
X365410Y195415D01*
G03Y196585I-1810J585D01*
G01X365400Y196615D01*
Y196773D01*
X365522Y196895D01*
Y197422D01*
X366500Y198400D01*
Y208000D01*
X368100Y209600D01*
X373000D01*
X373500Y209100D01*
Y206650D01*
X373000Y206150D01*
X370400D01*
X369100Y204850D01*
Y204468D01*
X369082Y204428D01*
G03X368998Y204050I818J-380D01*
G01Y201750D01*
G03X369082Y201372I902J2D01*
G01X369100Y201332D01*
Y200350D01*
X369758Y199692D01*
X369752Y199600D01*
G03X370250Y198449I1348J-100D01*
G01Y196861D01*
G03X370139Y196702I1050J-851D01*
G02X369772Y196760I-172J102D01*
G03X369433Y195521I-1317J-306D01*
G02X370082Y195419I289J-276D01*
G03X370250Y195155I1217J589D01*
G01Y194550D01*
X368947Y193247D01*
X368884Y193237D01*
G03X368150Y190947I222J-1334D01*
G01Y189952D01*
G03Y188248I1050J-852D01*
G01Y187235D01*
G03X369453Y184914I859J-1044D01*
G01X369485Y184925D01*
X369925D01*
X370500Y185500D01*
Y188400D01*
X371000Y188900D01*
X376900D01*
X377300Y188500D01*
Y186700D01*
X377200Y186600D01*
X375400D01*
X374700Y185900D01*
Y179100D01*
X374000Y178400D01*
X372200D01*
X371500Y177700D01*
Y171000D01*
X371000Y170500D01*
X364500D01*
X363500Y171500D01*
Y177000D01*
X365500Y179000D01*
Y183000D01*
X365900Y183400D01*
Y185766D01*
X365907Y185791D01*
G03Y186485I-1307J347D01*
G01X365900Y186510D01*
G37*
G36*
G01X366500Y229000D02*
X363100Y232400D01*
Y257000D01*
X363599Y257498D01*
X368501D01*
X370800Y255200D01*
X373400D01*
X373700Y254900D01*
Y246300D01*
X373800Y246200D01*
X377500D01*
X377700Y246000D01*
Y234917D01*
X371783Y229000D01*
X366500D01*
G37*
G36*
G01X373000Y133500D02*
X372502Y133999D01*
Y136002D01*
X373000Y136500D01*
Y141000D01*
X373499Y141498D01*
X381001D01*
X381500Y141000D01*
Y136500D01*
X381000Y136000D01*
X380000D01*
X379000Y135000D01*
Y134709D01*
X378998Y134708D01*
Y133999D01*
X378500Y133500D01*
X373000D01*
G37*
G36*
G01X380000Y145563D02*
X379500Y146063D01*
Y153063D01*
X380000Y153563D01*
X384000D01*
X384500Y153063D01*
Y146063D01*
X384000Y145563D01*
X380000D01*
G37*
G36*
G01X386000Y151500D02*
X385500Y152000D01*
Y155101D01*
G03X386099Y156503I-1100J1299D01*
G01X386093Y156593D01*
X386500Y157000D01*
X390500D01*
Y153000D01*
X390000Y152500D01*
X388000D01*
X387000Y151500D01*
X386000D01*
G37*
G36*
G01X385000Y203000D02*
X384500Y203500D01*
Y204500D01*
X383000Y206000D01*
X375000D01*
X374500Y206500D01*
Y210000D01*
X374667Y210167D01*
G02X375258Y210139I283J-283D01*
G03X377507Y210390I1042J861D01*
G01X377562Y210500D01*
X383500D01*
X385000Y212000D01*
X388500D01*
X389000Y211500D01*
Y206000D01*
X389500Y205500D01*
Y203500D01*
X389000Y203000D01*
X385000D01*
G37*
G36*
G01X418388Y256291D02*
G02X418926Y256260I252J-311D01*
G03X419112Y259509I1574J1540D01*
G02X418574Y259540I-252J311D01*
G03X414842Y258437I-1574J-1540D01*
G01X414830Y258377D01*
X408554Y252102D01*
X405399D01*
X405000Y252500D01*
Y255500D01*
X410096Y260596D01*
X410173Y260600D01*
G03X410900Y260849I-73J1400D01*
G03X411700Y260598I800J1151D01*
G01X413500D01*
G03X414368Y260900I-1J1402D01*
G01X414900D01*
X425983Y271983D01*
X426092Y271957D01*
G03X427235Y271992I506J2143D01*
G01X427263Y272000D01*
X432637D01*
X432665Y271992D01*
G03X433935I635J2108D01*
G01X433963Y272000D01*
X439500D01*
X445500Y266000D01*
X452500D01*
X453000Y265500D01*
Y257000D01*
X452000Y256000D01*
X446000D01*
X445000Y257000D01*
Y262000D01*
X444000Y263000D01*
X435000D01*
X434500Y262500D01*
Y252000D01*
X433500Y251000D01*
X430298D01*
G03X430102I-98J-2600D01*
G01X417500D01*
X416526Y250026D01*
X416525D01*
X407500Y241002D01*
X407484D01*
X402234Y235752D01*
X387899D01*
X386500Y237150D01*
Y242500D01*
X391000Y247000D01*
X396000D01*
X397499Y248498D01*
X410046D01*
X417377Y255830D01*
X417437Y255842D01*
G03X418388Y256291I-437J2158D01*
G37*
G36*
G01X400283Y104217D02*
X401000Y103500D01*
X405500D01*
X406000Y104000D01*
Y106500D01*
X406500Y107000D01*
X423000D01*
X423500Y106500D01*
Y100000D01*
X423000Y99500D01*
X418469D01*
G03X418331I-69J-1350D01*
G01X401310D01*
G03X399490I-910J-1000D01*
G01X395362D01*
X395307Y99610D01*
G03X392893I-1207J-610D01*
G01X392838Y99500D01*
X392000D01*
X390500Y101000D01*
Y105500D01*
X392000Y107000D01*
X397500D01*
X398117Y106383D01*
X398107Y106289D01*
G03X400189Y104207I1893J-189D01*
G01X400283Y104217D01*
G37*
G36*
G01X429500Y122563D02*
X430500Y121563D01*
X434500D01*
X435619Y122682D01*
X435681Y122693D01*
G03X436773Y123785I-239J1331D01*
G01X436784Y123847D01*
X438000Y125063D01*
X440000D01*
X442000Y123063D01*
Y121882D01*
G03Y119766I842J-1058D01*
G01Y110563D01*
X441000Y109563D01*
X433000D01*
X431500Y108063D01*
Y105063D01*
X428500Y102063D01*
Y94710D01*
G03Y92890I1000J-910D01*
G01Y77500D01*
X428000Y77000D01*
X425000D01*
X424500Y77500D01*
Y107563D01*
X424000Y108063D01*
X402500D01*
X402029Y108534D01*
X402041Y108631D01*
G03X400531Y110141I-1341J169D01*
G01X400434Y110129D01*
X397945Y112618D01*
X397934Y112682D01*
G03X395326Y112917I-1334J-219D01*
G01X395311Y112874D01*
X395000Y112563D01*
X392500D01*
X391000Y114063D01*
Y123731D01*
G03Y125341I-1086J805D01*
G01Y126063D01*
X393937Y129000D01*
X395054D01*
G02X395430Y128463I0J-400D01*
G03X396834Y126655I1270J-463D01*
G02X397245Y126108I40J-398D01*
G03X397686Y124524I1255J-504D01*
G02X397689Y123888I-241J-319D01*
G03X397168Y122671I823J-1072D01*
G02X396657Y122245I-398J-42D01*
G03X395536Y119816I-381J-1297D01*
G02X395531Y119143I-219J-335D01*
G03X395136Y118763I720J-1144D01*
G02X394469Y118773I-330J226D01*
G03X392601Y116905I-1138J-730D01*
G02X392605Y116235I-216J-336D01*
G03X394081Y116245I746J-1128D01*
G02X394077Y116915I216J336D01*
G03X394446Y117279I-747J1127D01*
G02X395113Y117269I330J-226D01*
G03X396111Y116654I1138J730D01*
G02X396431Y116084I-41J-398D01*
G03X397790Y116845I1219J-584D01*
G02X397470Y117415I41J398D01*
G03X396991Y119131I-1219J585D01*
G02X396996Y119804I219J335D01*
G03X397620Y121092I-720J1144D01*
G02X398131Y121518I398J42D01*
G03X399326Y123895I381J1297D01*
G02X399323Y124531I241J319D01*
G03X399657Y124904I-823J1073D01*
G02X400342Y124903I342J-207D01*
G03X400343Y126300I1158J698D01*
G02X399658Y126301I-342J207D01*
G03X398366Y126949I-1158J-697D01*
G02X397955Y127496I-40J398D01*
G03X397136Y129280I-1255J504D01*
G01X397000Y129326D01*
Y130500D01*
X397500Y131000D01*
X398000D01*
X398598Y130402D01*
Y130263D01*
G03X399298Y129562I701J0D01*
G01X400700D01*
G03X400740Y129563I2J701D01*
G01X402228D01*
X402292Y129498D01*
X406064D01*
X406158Y129405D01*
G02X405950Y128729I-282J-283D01*
G03X405118Y126589I250J-1329D01*
G02X404822Y125950I-320J-240D01*
G03X404668Y123268I78J-1350D01*
G02X404896Y122606I-69J-394D01*
G03X406132Y123032I1004J-906D01*
G02X405904Y123694I69J394D01*
G03X405982Y125411I-1004J906D01*
G02X406278Y126050I320J240D01*
G03X407529Y127150I-78J1350D01*
G02X408205Y127358I393J-74D01*
G01X408498Y127064D01*
Y125863D01*
G03X408500Y125823I701J15D01*
G01Y125063D01*
X409000Y124563D01*
X413000D01*
X413500Y124063D01*
Y123552D01*
G02X413100Y123152I-400J0D01*
G03X414233Y121063I0J-1352D01*
G01X414500D01*
X415211Y121774D01*
G02X415804Y121745I283J-282D01*
G03X416179Y121427I1047J855D01*
G02X416191Y120740I-199J-347D01*
G03X417576Y120764I713J-1149D01*
G02X417564Y121451I199J347D01*
G03X418041Y121958I-713J1149D01*
G01X418098Y122063D01*
X418500D01*
X419000Y122563D01*
X423428D01*
G02X423764Y121946I0J-400D01*
G03X426036I1136J-733D01*
G02X426372Y122563I336J217D01*
G01X429500D01*
G37*
G36*
G01X402300Y132564D02*
G03X402260Y132563I-2J-701D01*
G01X401500D01*
X401000Y132063D01*
Y130563D01*
X400501Y130064D01*
X399936D01*
X398500Y131500D01*
X398209D01*
X398208Y131502D01*
X397292D01*
X397291Y131500D01*
X397000D01*
X395563Y130063D01*
X394937D01*
X394500Y130500D01*
Y132500D01*
X393937Y133063D01*
X392500D01*
X392000Y133563D01*
Y137563D01*
X393419Y138982D01*
X393461Y138997D01*
G03X394271Y139807I-461J1271D01*
G01X394286Y139849D01*
X395000Y140563D01*
Y144063D01*
X395500Y144563D01*
X397000D01*
X397500Y144063D01*
Y142563D01*
X398500Y141563D01*
X405500D01*
X406000Y141063D01*
Y133063D01*
X405500Y132563D01*
X403740D01*
G03X403700Y132564I-38J-700D01*
G01X402300D01*
G37*
G36*
G01X445500Y139000D02*
X442500Y142000D01*
X439500D01*
X439000Y142500D01*
Y147063D01*
X437500Y148563D01*
X422500D01*
X422437Y148500D01*
X422059D01*
G02X421904Y148827I0J200D01*
G03X419653Y149080I-1043J860D01*
G02X419296Y148500I-357J-180D01*
G01X416603D01*
G02X416260Y149105I0J400D01*
G03X413940I-1160J695D01*
G02X413597Y148500I-343J-205D01*
G01X410500D01*
X410437Y148563D01*
X410371D01*
G02X410021Y149156I0J400D01*
G03X407653I-1184J653D01*
G02X407303Y148563I-350J-193D01*
G01X405000D01*
X404000Y147563D01*
Y146563D01*
X403500Y146063D01*
X402500D01*
X402000Y145563D01*
X398104D01*
X398052Y145615D01*
X395448D01*
X395000Y146063D01*
Y147563D01*
X394500Y148063D01*
X393000D01*
X392000Y149063D01*
Y154235D01*
G02X392584Y154590I400J0D01*
G03X394342Y155054I624J1200D01*
G02X395014I336J-217D01*
G03Y156526I1134J736D01*
G02X394342I-336J217D01*
G03X392584Y156990I-1134J-736D01*
G02X392000Y157345I-184J355D01*
G01Y162563D01*
X392500Y163063D01*
X393500D01*
X393532Y163032D01*
X398992D01*
X399000Y163024D01*
X402600D01*
X404530Y161093D01*
X405261D01*
X405292Y161062D01*
X409708D01*
X409709Y161063D01*
X419264D01*
G02X419637Y160520I0J-400D01*
G03X422163I1263J-483D01*
G02X422536Y161063I373J143D01*
G01X423791D01*
X423792Y161062D01*
X425262D01*
G02X425636Y160520I0J-400D01*
G03X427924Y160923I1264J-480D01*
G02X427943Y161467I302J262D01*
G01X429476Y163000D01*
X431500D01*
X432500Y164000D01*
Y168000D01*
X433500Y169000D01*
Y171000D01*
X436500Y174000D01*
Y174354D01*
X436502Y174355D01*
Y177501D01*
X437000Y178000D01*
X450500D01*
X451000Y177500D01*
Y174000D01*
X449000Y172000D01*
Y167500D01*
X453500Y163000D01*
Y139500D01*
X453000Y139000D01*
X445500D01*
G37*
G36*
G01X400500Y169024D02*
Y169500D01*
X399468Y170532D01*
X398032D01*
X398000Y170563D01*
X392750D01*
X392130Y171183D01*
Y172720D01*
X391680Y173170D01*
X390310D01*
X389334Y174146D01*
Y175396D01*
X389500Y175563D01*
X393980D01*
X394221Y175322D01*
X394229Y175252D01*
G03X394660Y174403I1344J148D01*
G01Y173900D01*
X395460Y173100D01*
X396791D01*
X396838Y172967D01*
G03X397500Y172498I662J233D01*
G01X399100D01*
G03X399762Y172967I0J702D01*
G01X399809Y173100D01*
X403020D01*
X403830Y173910D01*
Y174048D01*
X403846Y174086D01*
G03Y175136I-1246J525D01*
G01X403830Y175174D01*
Y176640D01*
X404280Y177090D01*
X406110D01*
X406498Y176701D01*
Y172498D01*
X405563Y171563D01*
X403910D01*
X402500Y170153D01*
Y168563D01*
X402001Y168064D01*
X401145D01*
X400643Y168566D01*
X400633Y168629D01*
G03X400520Y168984I-1333J-229D01*
G01X400500Y169024D01*
G37*
G36*
G01X395140Y196322D02*
Y201454D01*
X395510Y201824D01*
X411274D01*
Y200501D01*
X410174Y199401D01*
Y193699D01*
X410897Y192976D01*
X410875Y192870D01*
G03X411205Y191685I1325J-270D01*
G02X411192Y191402I-148J-135D01*
G03X413447Y190518I908J-1002D01*
G01X413439Y190611D01*
X414726Y191899D01*
Y196912D01*
X414802Y196987D01*
Y199326D01*
X413726Y200401D01*
Y201790D01*
X418979Y207042D01*
X427979D01*
X429468Y208532D01*
X433468D01*
X435000Y207000D01*
Y201500D01*
X435500Y201000D01*
Y199500D01*
X434500Y198500D01*
Y195548D01*
G03Y194100I1142J-724D01*
G01Y190000D01*
X435000Y189500D01*
Y188000D01*
X430141Y183141D01*
X425641D01*
X425500Y183000D01*
X423266D01*
X423242Y183024D01*
X419942D01*
X419901Y183169D01*
G03X417254Y182926I-1301J-369D01*
G02X416856Y182563I-398J37D01*
G01X415732D01*
G03X414168I-782J-1103D01*
G01X411726D01*
X411714Y182564D01*
G03X411392I-161J-1342D01*
G01X411380Y182563D01*
X410313D01*
X407682Y179932D01*
X407645Y179917D01*
G03X406907Y179179I513J-1251D01*
G01X406892Y179142D01*
X405590Y177840D01*
X404150D01*
X403710Y178280D01*
Y178310D01*
X403598Y178422D01*
X403583Y178463D01*
G03X403538Y178572I-1780J-671D01*
G02X403706Y178852I183J81D01*
G03X404554Y181158I-106J1348D01*
G02Y181442I141J142D01*
G03X404792Y183038I-954J958D01*
G02X405165Y183626I353J188D01*
G03X406314Y184167I66J1350D01*
G02X407001Y184086I320J-240D01*
G03X407159Y185433I1241J537D01*
G02X406472Y185514I-320J240D01*
G03X404039Y184338I-1241J-538D01*
G02X403666Y183750I-353J-188D01*
G03X402646Y181442I-66J-1350D01*
G02Y181158I-141J-142D01*
G03X402250Y180124I954J-958D01*
G02X401842Y179702I-399J-22D01*
G03X400381Y179067I-42J-1902D01*
G01X400322Y179000D01*
X399900D01*
X398600Y180300D01*
X398369D01*
Y180533D01*
X398380Y180564D01*
G03X395818Y180570I-1280J436D01*
G02X395676Y180313I-190J-63D01*
G03X395653Y180307I330J-1311D01*
G01X395628Y180300D01*
X395000D01*
X394600Y179900D01*
Y177000D01*
X394200Y176600D01*
X391600D01*
X391100Y177100D01*
Y180200D01*
X389500Y181800D01*
Y186354D01*
X389648Y186394D01*
G03X390332Y188573I-348J1306D01*
G01X390214Y188714D01*
X390500Y189000D01*
X391942D01*
Y189005D01*
X392232Y189295D01*
X392337Y189274D01*
G03X393689Y189799I263J1326D01*
G02X394374Y189730I322J-237D01*
G03X396951Y190353I1226J570D01*
G02X397454Y190755I400J16D01*
G03X397731Y193411I351J1306D01*
G02X397365Y194013I-21J399D01*
G03X395691Y195952I-1165J687D01*
G02X395140Y196322I-151J371D01*
G37*
G36*
G01X410500Y203000D02*
X399500D01*
X396500Y206000D01*
X395500D01*
X395000Y206500D01*
Y208000D01*
X395500Y208500D01*
X397000D01*
X399000Y210500D01*
X405000D01*
X405500Y210000D01*
Y207000D01*
X407500Y205000D01*
X410500D01*
X411000Y204500D01*
Y203500D01*
X410500Y203000D01*
G37*
G36*
G01X519000Y206500D02*
X513000Y212500D01*
X509000D01*
X502651Y206152D01*
X469349D01*
X441500Y234000D01*
Y246500D01*
X441974Y246974D01*
X458700D01*
X459226Y247500D01*
X461000D01*
X464000Y250500D01*
X467000D01*
X469500Y248000D01*
Y243825D01*
X469487Y243791D01*
G03X469398Y243300I1313J-492D01*
G01Y241700D01*
G03X469487Y241209I1402J1D01*
G01X469500Y241175D01*
Y230500D01*
X471750Y228250D01*
X488750D01*
X496000Y221000D01*
X528000D01*
X531250Y224250D01*
X550250D01*
X551500Y223000D01*
Y221500D01*
X550000Y220000D01*
Y211954D01*
G02X549400Y211607I-400J0D01*
G03X547137Y207830I-1100J-1907D01*
G02X547208Y207208I-212J-339D01*
G01X546500Y206500D01*
X519000D01*
G37*
G36*
G01X709500Y108500D02*
X727000Y91000D01*
X753500D01*
X777000Y114500D01*
X787000D01*
X789000Y112500D01*
Y98500D01*
X788500Y98000D01*
X782500D01*
X779500Y95000D01*
Y90000D01*
X789250Y80250D01*
X797500D01*
X799375Y82125D01*
Y87375D01*
X809000Y97000D01*
Y115000D01*
X804000Y120000D01*
Y120175D01*
X804013Y120209D01*
G03X804102Y120700I-1313J492D01*
G01Y122300D01*
G03X804013Y122791I-1402J-1D01*
G01X804000Y122825D01*
Y123675D01*
X804013Y123709D01*
G03X804102Y124200I-1313J492D01*
G01Y125800D01*
G03X804097Y125906I-1401J-13D01*
G02X804397Y126094I200J15D01*
G03X807112Y126500I1103J1906D01*
G01X812000D01*
X814500Y129000D01*
Y161500D01*
X811986Y164014D01*
X811994Y164107D01*
G03X807874Y165702I-2294J193D01*
G01X805002D01*
Y167500D01*
G03X804122Y168801I-1402J0D01*
G01X804084Y168816D01*
X802500Y170400D01*
X801555D01*
G03X800355Y171057I-1656J-1600D01*
G02X800068Y171609I79J392D01*
G03X800202Y172250I-1468J641D01*
G01Y174550D01*
G03X800139Y174993I-1602J-2D01*
G01X800106Y175106D01*
X800400Y175400D01*
X806600D01*
X807600Y176400D01*
Y176636D01*
G02X808120Y177018I400J0D01*
G03Y181982I780J2482D01*
G02X807600Y182364I-120J382D01*
G01Y183400D01*
X800000Y191000D01*
Y200500D01*
X801500Y202000D01*
Y218000D01*
X802200Y218700D01*
Y263900D01*
X803000Y264700D01*
X806300D01*
X810500Y260500D01*
X813000D01*
X815000Y262500D01*
Y274129D01*
G02X815441Y274527I400J0D01*
G03X812223Y284000I559J5473D01*
G01X808500D01*
X808000Y284500D01*
Y287000D01*
X808500Y287500D01*
X822500D01*
X823500Y286500D01*
Y4500D01*
X822000Y3000D01*
X780000D01*
X779000Y4000D01*
Y13500D01*
X779500Y14000D01*
X782500D01*
X788000Y8500D01*
X791500D01*
X793000Y10000D01*
Y13778D01*
X793007Y13804D01*
G03Y15196I-2507J696D01*
G01X793000Y15222D01*
Y16500D01*
X791926Y17574D01*
Y17591D01*
X787191Y22326D01*
X787174D01*
X781500Y28000D01*
Y42000D01*
X763000Y60500D01*
X762666D01*
X762611Y60543D01*
G03X759336Y60500I-1611J-2043D01*
G01X752500D01*
X752000Y61000D01*
Y63000D01*
X750000Y65000D01*
X737500D01*
X737136Y65364D01*
X737163Y65472D01*
G03X737202Y65800I-1363J328D01*
G01Y67200D01*
G03X735800Y68602I-1402J0D01*
G01X734200D01*
G03X733709Y68513I1J-1402D01*
G01X733675Y68500D01*
X732000D01*
X728000Y64500D01*
Y51000D01*
X729000Y50000D01*
X735000D01*
X736000Y49000D01*
Y45000D01*
X735000Y44000D01*
X688500D01*
X681000Y51500D01*
X667000D01*
X665664Y50164D01*
X665561Y50184D01*
G03X665300Y50208I-258J-1377D01*
G01X663700D01*
G03X663000Y50021I-1J-1401D01*
G03X662300Y50208I-699J-1214D01*
G01X660700D01*
G03X660000Y50021I-1J-1401D01*
G03X659300Y50208I-699J-1214D01*
G01X657700D01*
G03X656965Y50000I0J-1401D01*
G01X649000D01*
X648502Y50498D01*
Y50657D01*
G03X646900Y52258I-1601J0D01*
G01X643700D01*
G03X642873Y52029I-2J-1601D01*
G01X642826Y52000D01*
X642500D01*
X640000Y49500D01*
X621000D01*
X619000Y51500D01*
X605000D01*
X597500Y44000D01*
X513000D01*
X512000Y45000D01*
Y49182D01*
X512013Y49216D01*
G03X512102Y49707I-1313J492D01*
G01Y51307D01*
G03X512099Y51384I-1401J-16D01*
G02X512499Y51806I400J22D01*
G01X573493D01*
X581643Y59956D01*
X688113D01*
X706696Y78539D01*
Y91937D01*
G03X707000Y94686I-1551J1563D01*
G02X707318Y95301I337J215D01*
G03X705702Y99106I-109J2199D01*
G01X705644Y99052D01*
X705357D01*
X700994Y94688D01*
Y80902D01*
X685750Y65658D01*
X578907D01*
X571007Y57758D01*
X519094D01*
X519038Y57865D01*
G03X517800Y58608I-1237J-659D01*
G01X516200D01*
G03X515462Y58399I-2J-1401D01*
G03X514100Y59158I-1362J-843D01*
G01X510900D01*
G03X509405Y58130I0J-1601D01*
G01X509389Y58091D01*
X501164Y49865D01*
Y49664D01*
X500500Y49000D01*
Y27244D01*
G02X499959Y26870I-400J0D01*
G03Y18726I-1534J-4072D01*
G02X500500Y18352I141J-374D01*
G01Y9500D01*
X498626Y7626D01*
X472375D01*
X471502Y8500D01*
Y10502D01*
X477000Y16000D01*
Y36000D01*
X484000Y43000D01*
Y47500D01*
X473682Y57818D01*
Y83182D01*
X477327Y86826D01*
X498117D01*
X498134Y86824D01*
G03X500699Y89106I366J2171D01*
G01X500695Y89195D01*
X501496Y89996D01*
X502499D01*
X502948Y89547D01*
Y83072D01*
X503000Y83020D01*
Y83000D01*
X512000Y74000D01*
X641000D01*
X651000Y84000D01*
Y99498D01*
X660002Y108500D01*
X709500D01*
G37*
G36*
G01X502984Y223000D02*
Y225606D01*
X495395D01*
X491000Y230000D01*
X472000D01*
X470702Y231298D01*
Y248498D01*
X470500Y248699D01*
Y250000D01*
X473250Y252750D01*
X497750D01*
X501000Y249500D01*
Y239500D01*
X512500Y228000D01*
X517778D01*
X517804Y227993D01*
G03X519196I696J2507D01*
G01X519222Y228000D01*
X527500D01*
X528500Y227000D01*
Y224000D01*
X527500Y223000D01*
X502984D01*
G37*
G36*
G01X746788Y193298D02*
X763000Y177087D01*
Y176000D01*
X770000Y169000D01*
Y164000D01*
X774000Y160000D01*
X776176D01*
G03X776900Y159798I725J1200D01*
G01X778700D01*
G03X779381Y159975I-1J1402D01*
G01X779426Y160000D01*
X779574D01*
X779619Y159975D01*
G03X780300Y159798I682J1225D01*
G01X780702D01*
X781000Y159500D01*
Y155500D01*
X780500Y155000D01*
X772854D01*
G03X768863Y155637I-2254J-1300D01*
G01X766000Y158500D01*
X757500D01*
X755500Y156500D01*
Y151126D01*
G03Y146874I1500J-2126D01*
G01Y144500D01*
X752000Y141000D01*
Y126500D01*
X750577Y125077D01*
X750480Y125090D01*
G03X750300Y125102I-183J-1390D01*
G01X748700D01*
G03X748209Y125013I1J-1402D01*
G01X748175Y125000D01*
X744480D01*
X744431Y125129D01*
G03X739679Y125376I-2431J-929D01*
G03X739100Y125502I-581J-1276D01*
G01X737500D01*
G03X737414Y125499I6J-1402D01*
G02X737202Y125698I-12J199D01*
G01Y127400D01*
G03X737000Y128124I-1402J-1D01*
G01Y130039D01*
G03X737002Y130100I-1399J76D01*
G01Y131700D01*
G03X737000Y131761I-1401J-15D01*
G01Y139000D01*
X736000Y140000D01*
X733865D01*
X733763Y140102D01*
X733251D01*
G03X728681Y139150I-2050J-1602D01*
G01X728642Y139000D01*
X726500D01*
X726000Y139500D01*
Y167000D01*
X715500Y177500D01*
Y184000D01*
X681000Y218500D01*
X614001D01*
X609600Y222902D01*
X568098D01*
X566282Y224718D01*
X566267Y224759D01*
G03X564959Y226067I-2067J-759D01*
G01X564918Y226082D01*
X563384Y227616D01*
X563375Y227681D01*
G03X561511Y229545I-2179J-315D01*
G01X561446Y229554D01*
X561000Y230000D01*
X540500D01*
X540000Y230500D01*
Y234360D01*
G03X540002Y234400I-699J55D01*
G01Y236200D01*
G03X540000Y236240I-701J-15D01*
G01Y236500D01*
X539500Y237000D01*
X538000D01*
X537500Y237500D01*
Y241000D01*
X538000Y241500D01*
X569500D01*
X578500Y232500D01*
X598000D01*
X600000Y234500D01*
X602500D01*
X604000Y233000D01*
X608500D01*
X609500Y234000D01*
X625000D01*
X626000Y233000D01*
X645500D01*
X653000Y240500D01*
X714000D01*
X725700Y228800D01*
G03X729569Y227017I1700J-1400D01*
G01X729579Y227079D01*
X738500Y236000D01*
X742000D01*
X743000Y237000D01*
X748000D01*
X751000Y240000D01*
Y254500D01*
X752998Y256498D01*
X776002D01*
X776500Y256000D01*
Y241500D01*
X777000Y241000D01*
Y226500D01*
X778500Y225000D01*
X780000D01*
X780500Y224500D01*
Y206500D01*
X778500Y204500D01*
X776000D01*
X774000Y202500D01*
Y185000D01*
X771500Y182500D01*
X765500D01*
X764657Y181657D01*
X748612Y197702D01*
X743100D01*
G03Y193298I0J-2202D01*
G01X746788D01*
G37*
G36*
G01X579500Y234000D02*
X578500Y235000D01*
Y238500D01*
X581500Y241500D01*
X584100D01*
X585000Y242400D01*
Y249700D01*
X585200Y249900D01*
X586000D01*
X586300Y249600D01*
Y242300D01*
X587100Y241500D01*
X593600D01*
X594400Y242300D01*
Y249600D01*
X594800Y250000D01*
X595400D01*
X595800Y249600D01*
Y242400D01*
X596700Y241500D01*
X603200D01*
X603800Y242100D01*
Y249600D01*
X604200Y250000D01*
X604800D01*
X605200Y249600D01*
Y242200D01*
X605900Y241500D01*
X610300D01*
X610900Y242100D01*
Y249600D01*
X611300Y250000D01*
X611900D01*
X612300Y249600D01*
Y242200D01*
X613000Y241500D01*
X619600D01*
X620400Y242300D01*
Y249600D01*
X620800Y250000D01*
X621400D01*
X621700Y249700D01*
Y242400D01*
X622600Y241500D01*
X629200D01*
X629900Y242200D01*
Y249700D01*
X630200Y250000D01*
X630800D01*
X631200Y249600D01*
Y242200D01*
X631900Y241500D01*
X638600D01*
X639300Y242200D01*
Y249700D01*
X639600Y250000D01*
X640300D01*
X640600Y249700D01*
Y243400D01*
X645500Y238500D01*
Y235000D01*
X645000Y234500D01*
X626500D01*
X625700Y235300D01*
X625326D01*
X625281Y235325D01*
G03X624600Y235502I-682J-1225D01*
G01X623000D01*
G03X622300Y235314I1J-1402D01*
G03X621600Y235502I-701J-1214D01*
G01X620000D01*
G03X619300Y235314I1J-1402D01*
G03X618600Y235502I-701J-1214D01*
G01X617000D01*
G03X616276Y235300I1J-1402D01*
G01X608400D01*
X607800Y234700D01*
X604000D01*
X602700Y236000D01*
X599800D01*
X597800Y234000D01*
X579500D01*
G37*
G36*
G01X613600Y35507D02*
X613300Y35807D01*
Y42907D01*
X612700Y43507D01*
X605500D01*
X604500Y44507D01*
Y49007D01*
X605792Y50298D01*
X618208D01*
X619900Y48607D01*
X620194D01*
X620502Y48298D01*
X640498D01*
X642998Y50798D01*
X646502D01*
X648502Y48798D01*
X665998D01*
X667498Y50298D01*
X680208D01*
X680500Y50007D01*
Y44907D01*
X680000Y44407D01*
X669600D01*
X669000Y43807D01*
Y36007D01*
X668600Y35607D01*
X668000D01*
X667700Y35907D01*
Y43207D01*
X666900Y44007D01*
X660300D01*
X659400Y43107D01*
Y35807D01*
X659200Y35607D01*
X658400D01*
X658200Y35807D01*
Y43307D01*
X657500Y44007D01*
X650900D01*
X650000Y43107D01*
Y36107D01*
X649500Y35607D01*
X649100D01*
X648800Y35907D01*
Y43407D01*
X648200Y44007D01*
X643800D01*
X643000Y43207D01*
Y36007D01*
X642600Y35607D01*
X641900D01*
X641700Y35807D01*
Y43107D01*
X640800Y44007D01*
X634300D01*
X633500Y43207D01*
Y36007D01*
X633000Y35507D01*
X632500D01*
X632200Y35807D01*
Y43407D01*
X631600Y44007D01*
X625200D01*
X624200Y43007D01*
Y36007D01*
X623900Y35707D01*
X622900D01*
X622700Y35907D01*
Y43407D01*
X622100Y44007D01*
X616100D01*
X614700Y42607D01*
Y36107D01*
X614100Y35507D01*
X613600D01*
G37*
G36*
G01X764869Y52131D02*
X767753Y49247D01*
X767768Y49214D01*
G03X768714Y48268I1732J786D01*
G01X768747Y48253D01*
X772000Y45000D01*
Y18000D01*
X773000Y17000D01*
X773498D01*
Y15800D01*
G03X774200Y15098I702J0D01*
G01X774874D01*
X775824Y14148D01*
X777798D01*
Y3798D01*
X777000Y3000D01*
X754500D01*
X753700Y3800D01*
Y14173D01*
G02X754343Y14490I400J0D01*
G03Y17510I1157J1510D01*
G02X753700Y17827I-243J317D01*
G01Y18108D01*
X753862Y18140D01*
G03X754442Y21659I-362J1867D01*
G02Y22355I198J348D01*
G03X753862Y25874I-942J1652D01*
G01X753700Y25906D01*
Y26608D01*
X753862Y26640D01*
G03Y30374I-362J1867D01*
G01X753700Y30406D01*
Y34600D01*
X752650Y35650D01*
Y42500D01*
X754500Y44350D01*
Y50000D01*
X753000Y51500D01*
X749110D01*
X749096Y51502D01*
G03X749000Y51508I-92J-695D01*
G01X747200D01*
G03X747104Y51502I-4J-701D01*
G01X747090Y51500D01*
X745710D01*
X745696Y51502D01*
G03X745600Y51508I-92J-695D01*
G01X743800D01*
G03X743704Y51502I-4J-701D01*
G01X743690Y51500D01*
X730000D01*
X729500Y52000D01*
Y63500D01*
X733298Y67298D01*
X735502D01*
X735798Y67002D01*
Y65745D01*
G03Y65655I2202J-45D01*
G01Y65002D01*
X735982Y64819D01*
G03X736000Y64779I2017J884D01*
G01Y64500D01*
X737000Y63500D01*
X737910D01*
G03X738090I90J2200D01*
G01X749500D01*
X750500Y62500D01*
Y60000D01*
X751000Y59500D01*
X751801D01*
X752002Y59298D01*
X757702D01*
X758399Y58601D01*
X758398Y58518D01*
G03X761018Y55898I2602J-18D01*
G01X761101Y55899D01*
X762631Y54369D01*
X762617Y54270D01*
G03X764770Y52117I1883J-270D01*
G01X764869Y52131D01*
G37*
G36*
G01X800000Y90500D02*
X782000D01*
X781000Y91500D01*
Y94500D01*
X782500Y96000D01*
X791500D01*
X792000Y96500D01*
Y111500D01*
X798000Y117500D01*
X804500D01*
X806500Y115500D01*
Y97000D01*
X800000Y90500D01*
G37*
G36*
G01X777200Y186300D02*
X775500Y188000D01*
Y201000D01*
X777000Y202500D01*
X779500D01*
X782500Y205500D01*
Y224800D01*
X780800Y226500D01*
X779500D01*
X778500Y227500D01*
Y242000D01*
X778000Y242500D01*
Y256000D01*
X778498Y256498D01*
X785601D01*
X785603Y256500D01*
X789000D01*
X790500Y258000D01*
Y263000D01*
X794000Y266500D01*
X800000D01*
X801000Y265500D01*
Y264399D01*
X800998Y264398D01*
Y219998D01*
X800000Y219000D01*
Y203000D01*
X798500Y201500D01*
Y190000D01*
X800000Y188500D01*
Y187300D01*
X799000Y186300D01*
X777200D01*
G37*
%LPC*%
G75*
G36*
G01X9381Y120113D02*
G03X9395Y120752I-233J325D01*
G02X9188Y124667I1605J2048D01*
G03X9121Y125293I-279J287D01*
G02X12450Y129223I1379J2206D01*
G03X13050I300J264D01*
G02X16812Y125633I1950J-1723D01*
G03X16879Y125007I279J-287D01*
G02X17019Y120687I-1379J-2207D01*
G03X17005Y120048I233J-325D01*
G02X13450Y116277I-1605J-2048D01*
G03X12850I-300J-264D01*
G02X9381Y120113I-1950J1724D01*
G37*
G36*
G01X8950Y165423D02*
G03X9550I300J264D01*
G02X13119Y161663I1950J-1723D01*
G03Y161037I249J-313D01*
G02X9550Y157277I-1619J-2037D01*
G03X8950I-300J-264D01*
G02X5381Y161037I-1950J1723D01*
G03Y161663I-249J313D01*
G02X8950Y165423I1619J2037D01*
G37*
G36*
G01X86700Y238600D02*
Y238200D01*
X87700D01*
Y237200D01*
X86700D01*
Y237600D01*
X85700D01*
Y238600D01*
X86700D01*
G37*
G36*
G01X92300Y226300D02*
Y225300D01*
X91300D01*
Y225150D01*
X90300D01*
Y226150D01*
X91300D01*
Y226300D01*
X92300D01*
G37*
G36*
G01X98721Y264590D02*
G03X98628Y265189I-304J259D01*
G02X101979Y265710I1372J2211D01*
G03X102072Y265111I304J-259D01*
G02X98721Y264590I-1372J-2211D01*
G37*
G36*
G01X220169Y253057D02*
G03X219596Y252724I-174J-360D01*
G02X215717Y255164I-2596J176D01*
G03X215744Y255843I-197J348D01*
G02X219797Y258166I1456J2157D01*
G03X220343Y257820I399J26D01*
G02X220169Y253057I957J-2420D01*
G37*
G36*
G01X131702Y254412D02*
Y253888D01*
X131730Y253841D01*
G02X127270I-2230J-1341D01*
G01X127298Y253888D01*
Y254412D01*
X127270Y254459D01*
G02X131730I2230J1341D01*
G01X131702Y254412D01*
G37*
G36*
G01X165627Y238548D02*
X164073D01*
X164041Y238538D01*
G02Y243462I-841J2462D01*
G01X164073Y243452D01*
X165627D01*
X165659Y243462D01*
G02Y238538I841J-2462D01*
G01X165627Y238548D01*
G37*
G36*
G01X111402Y248087D02*
G02X111401Y245313I-2202J-1386D01*
G01Y241322D01*
G02X110166Y237298I-1235J-1822D01*
G01X110000D01*
G02X108443Y237943I0J2202D01*
G01X106998Y239388D01*
Y245313D01*
G02X106601Y246568I2202J1387D01*
G03X106002Y246893I-399J-21D01*
G02X106337Y250468I-1102J1906D01*
G03X106998Y250771I261J303D01*
G01Y253679D01*
X106986Y253713D01*
G02X106898Y254200I1314J489D01*
G01Y255800D01*
G02X106986Y256287I1402J-2D01*
G01X106998Y256321D01*
Y258912D01*
X107943Y259857D01*
G02X111426Y257235I1556J-1557D01*
G01X111402Y257189D01*
Y256321D01*
X111414Y256287D01*
G02X111502Y255800I-1314J-489D01*
G01Y254200D01*
G02X111414Y253713I-1402J2D01*
G01X111402Y253679D01*
Y248087D01*
G37*
G36*
G01X149668Y236201D02*
X148233Y234767D01*
G02X144767Y238233I-1733J1733D01*
G01X146201Y239668D01*
G02X149668Y236201I2350J-1117D01*
G37*
G36*
G01X148202Y231000D02*
Y229487D01*
G02X143798I-2202J-1387D01*
G01Y231000D01*
G02X148202I2202J0D01*
G37*
G36*
G01X128200Y169500D02*
X127200D01*
Y170500D01*
X127600D01*
Y171500D01*
X128600D01*
Y170500D01*
X128200D01*
Y169500D01*
G37*
G36*
G01X176500Y164100D02*
X177500D01*
Y163100D01*
X176500Y161850D01*
X175500D01*
Y162850D01*
X176500Y164100D01*
G37*
G36*
G01X267800Y69500D02*
X268800D01*
X269650Y68000D01*
Y67000D01*
X268650D01*
X267800Y68500D01*
Y69500D01*
G37*
G36*
G01X409412Y139738D02*
Y138738D01*
X409400Y138563D01*
Y137563D01*
X408400D01*
Y138563D01*
X408412Y138738D01*
Y139738D01*
X409412D01*
G37*
G36*
G01X462500Y118000D02*
X461500Y117000D01*
X451500D01*
X450500Y118000D01*
Y134000D01*
X451500Y135000D01*
X461500D01*
X461853Y134647D01*
G03X462137Y134648I142J142D01*
G02X462946Y132357I963J-948D01*
G03X462500Y131959I-46J-397D01*
G01Y127926D01*
G03X462968Y127532I400J0D01*
G02Y124868I232J-1332D01*
G03X462500Y124474I-68J-394D01*
G01Y118000D01*
G37*
G36*
G01X422089Y177434D02*
G02X422009Y178921I-1167J683D01*
G03X422675Y178957I321J238D01*
G02X422755Y177470I1167J-683D01*
G03X422089Y177434I-321J-238D01*
G37*
G36*
G01X423547Y166513D02*
G02X422618Y165479I398J-1292D01*
G03X422108Y165938I-393J77D01*
G02X423037Y166972I-398J1292D01*
G03X423547Y166513I393J-77D01*
G37*
G36*
G01X422126Y130672D02*
G02X422040Y132112I-1184J652D01*
G03X422716Y132152I325J233D01*
G02X422802Y130712I1184J-652D01*
G03X422126Y130672I-325J-233D01*
G37*
G36*
G01X337702Y94744D02*
G03Y94460I141J-142D01*
G02X335798I-952J-960D01*
G03Y94744I-141J142D01*
G02X337702I952J960D01*
G37*
G36*
G01X345340Y100340D02*
X346340D01*
Y99340D01*
X346600Y99000D01*
Y98000D01*
X345600D01*
Y99000D01*
X345340Y99340D01*
Y100340D01*
G37*
G36*
G01X362865Y104684D02*
G03X362485Y104242I18J-400D01*
G02X361079Y105450I-1344J-143D01*
G03X361459Y105892I-18J400D01*
G02X362865Y104684I1344J143D01*
G37*
G36*
G01X357050Y132200D02*
Y134200D01*
X359050D01*
Y133200D01*
X358050Y132200D01*
X357050D01*
G37*
G36*
G01X356500Y172600D02*
Y173600D01*
X358500D01*
Y171400D01*
X357500D01*
X356500Y172600D01*
G37*
G36*
G01X363850Y134200D02*
Y133200D01*
X364000Y132900D01*
Y131900D01*
X363000D01*
Y132900D01*
X362850Y133200D01*
Y134200D01*
X363850D01*
G37*
G36*
G01X373000Y187200D02*
Y186200D01*
X372880Y186110D01*
Y185110D01*
X371880D01*
Y186110D01*
X372000Y186200D01*
Y187200D01*
X373000D01*
G37*
G36*
G01X371056Y238758D02*
G02X370770Y235401I-1556J-1558D01*
G02X368230I-1270J-801D01*
G02X367944Y238758I1270J1799D01*
G03Y239042I-141J142D01*
G02X368277Y242431I1556J1558D01*
G03X368359Y243024I-222J333D01*
G02X370641I1141J976D01*
G03X370723Y242431I304J-260D01*
G02X371056Y239042I-1223J-1831D01*
G03Y238758I141J-142D01*
G37*
G36*
G01X387900Y153000D02*
X386900D01*
Y154000D01*
X388000Y154863D01*
X389000D01*
Y153863D01*
X387900Y153000D01*
G37*
G36*
G01X387600Y210000D02*
Y209000D01*
X387200D01*
Y208000D01*
X386200D01*
Y209000D01*
X386600D01*
Y210000D01*
X387600D01*
G37*
G36*
G01X387467Y205800D02*
X388000D01*
Y204800D01*
X387000Y204100D01*
X386000D01*
Y205100D01*
X386909Y205736D01*
X386353Y206569D01*
X386769Y206847D01*
X387467Y205800D01*
G37*
G36*
G01X390733Y239844D02*
X390726Y239851D01*
X393169Y242220D01*
X393180D01*
X393205Y242242D01*
G02X395741Y241138I1023J-1114D01*
G01X395742D01*
Y241136D01*
X395740D01*
Y241130D01*
X395741D01*
G02X395740Y241061I-1512J-13D01*
G01Y241043D01*
X395738Y241023D01*
G02X395284Y240044I-1509J105D01*
G01X395291Y240037D01*
X393982Y238768D01*
X393980D01*
X393975Y238762D01*
X393977D01*
X392846Y237665D01*
X392845Y237666D01*
X392750Y237593D01*
G02X390733Y239844I-963J1166D01*
G37*
G36*
G01X398367Y244906D02*
X400767Y247315D01*
G02X403350Y246258I1071J-1067D01*
G01Y246163D01*
X403340Y246079D01*
G02X402909Y245181I-1503J169D01*
G01X401534Y243802D01*
X400530Y242794D01*
X400529Y242793D01*
G02X398367Y244906I-1091J1046D01*
G37*
G36*
G01X393996Y105663D02*
X394996D01*
Y105263D01*
X395996D01*
Y104263D01*
X394996D01*
Y104663D01*
X393996D01*
Y105663D01*
G37*
G36*
G01X420943Y113583D02*
G02X420137Y114702I-1347J-120D01*
G03X420695Y115104I160J367D01*
G02X423141Y116011I1347J120D01*
G03X423748Y115960I325J233D01*
G02X423601Y114213I952J-960D01*
G03X422994Y114264I-325J-233D01*
G02X421501Y113985I-952J960D01*
G03X420943Y113583I-160J-367D01*
G37*
G36*
G01X401921Y117789D02*
G02X400635Y117708I-568J-1227D01*
G03X400591Y118409I-213J339D01*
G02X401877Y118490I568J1227D01*
G03X401921Y117789I213J-339D01*
G37*
G36*
G01X429111Y104985D02*
G03X428912Y104783I1J-200D01*
G02X427554Y106122I-1352J-13D01*
G03X427753Y106324I-1J200D01*
G02X429111Y104985I1352J13D01*
G37*
G36*
G01X428959Y115456D02*
G03X428933Y115172I127J-155D01*
G02X427041Y115344I-1033J-872D01*
G03X427067Y115628I-127J155D01*
G02X428959Y115456I1033J872D01*
G37*
G36*
G01X421663Y119681D02*
G03X421647Y119156I294J-272D01*
G02X419609Y119219I-1046J-856D01*
G03X419625Y119744I-294J272D01*
G02X421663Y119681I1046J856D01*
G37*
G36*
G01X438740Y121779D02*
G03X439197Y121437I396J53D01*
G02X438060Y119921I203J-1337D01*
G03X437603Y120263I-396J-53D01*
G02X438740Y121779I-203J1337D01*
G37*
G36*
G01X405000Y110863D02*
X405500Y110463D01*
X406500D01*
Y109463D01*
X405500D01*
X405000Y109863D01*
X404000D01*
Y110863D01*
X405000D01*
G37*
G36*
G01X403612Y139738D02*
X404612D01*
Y138738D01*
X404600Y138563D01*
Y137563D01*
X403600D01*
Y138563D01*
X403612Y138738D01*
Y139738D01*
G37*
G36*
G01X393395Y182779D02*
G02X391823Y182793I-796J-1093D01*
G03X391828Y183444I-230J327D01*
G02X393873Y185054I796J1093D01*
G03X394552Y184955I369J154D01*
G02X395699Y185448I1047J-855D01*
G03X396089Y186021I30J399D01*
G02X398575Y187076I1218J586D01*
G03X399259Y186960I375J139D01*
G02X399033Y185630I1042J-861D01*
G03X398349Y185746I-375J-139D01*
G02X397208Y185259I-1042J861D01*
G03X396818Y184686I-30J-399D01*
G02X394351Y183583I-1218J-586D01*
G03X393672Y183682I-369J-154D01*
G02X393400Y183430I-1046J857D01*
G03X393395Y182779I230J-327D01*
G37*
G36*
G01X416658Y187381D02*
G02X415326I-666J-1176D01*
G03Y188078I-197J349D01*
G02X416658I666J1176D01*
G03Y187381I197J-348D01*
G37*
G36*
G01X420284Y188915D02*
G02X420268Y190239I-1187J648D01*
G03X420965Y190248I346J200D01*
G02X420981Y188924I1187J-648D01*
G03X420284Y188915I-346J-200D01*
G37*
G36*
G01X430405Y189341D02*
G02X430111Y190594I-1305J355D01*
G03X430795Y190755I298J266D01*
G02X431089Y189502I1305J-355D01*
G03X430405Y189341I-298J-266D01*
G37*
G36*
G01X408790Y191716D02*
G02X407533Y191676I-590J-1216D01*
G03X407510Y192384I-198J348D01*
G02X408767Y192424I590J1216D01*
G03X408790Y191716I198J-348D01*
G37*
G36*
G01X404800Y192037D02*
G02X403674Y190439I200J-1337D01*
G03X403222Y190757I-393J-78D01*
G02X402249Y193203I-200J1337D01*
G03X402236Y193868I-229J328D01*
G02X403740Y193896I731J1137D01*
G03X403753Y193231I229J-328D01*
G02X404348Y192355I-731J-1137D01*
G03X404800Y192037I393J78D01*
G37*
G36*
G01X422247Y200739D02*
G02X420690Y201051I-994J-917D01*
G03X420817Y201686I-167J364D01*
G02X422374Y201374I994J917D01*
G03X422247Y200739I167J-364D01*
G37*
G36*
G01X430278Y195976D02*
G03X430136Y195730I51J-193D01*
G02X428485Y196686I-1306J-351D01*
G03X428627Y196932I-51J193D01*
G02X430278Y195976I1306J351D01*
G37*
G36*
G01X422500Y205663D02*
Y204663D01*
X421500D01*
Y204600D01*
X420500D01*
Y205600D01*
X421500D01*
Y205663D01*
X422500D01*
G37*
G36*
G01X396500Y198700D02*
Y199700D01*
X397500D01*
X398170Y198603D01*
Y197603D01*
X397170D01*
X396500Y198700D01*
G37*
G36*
G01X625000Y51907D02*
X626000D01*
Y50907D01*
X624500Y50057D01*
X623500D01*
Y51057D01*
X625000Y51907D01*
G37*
G36*
G01X744000Y235600D02*
Y234600D01*
X743000D01*
X742500Y234450D01*
X741500D01*
Y235450D01*
X742500D01*
X743000Y235600D01*
X744000D01*
G37*
G36*
G01X739200Y136600D02*
Y135600D01*
X739600D01*
Y134600D01*
X738600D01*
Y135600D01*
X738200D01*
Y136600D01*
X739200D01*
G37*
G36*
G01X739600Y133600D02*
Y132600D01*
X739300Y132400D01*
Y131400D01*
X738300D01*
Y132400D01*
X738600Y132600D01*
Y133600D01*
X739600D01*
G37*
G36*
G01X742013Y213419D02*
G03X742490Y213142I384J112D01*
G02X740887Y210381I510J-2142D01*
G03X740410Y210658I-384J-112D01*
G02X738229Y214234I-510J2142D01*
G03X738214Y214772I-303J261D01*
G02X741632Y217522I1586J1527D01*
G03X742247Y217461I333J222D01*
G02X741968Y214678I1553J-1561D01*
G03X741353Y214739I-333J-222D01*
G03X741361Y214447I141J-142D01*
G02X742013Y213419I-1461J-1647D01*
G37*
G36*
G01X726636Y174731D02*
G03X726114Y174642I-211J-340D01*
G02X725564Y177894I-1714J1383D01*
G03X726086Y177983I211J340D01*
G02X726636Y174731I1714J-1383D01*
G37*
G36*
G01X741857Y166257D02*
G02X738743Y163143I-1557J-1557D01*
G01X730798Y171088D01*
Y176200D01*
G02X731198Y177465I2202J0D01*
G01Y183223D01*
G02X731141Y186921I1802J1877D01*
G01X731198Y186979D01*
Y187254D01*
X725123Y193330D01*
X725063Y193342D01*
G02X723698Y196766I437J2158D01*
G01Y205446D01*
X728830Y210577D01*
X728842Y210637D01*
G02X731437Y208042I2158J-437D01*
G01X731377Y208030D01*
X727302Y203954D01*
Y196766D01*
G02X727658Y195937I-1802J-1265D01*
G01X727670Y195877D01*
X734802Y188746D01*
Y186977D01*
G02Y183223I-1802J-1877D01*
G01Y177465D01*
G02X735202Y176200I-1802J-1265D01*
G01Y172912D01*
X741857Y166257D01*
G37*
G36*
G01X626500Y238150D02*
Y237150D01*
X625500D01*
X625300Y236800D01*
X624300D01*
Y237800D01*
X625300D01*
X625500Y238150D01*
X626500D01*
G37*
G36*
G01X607500D02*
X608500D01*
X609700Y237500D01*
Y236500D01*
X608700D01*
X607500Y237150D01*
Y238150D01*
G37*
G54D115*
X129000Y268000D03*
X721200Y65100D03*
G54D114*
X97600Y246500D03*
X366700Y68700D03*
X718900Y94000D03*
X744100Y221900D03*
G54D118*
X416000Y135983D03*
X418500Y128200D03*
X413300Y139100D03*
X418439Y167118D03*
X416400Y170300D03*
X431700Y128300D03*
X419500Y136400D03*
X430100Y131500D03*
X425000Y135350D03*
X422400Y139000D03*
X424856Y142270D03*
X427600Y143841D03*
X428390Y139059D03*
X430694Y142275D03*
X431100Y145500D03*
X421500Y142400D03*
X419453Y173187D03*
X426970Y178310D03*
X430340Y177620D03*
X420975Y211300D03*
X438742Y197224D03*
X471300Y181800D03*
X473900Y178200D03*
X466900D03*
X469500Y189000D03*
X473100Y185500D03*
X466000D03*
X355175Y108212D03*
X354333Y125665D03*
X361200Y97500D03*
X365000Y94700D03*
X357721Y95100D03*
X364874Y98250D03*
X357900Y99200D03*
X358000Y115500D03*
X359942Y110924D03*
X365316Y108130D03*
X364800Y91200D03*
X361200Y90200D03*
X357721Y91779D03*
X360900Y94200D03*
X356900Y186100D03*
X353342Y186124D03*
X364600Y137063D03*
X368100Y162200D03*
X434960Y114529D03*
X438700Y112900D03*
X438500Y116400D03*
X428100Y120000D03*
X430302Y112098D03*
X412462Y115713D03*
X404529Y118507D03*
X409196Y118195D03*
X405200Y115343D03*
X409110Y114910D03*
X393482Y123982D03*
X401749Y112418D03*
X399452Y133964D03*
X410100Y157700D03*
X413314Y154908D03*
X430542Y160753D03*
X422363Y154700D03*
X431620Y154620D03*
X443443Y144757D03*
X435453Y167560D03*
X439276Y159645D03*
X434834Y163817D03*
X424832Y200174D03*
X427900Y202800D03*
X425500Y186045D03*
X420800Y193100D03*
X431270Y193425D03*
X426173Y190784D03*
X421171Y196496D03*
X416900Y200100D03*
X416500Y195563D03*
X405800Y196700D03*
X411342Y185024D03*
X400252Y182966D03*
G54D125*
X767500Y19507D03*
X760500Y29000D03*
X767500Y24007D03*
Y28507D03*
X761000Y16007D03*
X764200Y44200D03*
X767500Y33207D03*
X764300Y49200D03*
G54D111*
X24000Y280000D03*
X799500Y10500D03*
G54D121*
X794032Y27032D03*
X804032Y37032D03*
Y47032D03*
X794032Y37032D03*
Y47032D03*
X804032Y57032D03*
X794032D03*
Y67032D03*
G54D124*
X761417Y22798D03*
G54D120*
X804032Y27032D03*
Y67032D03*
G54D109*
X22100Y139500D03*
X111000Y131650D03*
X101500D03*
X59700Y95500D03*
X57500Y187100D03*
X68500Y191900D03*
X61000Y197350D03*
X86800Y225650D03*
X93800Y225800D03*
X82500Y233600D03*
X89200Y237700D03*
X104700Y254000D03*
Y256000D03*
X89000Y257800D03*
X64900Y255500D03*
Y260700D03*
Y250500D03*
Y265800D03*
X60100Y260700D03*
X106500Y191100D03*
X131700Y190500D03*
X126500Y102300D03*
X119350Y119000D03*
X101500Y123350D03*
X111000D03*
X121600Y174000D03*
X125500Y171650D03*
X121500D03*
X101650Y195000D03*
X104500Y195900D03*
X125500Y163350D03*
X183000Y161850D03*
X179000Y163600D03*
X205500Y64600D03*
X200500D03*
X194300Y58500D03*
X208100Y67000D03*
X212900Y70000D03*
X268300Y71000D03*
X269150Y63500D03*
X287100Y76800D03*
X297650Y88600D03*
X293000Y91600D03*
X287100Y81600D03*
X289350Y84600D03*
X307150Y75700D03*
X311500Y64400D03*
X309500D03*
X333000Y54600D03*
X335000D03*
X355000Y62100D03*
X405500Y72400D03*
X407500D03*
X396500Y74100D03*
X382500Y75213D03*
X380400Y76500D03*
X435000Y106663D03*
X437000D03*
X444900Y110563D03*
Y115563D03*
X445300Y128063D03*
X408900Y133063D03*
X410500Y133900D03*
X412500D03*
X440000Y139100D03*
X442000D03*
X408912Y141238D03*
X433900Y145600D03*
X435900D03*
X400866Y165900D03*
X402866D03*
X437900Y187500D03*
Y189500D03*
X438400Y201063D03*
X414900Y209000D03*
X424000Y209963D03*
X325100Y86000D03*
Y84000D03*
X348600Y107500D03*
X343600Y92500D03*
Y87500D03*
X341800Y85500D03*
X340840Y99840D03*
X353400Y99500D03*
X352750Y130700D03*
Y135700D03*
X362600Y117500D03*
X361200Y120500D03*
Y122500D03*
X355000Y66900D03*
X348400Y87500D03*
X350900Y93500D03*
X365500Y127600D03*
X368800Y129100D03*
X358550Y135700D03*
X370900Y107000D03*
X353500Y177900D03*
X360000Y171900D03*
Y183900D03*
X362600Y183700D03*
X365500Y132400D03*
X369742Y139024D03*
X384400Y140500D03*
X365300Y158950D03*
X367400Y183700D03*
X372380Y183610D03*
X367400Y178700D03*
X379600Y138500D03*
X382600Y151500D03*
X392496Y105163D03*
X409000Y122263D03*
X434000Y119263D03*
X432000D03*
X435000Y111463D03*
X423000Y109963D03*
X433900Y150400D03*
X435900D03*
X423500Y159100D03*
X400866Y161100D03*
X435400Y171000D03*
X424000Y205163D03*
X419000Y205100D03*
X433600Y201063D03*
X422142Y184924D03*
X420142D03*
X399500Y200163D03*
Y204963D03*
X403200Y207000D03*
Y209000D03*
X505000Y217850D03*
X524500D03*
X465850Y231000D03*
Y240500D03*
X467600Y241500D03*
Y243500D03*
X782650Y4500D03*
X733700Y45507D03*
Y47507D03*
X515650Y48507D03*
X513900Y49507D03*
X627500Y51407D03*
X632300D03*
X637600D03*
X724350Y52000D03*
X657500Y52007D03*
X665500D03*
X620000Y53657D03*
X624000D03*
X648500D03*
X652500D03*
X643300Y56257D03*
X647300D03*
X516000Y60407D03*
X518000D03*
X724350Y61000D03*
X510500Y63157D03*
X514500D03*
X740000Y68650D03*
X749500D03*
X734000Y70400D03*
X736000D03*
X805900Y120500D03*
X806800Y167700D03*
X806150Y250300D03*
X505000Y226150D03*
X524500D03*
X474150Y240500D03*
X472400Y241500D03*
Y243500D03*
X748500Y127300D03*
X750500D03*
X739300Y127700D03*
X738800Y129900D03*
X738700Y138100D03*
X594000Y229350D03*
X598000D03*
X604000D03*
X608000D03*
X626000D03*
X630000D03*
X738000Y231850D03*
X742000D03*
X614200Y232200D03*
X616800Y232500D03*
X600100Y232600D03*
X602100D03*
X745500Y235100D03*
X539500Y239800D03*
X773250Y242300D03*
X614200Y237000D03*
X616800Y237300D03*
X600100Y237400D03*
X602100D03*
X594000Y237650D03*
X598000D03*
X604000D03*
X630000D03*
X620000Y45357D03*
X624000D03*
X648500D03*
X652500D03*
X625500Y46607D03*
X627500D03*
X632300D03*
X637600D03*
X657500Y47207D03*
X665500D03*
X643300Y47957D03*
X647300D03*
X774350Y4500D03*
Y13700D03*
X740000Y60350D03*
X732650Y61000D03*
X734000Y65600D03*
X781550Y242300D03*
X797850Y250300D03*
Y264500D03*
G54D116*
X64900Y253000D03*
X208100Y75500D03*
Y72500D03*
Y69500D03*
X212900Y72500D03*
Y75500D03*
X444900Y113063D03*
X408900Y135563D03*
X348600Y105000D03*
Y102000D03*
X346100Y96000D03*
X343600Y90000D03*
X350900Y96000D03*
X353400Y102000D03*
Y105000D03*
X352750Y133200D03*
X366100Y101500D03*
Y104500D03*
X348400Y90000D03*
X370900Y101500D03*
Y104500D03*
X362600Y181200D03*
X367400D03*
X404100Y135563D03*
X724350Y56500D03*
X806150Y254800D03*
X773250Y246800D03*
Y251800D03*
X732650Y56500D03*
X781550Y246800D03*
Y251800D03*
X797850Y254800D03*
G54D113*
X66000Y187100D03*
X63000D03*
X60000D03*
Y191900D03*
X63000D03*
X66000D03*
X65500Y197350D03*
X203000Y64600D03*
X343340Y99840D03*
X376000Y135400D03*
X420500Y105163D03*
X417500D03*
X414500D03*
X411500D03*
X408500D03*
X420500Y109963D03*
X417500D03*
X414500D03*
X411500D03*
X408500D03*
X408000Y200163D03*
X405000D03*
X402000D03*
Y204963D03*
X405000D03*
X515000Y217850D03*
X520000D03*
X660000Y52007D03*
X663000D03*
X515000Y226150D03*
X520000D03*
X611700Y232200D03*
X619300Y232500D03*
X622300D03*
X611700Y237000D03*
X619300Y237300D03*
X622300D03*
X660000Y47207D03*
X663000D03*
G54D117*
X64900Y263250D03*
X60100D03*
G54D122*
X782650Y9100D03*
X806150Y259900D03*
X774350Y9100D03*
X797850Y259900D03*
G54D123*
X634950Y51407D03*
Y46607D03*
G54D119*
X465850Y235750D03*
X805900Y123250D03*
X474150Y235750D03*
G54D110*
X106250Y131650D03*
Y123350D03*
X393750Y74100D03*
X509750Y217850D03*
X744750Y68650D03*
X509750Y226150D03*
X744750Y60350D03*
G54D112*
X12000Y279000D03*
%LPD*%
G75*
G54D100*
G01X70851Y-113865D02*
Y-96365D01*
G01X80021D02*
Y-113865D01*
G01Y-105115D02*
X70851D01*
G01X92936Y-113865D02*
X91626Y-113573D01*
X90316Y-112407D01*
X89442Y-110365D01*
X89006Y-108032D01*
X89442Y-105698D01*
X90316Y-103657D01*
X91626Y-102490D01*
X92936Y-102199D01*
X94246Y-102490D01*
X95556Y-103657D01*
X96429Y-105698D01*
X96648Y-108032D01*
X96429Y-110365D01*
X95556Y-112407D01*
X94246Y-113573D01*
X92936Y-113865D01*
G01X106724D02*
Y-102199D01*
G01Y-105115D02*
X107598Y-103657D01*
X108908Y-102490D01*
X110654Y-102199D01*
X112182Y-102490D01*
X113493Y-103657D01*
X114148Y-105698D01*
Y-113865D01*
G01X124661Y-105990D02*
X131648D01*
X130993Y-103948D01*
X129901Y-102782D01*
X128373Y-102199D01*
X126844Y-102490D01*
X125534Y-103365D01*
X124661Y-105407D01*
X124224Y-107157D01*
Y-108907D01*
X124661Y-110657D01*
X125753Y-112407D01*
X127063Y-113573D01*
X128591Y-113865D01*
X130119Y-113282D01*
X131648Y-111532D01*
G01X140851Y-119115D02*
X142161Y-119698D01*
X143908Y-119115D01*
X144999Y-117949D01*
X145873Y-116490D01*
X147182Y-111824D01*
X150021Y-102199D01*
G01X143034D02*
X147182Y-111824D01*
G01X182182Y-104532D02*
X183056Y-103657D01*
X183711Y-102199D01*
X184148Y-100156D01*
X183711Y-98407D01*
X182838Y-97240D01*
X181309Y-96365D01*
X175414D01*
Y-113865D01*
X182619D01*
X184148Y-112699D01*
X185021Y-110948D01*
X185458Y-108907D01*
X185021Y-106865D01*
X183711Y-105115D01*
X182182Y-104532D01*
X175414D01*
G01X201866Y-113865D02*
Y-102199D01*
G01Y-104240D02*
X200993Y-103074D01*
X199682Y-102490D01*
X198154Y-102199D01*
X196626Y-102782D01*
X195316Y-103948D01*
X194442Y-105698D01*
X194006Y-108032D01*
X194442Y-110365D01*
X195316Y-112115D01*
X196626Y-113282D01*
X198154Y-113865D01*
X199682Y-113573D01*
X200993Y-112699D01*
X201866Y-111532D01*
G01X219366Y-96365D02*
Y-113865D01*
G01Y-111241D02*
X218493Y-112699D01*
X217182Y-113573D01*
X215654Y-113865D01*
X213908Y-113282D01*
X212598Y-111824D01*
X211724Y-110074D01*
X211506Y-108032D01*
X211724Y-105990D01*
X212598Y-104240D01*
X213908Y-102782D01*
X215654Y-102199D01*
X217182Y-102490D01*
X218274Y-103074D01*
X219366Y-104240D01*
G01X229879Y-118240D02*
X231408Y-119407D01*
X233154Y-119698D01*
X234682Y-119407D01*
X235993Y-117949D01*
X236866Y-115907D01*
Y-102199D01*
G01Y-104532D02*
X235993Y-103365D01*
X234682Y-102490D01*
X233154Y-102199D01*
X231408Y-102782D01*
X230316Y-103948D01*
X229442Y-105990D01*
X229006Y-108032D01*
X229224Y-109782D01*
X230098Y-111824D01*
X231408Y-113282D01*
X233154Y-113865D01*
X234464Y-113573D01*
X235993Y-112407D01*
X236866Y-111241D01*
G01X247161Y-105990D02*
X254148D01*
X253493Y-103948D01*
X252401Y-102782D01*
X250873Y-102199D01*
X249344Y-102490D01*
X248034Y-103365D01*
X247161Y-105407D01*
X246724Y-107157D01*
Y-108907D01*
X247161Y-110657D01*
X248253Y-112407D01*
X249563Y-113573D01*
X251091Y-113865D01*
X252619Y-113282D01*
X254148Y-111532D01*
G01X264879Y-113865D02*
Y-102199D01*
G01Y-104532D02*
X265971Y-103365D01*
X267063Y-102490D01*
X268591Y-102199D01*
X269682Y-102490D01*
X270993Y-103365D01*
G01X298569Y-113865D02*
Y-96365D01*
X303809D01*
X305556Y-97240D01*
X306866Y-99282D01*
X307303Y-101615D01*
X306866Y-103948D01*
X305774Y-105698D01*
X303809Y-106574D01*
X298569D01*
G01X324366Y-113865D02*
Y-102199D01*
G01Y-104240D02*
X323493Y-103074D01*
X322182Y-102490D01*
X320654Y-102199D01*
X319126Y-102782D01*
X317816Y-103948D01*
X316942Y-105698D01*
X316506Y-108032D01*
X316942Y-110365D01*
X317816Y-112115D01*
X319126Y-113282D01*
X320654Y-113865D01*
X322182Y-113573D01*
X323493Y-112699D01*
X324366Y-111532D01*
G01X334224Y-113865D02*
Y-102199D01*
G01Y-105115D02*
X335098Y-103657D01*
X336408Y-102490D01*
X338154Y-102199D01*
X339682Y-102490D01*
X340993Y-103657D01*
X341648Y-105698D01*
Y-113865D01*
G01X355436Y-96365D02*
Y-113865D01*
G01X352379Y-102199D02*
X358493D01*
G01X369224Y-113865D02*
Y-96365D01*
G01Y-104823D02*
X370316Y-103365D01*
X371408Y-102490D01*
X373154Y-102199D01*
X374464Y-102490D01*
X375993Y-103657D01*
X376648Y-105407D01*
Y-113865D01*
G01X387161Y-105990D02*
X394148D01*
X393493Y-103948D01*
X392401Y-102782D01*
X390873Y-102199D01*
X389344Y-102490D01*
X388034Y-103365D01*
X387161Y-105407D01*
X386724Y-107157D01*
Y-108907D01*
X387161Y-110657D01*
X388253Y-112407D01*
X389563Y-113573D01*
X391091Y-113865D01*
X392619Y-113282D01*
X394148Y-111532D01*
G01X404879Y-113865D02*
Y-102199D01*
G01Y-104532D02*
X405971Y-103365D01*
X407063Y-102490D01*
X408591Y-102199D01*
X409682Y-102490D01*
X410993Y-103365D01*
G01X437259Y-113865D02*
Y-96365D01*
X442936Y-110948D01*
X448613Y-96365D01*
Y-113865D01*
G01X462182Y-104532D02*
X463056Y-103657D01*
X463711Y-102199D01*
X464148Y-100156D01*
X463711Y-98407D01*
X462838Y-97240D01*
X461309Y-96365D01*
X455414D01*
Y-113865D01*
X462619D01*
X464148Y-112699D01*
X465021Y-110948D01*
X465458Y-108907D01*
X465021Y-106865D01*
X463711Y-105115D01*
X462182Y-104532D01*
X455414D01*
G01X227259Y-68865D02*
Y-51365D01*
X232936Y-65948D01*
X238613Y-51365D01*
Y-68865D01*
G01X250436D02*
X249126Y-68573D01*
X247816Y-67407D01*
X246942Y-65365D01*
X246506Y-63032D01*
X246942Y-60698D01*
X247816Y-58657D01*
X249126Y-57490D01*
X250436Y-57199D01*
X251746Y-57490D01*
X253056Y-58657D01*
X253929Y-60698D01*
X254148Y-63032D01*
X253929Y-65365D01*
X253056Y-67407D01*
X251746Y-68573D01*
X250436Y-68865D01*
G01X271866Y-51365D02*
Y-68865D01*
G01Y-66241D02*
X270993Y-67699D01*
X269682Y-68573D01*
X268154Y-68865D01*
X266408Y-68282D01*
X265098Y-66824D01*
X264224Y-65074D01*
X264006Y-63032D01*
X264224Y-60990D01*
X265098Y-59240D01*
X266408Y-57782D01*
X268154Y-57199D01*
X269682Y-57490D01*
X270774Y-58074D01*
X271866Y-59240D01*
G01X282161Y-60990D02*
X289148D01*
X288493Y-58948D01*
X287401Y-57782D01*
X285873Y-57199D01*
X284344Y-57490D01*
X283034Y-58365D01*
X282161Y-60407D01*
X281724Y-62157D01*
Y-63907D01*
X282161Y-65657D01*
X283253Y-67407D01*
X284563Y-68573D01*
X286091Y-68865D01*
X287619Y-68282D01*
X289148Y-66532D01*
G01X302936Y-68865D02*
Y-51365D01*
G01X542319Y-68865D02*
Y-51365D01*
X547559D01*
X549306Y-52240D01*
X550616Y-54282D01*
X551053Y-56615D01*
X550616Y-58948D01*
X549524Y-60698D01*
X547559Y-61574D01*
X542319D01*
G01X568989Y-52824D02*
X567679Y-51948D01*
X566151Y-51365D01*
X564404D01*
X562439Y-52240D01*
X560911Y-53698D01*
X559819Y-55449D01*
X558946Y-58365D01*
X558727Y-60990D01*
X559164Y-63615D01*
X559819Y-65365D01*
X561129Y-67115D01*
X562658Y-68282D01*
X564186Y-68865D01*
X565714D01*
X567243Y-68282D01*
X568553Y-67407D01*
X569645Y-66241D01*
G01X583432Y-59532D02*
X584306Y-58657D01*
X584961Y-57199D01*
X585398Y-55156D01*
X584961Y-53407D01*
X584088Y-52240D01*
X582559Y-51365D01*
X576664D01*
Y-68865D01*
X583869D01*
X585398Y-67699D01*
X586271Y-65948D01*
X586708Y-63907D01*
X586271Y-61865D01*
X584961Y-60115D01*
X583432Y-59532D01*
X576664D01*
G01X592636Y-74698D02*
X605736D01*
G01X611664Y-68865D02*
Y-51365D01*
X621708Y-68865D01*
Y-51365D01*
G01X634186Y-68865D02*
X632439Y-68573D01*
X630911Y-67407D01*
X629601Y-65657D01*
X628727Y-63615D01*
X628291Y-61282D01*
Y-58948D01*
X628727Y-56615D01*
X629601Y-54573D01*
X630911Y-52824D01*
X632439Y-51657D01*
X634186Y-51365D01*
X635932Y-51657D01*
X637461Y-52824D01*
X638771Y-54573D01*
X639645Y-56615D01*
X640081Y-58948D01*
Y-61282D01*
X639645Y-63615D01*
X638771Y-65657D01*
X637461Y-67407D01*
X635932Y-68573D01*
X634186Y-68865D01*
G01X555436Y-113865D02*
Y-96365D01*
X552816Y-99865D01*
G01Y-113865D02*
X558056D01*
G01X568133Y-110365D02*
X569442Y-112407D01*
X571189Y-113573D01*
X573154Y-113865D01*
X574901Y-113573D01*
X576648Y-112115D01*
X577739Y-110365D01*
X577958Y-108615D01*
X577521Y-106574D01*
X575993Y-105115D01*
X574464Y-104532D01*
X572499D01*
G01X574464D02*
X575774Y-103657D01*
X576866Y-102199D01*
X577303Y-100449D01*
X576866Y-98698D01*
X575774Y-97240D01*
X573809Y-96365D01*
X571844Y-96657D01*
X569879Y-97824D01*
G01X590436Y-113865D02*
Y-96365D01*
X587816Y-99865D01*
G01Y-113865D02*
X593056D01*
G01X603133Y-110365D02*
X604442Y-112407D01*
X606189Y-113573D01*
X608154Y-113865D01*
X609901Y-113573D01*
X611648Y-112115D01*
X612739Y-110365D01*
X612958Y-108615D01*
X612521Y-106574D01*
X610993Y-105115D01*
X609464Y-104532D01*
X607499D01*
G01X609464D02*
X610774Y-103657D01*
X611866Y-102199D01*
X612303Y-100449D01*
X611866Y-98698D01*
X610774Y-97240D01*
X608809Y-96365D01*
X606844Y-96657D01*
X604879Y-97824D01*
G01X625436Y-96365D02*
X623689Y-96948D01*
X622379Y-98407D01*
X621506Y-100156D01*
X620851Y-102490D01*
X620633Y-105115D01*
X620851Y-107740D01*
X621506Y-110074D01*
X622379Y-111824D01*
X623689Y-113282D01*
X625436Y-113865D01*
X627182Y-113282D01*
X628493Y-111824D01*
X629366Y-110074D01*
X630021Y-107740D01*
X630239Y-105115D01*
X630021Y-102490D01*
X629366Y-100156D01*
X628493Y-98407D01*
X627182Y-96948D01*
X625436Y-96365D01*
G01X685027Y-51365D02*
X690486Y-68865D01*
X695945Y-51365D01*
G01X712353Y-68865D02*
X703619D01*
Y-51365D01*
X712353D01*
G01X708859Y-59823D02*
X703619D01*
G01X721119Y-68865D02*
Y-51365D01*
X726578D01*
X728324Y-52240D01*
X729416Y-53407D01*
X729853Y-55740D01*
X729416Y-58074D01*
X728106Y-59532D01*
X726578Y-60407D01*
X721119D01*
G01X726578D02*
X729853Y-68865D01*
G01X742986Y-69448D02*
X742549Y-69157D01*
Y-68573D01*
X742986Y-68282D01*
X743423Y-68573D01*
Y-69157D01*
X742986Y-69448D01*
G01X707986Y-113865D02*
Y-96365D01*
X705366Y-99865D01*
G01Y-113865D02*
X710606D01*
G01X727232Y-104532D02*
X728106Y-103657D01*
X728761Y-102199D01*
X729198Y-100156D01*
X728761Y-98407D01*
X727888Y-97240D01*
X726359Y-96365D01*
X720464D01*
Y-113865D01*
X727669D01*
X729198Y-112699D01*
X730071Y-110948D01*
X730508Y-108907D01*
X730071Y-106865D01*
X728761Y-105115D01*
X727232Y-104532D01*
X720464D01*
G01X818569Y-51365D02*
Y-68865D01*
X827303D01*
G01X844366D02*
Y-57199D01*
G01Y-59240D02*
X843493Y-58074D01*
X842182Y-57490D01*
X840654Y-57199D01*
X839126Y-57782D01*
X837816Y-58948D01*
X836942Y-60698D01*
X836506Y-63032D01*
X836942Y-65365D01*
X837816Y-67115D01*
X839126Y-68282D01*
X840654Y-68865D01*
X842182Y-68573D01*
X843493Y-67699D01*
X844366Y-66532D01*
G01X853351Y-74115D02*
X854661Y-74698D01*
X856408Y-74115D01*
X857499Y-72949D01*
X858373Y-71490D01*
X859682Y-66824D01*
X862521Y-57199D01*
G01X855534D02*
X859682Y-66824D01*
G01X872161Y-60990D02*
X879148D01*
X878493Y-58948D01*
X877401Y-57782D01*
X875873Y-57199D01*
X874344Y-57490D01*
X873034Y-58365D01*
X872161Y-60407D01*
X871724Y-62157D01*
Y-63907D01*
X872161Y-65657D01*
X873253Y-67407D01*
X874563Y-68573D01*
X876091Y-68865D01*
X877619Y-68282D01*
X879148Y-66532D01*
G01X889879Y-68865D02*
Y-57199D01*
G01Y-59532D02*
X890971Y-58365D01*
X892063Y-57490D01*
X893591Y-57199D01*
X894682Y-57490D01*
X895993Y-58365D01*
G01X879803Y-96365D02*
Y-113865D01*
X871069D01*
G01X857936D02*
Y-96365D01*
X860556Y-99865D01*
G01Y-113865D02*
X855316D01*
G01X844584Y-99282D02*
X843274Y-97532D01*
X841746Y-96657D01*
X839999Y-96365D01*
X837816Y-96948D01*
X836288Y-98407D01*
X835851Y-100156D01*
X836069Y-101907D01*
X836943Y-103365D01*
X841309Y-106282D01*
X843274Y-108323D01*
X844584Y-111241D01*
X845021Y-113865D01*
X835851D01*
G01X943619Y-110365D02*
X944711Y-112115D01*
X946021Y-113282D01*
X947549Y-113865D01*
X949296Y-113282D01*
X950606Y-112115D01*
X951916Y-110365D01*
X952353Y-108032D01*
Y-96365D01*
G01X965486Y-113865D02*
X963739Y-113573D01*
X962211Y-112407D01*
X960901Y-110657D01*
X960027Y-108615D01*
X959591Y-106282D01*
Y-103948D01*
X960027Y-101615D01*
X960901Y-99573D01*
X962211Y-97824D01*
X963739Y-96657D01*
X965486Y-96365D01*
X967232Y-96657D01*
X968761Y-97824D01*
X970071Y-99573D01*
X970945Y-101615D01*
X971381Y-103948D01*
Y-106282D01*
X970945Y-108615D01*
X970071Y-110657D01*
X968761Y-112407D01*
X967232Y-113573D01*
X965486Y-113865D01*
G01X978401Y-111532D02*
X980148Y-112990D01*
X982113Y-113865D01*
X983859D01*
X985606Y-112990D01*
X986916Y-111532D01*
X987571Y-109490D01*
X987134Y-107449D01*
X986043Y-105698D01*
X984078Y-104532D01*
X981458Y-103948D01*
X979929Y-102782D01*
X979274Y-100740D01*
X979711Y-98698D01*
X980803Y-97240D01*
X982331Y-96365D01*
X983859D01*
X985388Y-96948D01*
X986698Y-98407D01*
G01X1004853Y-113865D02*
X996119D01*
Y-96365D01*
X1004853D01*
G01X1001359Y-104823D02*
X996119D01*
G01X1013619Y-113865D02*
Y-96365D01*
X1018859D01*
X1020606Y-97240D01*
X1021916Y-99282D01*
X1022353Y-101615D01*
X1021916Y-103948D01*
X1020824Y-105698D01*
X1018859Y-106574D01*
X1013619D01*
G01X1030901Y-113865D02*
Y-96365D01*
G01X1040071D02*
Y-113865D01*
G01Y-105115D02*
X1030901D01*
G01X1066119Y-96365D02*
Y-113865D01*
X1074853D01*
G01X1082527D02*
X1087986Y-96365D01*
X1093445Y-113865D01*
G01X1091479Y-107740D02*
X1084492D01*
G01X1100683Y-96365D02*
Y-108907D01*
X1101556Y-111532D01*
X1103303Y-113282D01*
X1105486Y-113865D01*
X1107669Y-113282D01*
X1109416Y-111532D01*
X1110289Y-108907D01*
Y-96365D01*
G01X960683Y-68865D02*
Y-51365D01*
X965049D01*
X966796Y-52240D01*
X968106Y-53407D01*
X969198Y-55156D01*
X970071Y-57199D01*
X970289Y-60115D01*
X970071Y-63032D01*
X969198Y-65074D01*
X968106Y-66824D01*
X966796Y-67990D01*
X965049Y-68865D01*
X960683D01*
G01X979711Y-60990D02*
X986698D01*
X986043Y-58948D01*
X984951Y-57782D01*
X983423Y-57199D01*
X981894Y-57490D01*
X980584Y-58365D01*
X979711Y-60407D01*
X979274Y-62157D01*
Y-63907D01*
X979711Y-65657D01*
X980803Y-67407D01*
X982113Y-68573D01*
X983641Y-68865D01*
X985169Y-68282D01*
X986698Y-66532D01*
G01X997211Y-66824D02*
X998303Y-67990D01*
X999831Y-68865D01*
X1001141D01*
X1002451Y-68282D01*
X1003324Y-67407D01*
X1003761Y-66241D01*
X1003543Y-64490D01*
X1002669Y-63615D01*
X998739Y-61865D01*
X997866Y-59823D01*
X998303Y-58365D01*
X999176Y-57490D01*
X1000486Y-57199D01*
X1001796Y-57490D01*
X1003106Y-58365D01*
G01X1017986Y-57199D02*
Y-68865D01*
G01Y-52532D02*
X1017549Y-52240D01*
Y-51657D01*
X1017986Y-51365D01*
X1018423Y-51657D01*
Y-52240D01*
X1017986Y-52532D01*
G01X1032429Y-73240D02*
X1033958Y-74407D01*
X1035704Y-74698D01*
X1037232Y-74407D01*
X1038543Y-72949D01*
X1039416Y-70907D01*
Y-57199D01*
G01Y-59532D02*
X1038543Y-58365D01*
X1037232Y-57490D01*
X1035704Y-57199D01*
X1033958Y-57782D01*
X1032866Y-58948D01*
X1031992Y-60990D01*
X1031556Y-63032D01*
X1031774Y-64782D01*
X1032648Y-66824D01*
X1033958Y-68282D01*
X1035704Y-68865D01*
X1037014Y-68573D01*
X1038543Y-67407D01*
X1039416Y-66241D01*
G01X1049274Y-68865D02*
Y-57199D01*
G01Y-60115D02*
X1050148Y-58657D01*
X1051458Y-57490D01*
X1053204Y-57199D01*
X1054732Y-57490D01*
X1056043Y-58657D01*
X1056698Y-60698D01*
Y-68865D01*
G01X1067211Y-60990D02*
X1074198D01*
X1073543Y-58948D01*
X1072451Y-57782D01*
X1070923Y-57199D01*
X1069394Y-57490D01*
X1068084Y-58365D01*
X1067211Y-60407D01*
X1066774Y-62157D01*
Y-63907D01*
X1067211Y-65657D01*
X1068303Y-67407D01*
X1069613Y-68573D01*
X1071141Y-68865D01*
X1072669Y-68282D01*
X1074198Y-66532D01*
G01X1084929Y-68865D02*
Y-57199D01*
G01Y-59532D02*
X1086021Y-58365D01*
X1087113Y-57490D01*
X1088641Y-57199D01*
X1089732Y-57490D01*
X1091043Y-58365D01*
G01X1131686Y-113865D02*
Y-96365D01*
X1129066Y-99865D01*
G01Y-113865D02*
X1134306D01*
G01X1149186D02*
Y-96365D01*
X1146566Y-99865D01*
G01Y-113865D02*
X1151806D01*
G01X1162756Y-114448D02*
X1170616Y-96365D01*
G01X1184186Y-113865D02*
Y-96365D01*
X1181566Y-99865D01*
G01Y-113865D02*
X1186806D01*
G01X1196883Y-110365D02*
X1198192Y-112407D01*
X1199939Y-113573D01*
X1201904Y-113865D01*
X1203651Y-113573D01*
X1205398Y-112115D01*
X1206489Y-110365D01*
X1206708Y-108615D01*
X1206271Y-106574D01*
X1204743Y-105115D01*
X1203214Y-104532D01*
X1201249D01*
G01X1203214D02*
X1204524Y-103657D01*
X1205616Y-102199D01*
X1206053Y-100449D01*
X1205616Y-98698D01*
X1204524Y-97240D01*
X1202559Y-96365D01*
X1200594Y-96657D01*
X1198629Y-97824D01*
G01X1215256Y-114448D02*
X1223116Y-96365D01*
G01X1232538Y-99282D02*
X1233848Y-97532D01*
X1235376Y-96657D01*
X1237123Y-96365D01*
X1239306Y-96948D01*
X1240834Y-98407D01*
X1241271Y-100156D01*
X1241053Y-101907D01*
X1240179Y-103365D01*
X1235813Y-106282D01*
X1233848Y-108323D01*
X1232538Y-111241D01*
X1232101Y-113865D01*
X1241271D01*
G01X1254186Y-96365D02*
X1252439Y-96948D01*
X1251129Y-98407D01*
X1250256Y-100156D01*
X1249601Y-102490D01*
X1249383Y-105115D01*
X1249601Y-107740D01*
X1250256Y-110074D01*
X1251129Y-111824D01*
X1252439Y-113282D01*
X1254186Y-113865D01*
X1255932Y-113282D01*
X1257243Y-111824D01*
X1258116Y-110074D01*
X1258771Y-107740D01*
X1258989Y-105115D01*
X1258771Y-102490D01*
X1258116Y-100156D01*
X1257243Y-98407D01*
X1255932Y-96948D01*
X1254186Y-96365D01*
G01X1271686Y-113865D02*
Y-96365D01*
X1269066Y-99865D01*
G01Y-113865D02*
X1274306D01*
G01X1291806D02*
Y-96365D01*
X1283727Y-108907D01*
X1294645D01*
G01X1179383Y-68865D02*
Y-51365D01*
X1183749D01*
X1185496Y-52240D01*
X1186806Y-53407D01*
X1187898Y-55156D01*
X1188771Y-57199D01*
X1188989Y-60115D01*
X1188771Y-63032D01*
X1187898Y-65074D01*
X1186806Y-66824D01*
X1185496Y-67990D01*
X1183749Y-68865D01*
X1179383D01*
G01X1205616D02*
Y-57199D01*
G01Y-59240D02*
X1204743Y-58074D01*
X1203432Y-57490D01*
X1201904Y-57199D01*
X1200376Y-57782D01*
X1199066Y-58948D01*
X1198192Y-60698D01*
X1197756Y-63032D01*
X1198192Y-65365D01*
X1199066Y-67115D01*
X1200376Y-68282D01*
X1201904Y-68865D01*
X1203432Y-68573D01*
X1204743Y-67699D01*
X1205616Y-66532D01*
G01X1219186Y-51365D02*
Y-68865D01*
G01X1216129Y-57199D02*
X1222243D01*
G01X1233411Y-60990D02*
X1240398D01*
X1239743Y-58948D01*
X1238651Y-57782D01*
X1237123Y-57199D01*
X1235594Y-57490D01*
X1234284Y-58365D01*
X1233411Y-60407D01*
X1232974Y-62157D01*
Y-63907D01*
X1233411Y-65657D01*
X1234503Y-67407D01*
X1235813Y-68573D01*
X1237341Y-68865D01*
X1238869Y-68282D01*
X1240398Y-66532D01*
G54D101*
G01X21949Y267519D02*
X18381D01*
X16900Y269000D01*
G01X29400Y180000D02*
Y175600D01*
X27400Y173600D01*
G01D02*
X20331D01*
X19000Y174931D01*
G01X24173Y178154D02*
X26500Y180481D01*
Y181800D01*
G01X19000Y180069D02*
X19631D01*
X21546Y178154D01*
X24173D01*
G01X51674Y258661D02*
X48000D01*
X46550Y260111D01*
Y270550D01*
X49500Y273500D01*
X60300D01*
X61500Y272300D01*
G01D02*
X64500D01*
X64700Y272500D01*
G01X92900Y204008D02*
Y207400D01*
X93500Y208000D01*
G01X86000Y206000D02*
X87500D01*
X89500Y204000D01*
G01X246600Y73700D02*
Y77600D01*
X248921Y79921D01*
X251758D01*
G01X261300Y93600D02*
X264969D01*
X265500Y93069D01*
G01X272000Y176709D02*
X270791D01*
X266850Y180650D01*
Y189150D01*
X267990Y190290D01*
Y192617D01*
X265351Y195256D01*
Y211607D01*
X261750Y215208D01*
Y228450D01*
X262300Y229000D01*
Y232500D01*
G01X319400Y278800D02*
X319500Y278700D01*
Y277200D01*
X316050Y273750D01*
X305608D01*
X304145Y272287D01*
X293180D01*
X292692Y272775D01*
X274705D01*
X261750Y259820D01*
Y235100D01*
X262300Y234550D01*
Y232500D01*
G01X275740Y168291D02*
X279609D01*
X279900Y168000D01*
G01X278700Y241200D02*
Y244400D01*
G01X269500Y244200D02*
X271900D01*
X272500Y244800D01*
G01X277800Y249400D02*
X275300Y251900D01*
Y254100D01*
G01X278700Y244400D02*
Y248500D01*
X277800Y249400D01*
G01X278700Y244400D02*
X275900D01*
X275500Y244800D01*
G01X274200Y247500D02*
Y252583D01*
X273450Y253333D01*
Y254867D01*
X274533Y255950D01*
X276990D01*
X278700Y254240D01*
G01X269500Y244200D02*
X266000D01*
G01X274200Y247500D02*
X273000Y246300D01*
Y245300D01*
X272500Y244800D01*
G01X343560Y150400D02*
X343320D01*
X337370Y144450D01*
X333128D01*
X333124Y144454D01*
X322424D01*
X321645Y143675D01*
X317166D01*
X315891Y142400D01*
X314962D01*
X312512Y139950D01*
X306212D01*
X304223Y137961D01*
X285661D01*
X283200Y135500D01*
G01X293200Y131000D02*
X296742D01*
X297192Y131450D01*
X297254D01*
X298304Y132500D01*
X301367D01*
X306467Y137600D01*
X309000D01*
G01X287100Y168000D02*
X289150Y165950D01*
X291650D01*
X293700Y168000D01*
G01X279900D02*
X283700D01*
G01X293700D02*
X297600D01*
X298500Y167100D01*
G01X322700Y277700D02*
X309150Y264150D01*
X306850D01*
X304064Y266936D01*
X295340D01*
X289250Y260846D01*
Y242666D01*
X282950Y236366D01*
Y223450D01*
X285525Y220875D01*
X294260D01*
X305300Y209835D01*
Y203125D01*
G01X317352Y116648D02*
X313188Y112484D01*
Y110266D01*
X312022Y109100D01*
X308795D01*
X302544Y102849D01*
Y99356D01*
X303400Y98500D01*
G01X313300Y103500D02*
X311100D01*
X308700Y101100D01*
G01D02*
Y99300D01*
X305000Y95600D01*
X303776D01*
X303376Y95200D01*
G01X322500Y114500D02*
Y111290D01*
X321320Y110110D01*
X318610D01*
X315500Y107000D01*
X311200D01*
X308700Y104500D01*
G01X309000Y137600D02*
X309560D01*
X309585Y137575D01*
X319273D01*
X321402Y139704D01*
X324677D01*
X324973Y140000D01*
X326040D01*
X327963Y141923D01*
Y142008D01*
G01X335964Y158512D02*
X335462D01*
X333146Y156196D01*
X328048D01*
X324944Y159300D01*
X321086D01*
X318765Y161621D01*
X315279D01*
X310700Y166200D01*
X299400D01*
X298500Y167100D01*
G01Y241800D02*
X302000Y245300D01*
Y245400D01*
G01X299600Y238200D02*
X298500Y239300D01*
Y241800D01*
G01X309400Y253600D02*
Y249800D01*
X309300Y249700D01*
G01X305000Y245400D02*
X309300Y249700D01*
G01X306000Y253600D02*
Y249400D01*
X302000Y245400D01*
G01X317352Y116648D02*
X324604Y123900D01*
X327400D01*
X328928Y125428D01*
X329031D01*
G01X343000Y126200D02*
X342587D01*
X338887Y122500D01*
X333479D01*
X332034Y121055D01*
Y119218D01*
X330389Y117573D01*
X325573D01*
X322500Y114500D01*
G01X325763Y141958D02*
X325750Y141945D01*
X325645D01*
X324304Y140604D01*
X321029D01*
X319874Y139449D01*
X317151D01*
X317000Y139600D01*
G01X338000Y171500D02*
X341522D01*
X343556Y169466D01*
X344165D01*
G01X343560Y150400D02*
X343780Y150620D01*
X351350D01*
X351780Y151050D01*
X357250D01*
X358100Y151900D01*
G01X373500Y109063D02*
X372518D01*
X368497Y113084D01*
Y121352D01*
X367321Y122528D01*
G01X373500Y114063D02*
X371000Y116563D01*
X370000D01*
G01X375100Y118700D02*
Y120549D01*
X370121Y125528D01*
G01X371100Y168700D02*
Y165400D01*
X370700Y165000D01*
G01X374100Y159150D02*
X373892D01*
X371700Y156958D01*
Y156440D01*
G01X358500Y155700D02*
Y152300D01*
X358100Y151900D01*
G01X375000Y123563D02*
X374886D01*
X372821Y125628D01*
G01X386938Y146572D02*
X389844D01*
X389848Y146568D01*
G01X384400Y156400D02*
Y158100D01*
X383500Y159000D01*
G01X379700Y157450D02*
Y158199D01*
X383700Y162199D01*
G01X376300Y160900D02*
X379375D01*
X380500Y162025D01*
G01X375300Y166545D02*
X376195D01*
X377500Y165240D01*
G01X374300Y155800D02*
Y155700D01*
X377700Y152300D01*
G01X389624Y140246D02*
X391221Y141843D01*
Y144453D01*
X393204Y146436D01*
G01X407492Y164734D02*
X407100Y165126D01*
Y167429D01*
G01X412000Y168200D02*
X410337D01*
X409300Y167163D01*
G01X439441Y260531D02*
Y255059D01*
X443350Y251150D01*
X451500D01*
G01X458700Y252000D02*
Y255600D01*
G01D02*
Y255800D01*
X456760Y257740D01*
Y259791D01*
G01X455300Y252000D02*
X454450Y251150D01*
X451500D01*
G01X452500Y275200D02*
Y273265D01*
X449500Y270265D01*
Y269800D01*
G01X460500Y268209D02*
X456791D01*
X455500Y269500D01*
G01D02*
X455200Y269800D01*
X449500D01*
G01X576500Y178700D02*
Y181086D01*
X578714Y183300D01*
X578795D01*
G01D02*
X580558Y185063D01*
X589462D01*
X589500Y185025D01*
X602019D01*
X610544Y176500D01*
X625300D01*
X627500Y174300D01*
G01X661000Y173800D02*
X660800Y174000D01*
X627800D01*
X627500Y174300D01*
G01X626300Y198250D02*
X627074Y199024D01*
X627150D01*
X628276Y200150D01*
X658750D01*
X658800Y200100D01*
G01D02*
X661600Y197300D01*
G01X762000Y281000D02*
X759495D01*
X750912Y272417D01*
Y260692D01*
X753654Y257950D01*
X785000D01*
X787215Y260165D01*
Y261024D01*
G01X782077Y270866D02*
X778634D01*
X774500Y275000D01*
X771400D01*
X765400Y281000D01*
G01X778200Y266000D02*
X778051D01*
X771791Y272260D01*
G01X789831Y124000D02*
X787831D01*
X786231Y125600D01*
X782300D01*
X779200Y122500D01*
G01X785297Y128876D02*
X782076D01*
X779200Y126000D01*
G01X785297Y128876D02*
X789407D01*
X789831Y129300D01*
G01X785324Y133676D02*
X781148Y129500D01*
X779200D01*
G01X789831Y134600D02*
X786248D01*
X785324Y133676D01*
G01X785100Y139900D02*
X784451Y139251D01*
Y135986D01*
X781465Y133000D01*
X779200D01*
G01X789831Y139900D02*
X785100D01*
G01X789931Y162700D02*
X787631D01*
X785831Y164500D01*
G01X781200Y168000D02*
X782331D01*
X785831Y164500D01*
G01X789931Y152300D02*
X787367D01*
X785453Y154214D01*
G01X781200Y162000D02*
X782500Y160700D01*
Y157167D01*
X785453Y154214D01*
G01X785831Y159000D02*
Y160669D01*
X781500Y165000D01*
X781200D01*
G01X789931Y157500D02*
X787331D01*
X785831Y159000D01*
G01X781200Y171000D02*
X782056Y171856D01*
X786000D01*
G01D02*
X786644D01*
X789931Y168569D01*
Y167900D01*
G01X787215Y270866D02*
Y267201D01*
X783888Y263874D01*
X779074D01*
X778200Y263000D01*
G01X787215Y270866D02*
X791366D01*
G01X778200Y260000D02*
X781053D01*
X782077Y261024D01*
G01X788955Y265773D02*
X787202D01*
X782453Y261024D01*
X782077D01*
G01X778200Y266000D02*
X782832D01*
X783078Y266246D01*
G01X786500Y276000D02*
X780209D01*
G01X787646Y280709D02*
Y277146D01*
X786500Y276000D01*
G01X781646Y280709D02*
X784937Y284000D01*
X788800D01*
X792000Y280800D01*
G01Y119465D02*
X791500Y119965D01*
Y122331D01*
X789831Y124000D01*
G01X811000Y130000D02*
X800742D01*
X797050Y126308D01*
Y126081D01*
X794969Y124000D01*
G01X811000Y134000D02*
X809000Y132000D01*
X797669D01*
X794969Y129300D01*
G01Y134600D02*
X807600D01*
X811000Y138000D01*
G01X794969Y139900D02*
X809500D01*
X811200Y141600D01*
G01X795069Y152300D02*
X802600D01*
X805700Y149200D01*
X809000D01*
G01X795069Y162700D02*
X804600D01*
X806800Y160500D01*
X809600D01*
G01X795069Y157500D02*
X796100D01*
X799050Y160450D01*
X804350D01*
X807900Y156900D01*
X809500D01*
G01X795069Y167900D02*
X797000D01*
X800650Y164250D01*
X809650D01*
X809700Y164300D01*
G01X792000Y280800D02*
X795400D01*
X796700Y279500D01*
G54D102*
G01X388800Y81000D02*
X386500D01*
X385300Y82200D01*
Y94300D01*
G01X390205Y133858D02*
X390058D01*
X387600Y131400D01*
Y126841D01*
X387214Y126455D01*
Y120298D01*
X387321Y120191D01*
Y113803D01*
X386963Y113445D01*
Y111477D01*
X384850Y109364D01*
Y94750D01*
X385300Y94300D01*
G01X390100Y127600D02*
X388314Y125814D01*
Y120754D01*
X388421Y120647D01*
Y113347D01*
X388100Y113026D01*
Y109536D01*
X388161Y109475D01*
Y104161D01*
X387100Y103100D01*
G01X393500Y88000D02*
X392500Y89000D01*
Y97395D01*
X387100Y102795D01*
Y103100D01*
G01X380443Y130102D02*
X379882D01*
X377880Y128100D01*
X376900D01*
G01D02*
X373300D01*
G01X389700Y112363D02*
X392700Y109363D01*
X393496D01*
G01X403500Y105863D02*
X400237D01*
X400000Y106100D01*
G01D02*
X396837Y109263D01*
X396496D01*
G01D02*
X396396Y109363D01*
X393496D01*
G01X398300Y174100D02*
X402089D01*
X402600Y174611D01*
G01D02*
Y177000D01*
X401800Y177800D01*
G01X389480Y197040D02*
X387884Y195444D01*
Y189779D01*
X389300Y188363D01*
Y187700D01*
G01X388500Y200800D02*
X389710Y199590D01*
Y197270D01*
X389480Y197040D01*
G01X389484Y190442D02*
X391100Y192058D01*
Y195033D01*
X393170Y197103D01*
G01D02*
Y202130D01*
X392300Y203000D01*
G01D02*
Y206400D01*
X391200Y207500D01*
G01D02*
X391300Y207600D01*
Y210500D01*
G01X415950Y175623D02*
X415890Y175563D01*
X412573D01*
X412560Y175550D01*
X412350D01*
G01D02*
X410620Y173820D01*
Y173300D01*
G01X512500Y56407D02*
X509900D01*
X502715Y49222D01*
Y35913D01*
X504000Y34628D01*
Y12507D01*
G01X508858Y6656D02*
Y12949D01*
X508500Y13307D01*
Y14407D01*
X508700Y14607D01*
G01X505315Y38940D02*
Y42922D01*
X508900Y46507D01*
G01X510039Y38940D02*
Y34646D01*
X509000Y33607D01*
Y31523D01*
X507839Y30362D01*
G01X705145Y93500D02*
Y79182D01*
X687470Y61507D01*
X581000D01*
X572850Y53357D01*
X510650D01*
X509700Y52407D01*
Y50507D01*
G01D02*
Y47307D01*
X508900Y46507D01*
G01X523031Y6656D02*
Y10376D01*
X521919Y11488D01*
Y11531D01*
X521410Y12040D01*
Y14097D01*
X520700Y14807D01*
G01X515945Y6656D02*
Y9652D01*
X516526Y10233D01*
Y21865D01*
X515484Y22907D01*
G01X518307Y6656D02*
Y9700D01*
X517726Y10281D01*
Y21864D01*
X518769Y22907D01*
G01X511220Y6656D02*
Y11927D01*
X511800Y12507D01*
G01X525393Y6656D02*
Y10514D01*
X523600Y12307D01*
X523506D01*
X523453Y12360D01*
G01X521850Y38940D02*
Y36147D01*
X524600Y33397D01*
Y32046D01*
X525753Y30893D01*
G01X519488Y38940D02*
Y36077D01*
X522733Y32832D01*
G01X512401Y38940D02*
Y34808D01*
X511200Y33607D01*
Y30684D01*
X511589Y30295D01*
G01X512500Y56407D02*
X516800D01*
X517000Y56207D01*
G01X707209Y97500D02*
X706000D01*
X702545Y94045D01*
Y80259D01*
X686393Y64107D01*
X579550D01*
X571650Y56207D01*
X517000D01*
G01X512402Y246456D02*
Y255194D01*
X511640Y255956D01*
G01X524213Y246456D02*
Y250113D01*
X525200Y251100D01*
Y253185D01*
X526715Y254700D01*
G01X521851Y246456D02*
Y249851D01*
X523500Y251500D01*
Y254500D01*
X522908Y255092D01*
Y255117D01*
G01X514764Y246456D02*
Y255462D01*
X514137Y256089D01*
G01X511221Y278740D02*
Y273516D01*
X511736Y273001D01*
G01X527756Y278740D02*
Y275166D01*
X525845Y273255D01*
Y272863D01*
G01X520670Y278740D02*
Y275722D01*
X520089Y275141D01*
Y263531D01*
X521131Y262489D01*
G01X518307Y278740D02*
Y275819D01*
X518889Y275237D01*
Y263532D01*
X517846Y262489D01*
G01X525394Y278740D02*
Y275394D01*
X523850Y273850D01*
Y271757D01*
X522992Y270900D01*
Y270700D01*
G01X513583Y278740D02*
Y272667D01*
X514900Y271350D01*
G01X530118Y6656D02*
Y10389D01*
X528600Y11907D01*
Y12474D01*
X528525Y12549D01*
G01X532480Y6656D02*
Y10067D01*
X530600Y11947D01*
Y15307D01*
X530700Y15407D01*
G01X533661Y38940D02*
Y35946D01*
X534242Y35365D01*
Y23949D01*
X533200Y22907D01*
G01X536023Y38940D02*
Y35930D01*
X535442Y35349D01*
Y23950D01*
X536485Y22907D01*
G01X526575Y38940D02*
Y36132D01*
X529000Y33707D01*
Y32695D01*
X529120Y32575D01*
G01X540748Y38940D02*
Y35855D01*
X540100Y35207D01*
Y32785D01*
X542003Y30882D01*
X542407D01*
G01X528937Y38940D02*
Y35470D01*
X530842Y33565D01*
Y32304D01*
X532339Y30807D01*
X532350D01*
G01X543110Y246456D02*
Y250090D01*
X542600Y250600D01*
Y253205D01*
X541005Y254800D01*
G01X531299Y246456D02*
Y249079D01*
X532412Y250192D01*
Y251594D01*
X531775Y252231D01*
G01X538386Y246456D02*
Y249776D01*
X537998Y250164D01*
Y261640D01*
X538847Y262489D01*
G01X536024Y246456D02*
Y249576D01*
X536798Y250350D01*
Y261253D01*
X535562Y262489D01*
G01X528937Y246456D02*
Y250637D01*
X529900Y251600D01*
Y254885D01*
X530015Y255000D01*
G01X541929Y278740D02*
Y273497D01*
X542437Y272989D01*
Y271837D01*
X541500Y270900D01*
G01X532481Y278740D02*
Y274833D01*
X530900Y273252D01*
Y273000D01*
G01X534843Y278740D02*
Y275440D01*
X533180Y273777D01*
Y271620D01*
X534100Y270700D01*
G01X544291Y6656D02*
Y10376D01*
X543050Y11617D01*
Y14157D01*
X542100Y15107D01*
G01X553740Y6656D02*
Y9757D01*
X552020Y11477D01*
Y14027D01*
X552800Y14807D01*
G01X551378Y6656D02*
Y10129D01*
X550000Y11507D01*
Y12507D01*
G01X546653Y6656D02*
Y10254D01*
X544860Y12047D01*
Y12407D01*
G01X557283Y38940D02*
Y35990D01*
X556702Y35409D01*
Y23950D01*
X557745Y22907D01*
G01X554921Y38940D02*
Y35886D01*
X555502Y35305D01*
Y23949D01*
X554460Y22907D01*
G01X543110Y38940D02*
Y35470D01*
X545100Y33480D01*
Y31875D01*
X545928Y31047D01*
G01X547834Y38940D02*
Y35132D01*
X549400Y33566D01*
Y31707D01*
X549500Y31607D01*
G01X550197Y38940D02*
Y35210D01*
X551100Y34307D01*
Y32691D01*
X553079Y30712D01*
G01X550197Y246456D02*
Y249706D01*
X549300Y250603D01*
Y254600D01*
X550200Y255500D01*
G01X545473Y246456D02*
Y249527D01*
X543800Y251200D01*
Y254100D01*
X544800Y255100D01*
G01X552559Y246456D02*
Y250213D01*
X551000Y251772D01*
Y252056D01*
G01X549016Y278740D02*
Y271216D01*
X548800Y271000D01*
G01X556103Y278740D02*
Y275623D01*
X556684Y275042D01*
Y263532D01*
X555641Y262489D01*
G01X551378Y278740D02*
Y273548D01*
X551937Y272989D01*
Y272789D01*
G01X544292Y278740D02*
Y273128D01*
G01X560827Y6656D02*
Y12134D01*
X561200Y12507D01*
G01X567913Y6656D02*
Y11765D01*
X568555Y12407D01*
G01X563189Y6656D02*
Y13096D01*
X564400Y14307D01*
G01X570275Y6656D02*
Y12882D01*
X571600Y14207D01*
G01X564370Y38940D02*
Y35307D01*
X563570Y34507D01*
Y32336D01*
X565091Y30815D01*
G01X569094Y38940D02*
Y34501D01*
X568500Y33907D01*
Y31277D01*
X569800Y29977D01*
Y29807D01*
G01X562008Y38940D02*
Y34267D01*
X562440Y33835D01*
Y31407D01*
X561935Y30902D01*
X561456D01*
G01X571456Y38940D02*
Y33808D01*
X570852Y33204D01*
G01X562008Y246456D02*
Y249308D01*
X564200Y251500D01*
Y254200D01*
X564666Y254666D01*
X564947D01*
X565054Y254773D01*
G01X569095Y246456D02*
Y250659D01*
X570100Y251664D01*
Y252918D01*
X571867Y254685D01*
G01X559646Y246456D02*
Y249189D01*
X562255Y251798D01*
Y253945D01*
X561419Y254781D01*
Y254850D01*
G01X566733Y246456D02*
Y250033D01*
X568312Y251612D01*
Y253212D01*
X568327Y253227D01*
Y253348D01*
G01X565551Y278740D02*
Y275351D01*
X563835Y273635D01*
Y271565D01*
X564100Y271300D01*
Y271100D01*
G01X558465Y278740D02*
Y275670D01*
X557884Y275089D01*
Y263531D01*
X558926Y262489D01*
G01X570276Y278740D02*
Y275676D01*
X567800Y273200D01*
Y270500D01*
G01X563189Y278740D02*
Y275041D01*
X561337Y273189D01*
Y271037D01*
X560600Y270300D01*
G01X572638Y278740D02*
Y275638D01*
X570400Y273400D01*
Y273300D01*
X570200Y273100D01*
G01X582086Y6656D02*
Y10376D01*
X580790Y11672D01*
Y13907D01*
X579890Y14807D01*
X579800D01*
G01X575000Y6656D02*
Y9707D01*
X575581Y10288D01*
Y21865D01*
X574539Y22907D01*
G01X584449Y6656D02*
Y9628D01*
X582655Y11422D01*
Y12407D01*
G01X577362Y6656D02*
Y9545D01*
X576781Y10126D01*
Y21864D01*
X577824Y22907D01*
G01X580905Y38940D02*
Y36052D01*
X583800Y33157D01*
Y32246D01*
X585179Y30867D01*
G01X585630Y38940D02*
Y36257D01*
X588880Y33007D01*
X589300D01*
G01X578543Y38940D02*
Y36166D01*
X578545Y36164D01*
X578548D01*
X581450Y33262D01*
Y30707D01*
G01X573819Y246456D02*
Y249471D01*
X574400Y250052D01*
Y261446D01*
X573357Y262489D01*
G01X587992Y246456D02*
Y251208D01*
X587642Y251558D01*
Y252206D01*
G01X580906Y246456D02*
Y251095D01*
X580500Y251501D01*
Y253555D01*
X579205Y254850D01*
G01X583268Y246456D02*
Y251132D01*
X582200Y252200D01*
Y252206D01*
G01X576181Y246456D02*
Y249345D01*
X575600Y249926D01*
Y261447D01*
X576642Y262489D01*
G01X579725Y278740D02*
Y273475D01*
X580200Y273000D01*
G01X582087Y278740D02*
Y273539D01*
X582600Y273026D01*
Y270300D01*
G01X600984Y6656D02*
X594851D01*
X594800Y6707D01*
X594600D01*
G01X589173Y6656D02*
Y11634D01*
X588390Y12417D01*
X587940D01*
G01X602165Y38940D02*
Y34652D01*
X602746Y34071D01*
Y23949D01*
X601704Y22907D01*
G01X587992Y38940D02*
X591667D01*
X594400Y36207D01*
G01X590355Y246456D02*
Y251219D01*
X591342Y252206D01*
G01X591536Y273000D02*
Y278740D01*
G01X589173D02*
Y274527D01*
X589786Y273914D01*
Y271814D01*
X591500Y270100D01*
G01X610433Y6656D02*
Y11788D01*
X610952Y12307D01*
G01X608071Y6656D02*
Y10711D01*
X608567Y11207D01*
Y13240D01*
X607300Y14507D01*
G01X604527Y38940D02*
Y34652D01*
X603946Y34071D01*
Y23950D01*
X604989Y22907D01*
G01X616338Y38940D02*
Y34513D01*
X616894Y33957D01*
Y32423D01*
X615261Y30790D01*
X615203D01*
X615103Y30690D01*
G01X611614Y38940D02*
Y34003D01*
X610944Y33333D01*
G01X609252Y38940D02*
Y34046D01*
X609244Y34038D01*
Y31851D01*
X607800Y30407D01*
G01X618701Y38940D02*
Y33706D01*
X618900Y33507D01*
Y33290D01*
G01X637599Y246456D02*
Y250883D01*
X637043Y251439D01*
Y252973D01*
X638676Y254606D01*
X638697D01*
X638900Y254809D01*
G01X635236Y246456D02*
Y251913D01*
X635043Y252106D01*
G01X642323Y246456D02*
Y251707D01*
X642802Y252186D01*
G01X644685Y246456D02*
Y252895D01*
X645920Y254130D01*
G01X643504Y278740D02*
Y273656D01*
X642937Y273089D01*
G01X645866Y278740D02*
Y272024D01*
X646360Y271530D01*
G01X649410Y246456D02*
Y250744D01*
X649991Y251325D01*
Y261446D01*
X648948Y262489D01*
G01X662401Y6656D02*
Y12337D01*
X662359Y12379D01*
G01X664764Y6656D02*
Y10969D01*
X664151Y11582D01*
Y13056D01*
X662333Y14874D01*
X662192D01*
G01X663582Y38940D02*
Y35784D01*
X664092Y34609D01*
X664221Y33915D01*
X664353Y33207D01*
X663836Y31871D01*
X663089Y31124D01*
X661708Y30699D01*
G01X651772Y246456D02*
Y250744D01*
X651191Y251325D01*
Y261447D01*
X652233Y262489D01*
G01X665945Y246456D02*
X659504D01*
X659437Y246389D01*
G01X652953Y278740D02*
Y276347D01*
X655300Y274000D01*
X659500D01*
G01X664764Y278740D02*
Y275604D01*
X664060Y274900D01*
Y273740D01*
X665100Y272700D01*
G01X674212Y6656D02*
Y11795D01*
X673600Y12407D01*
Y13499D01*
X674320Y14219D01*
G01X671850Y6656D02*
Y11897D01*
X671290Y12457D01*
G01X677756Y38940D02*
Y36051D01*
X678337Y35470D01*
Y23849D01*
X677295Y22807D01*
G01X680118Y38940D02*
Y35925D01*
X679537Y35344D01*
Y23850D01*
X680580Y22807D01*
G01X665945Y38940D02*
Y31196D01*
X665056Y30307D01*
X664678D01*
G01X673031Y38940D02*
Y32676D01*
X674400Y31307D01*
G01X670669Y38940D02*
Y33816D01*
X671295Y33190D01*
G01X673032Y246456D02*
Y249598D01*
X671630Y251000D01*
Y253270D01*
X670200Y254700D01*
G01X668307Y246456D02*
Y250319D01*
X666437Y252189D01*
X665500D01*
G01X675394Y246456D02*
Y249241D01*
X672730Y251905D01*
Y253830D01*
X673652Y254752D01*
X673770D01*
G01X669488Y278740D02*
X669489Y278739D01*
Y274882D01*
X671000Y273371D01*
Y272100D01*
X669800Y270900D01*
X669700D01*
G01X678937Y278740D02*
Y275689D01*
X678356Y275108D01*
Y263531D01*
X679398Y262489D01*
G01X676575Y278740D02*
Y275851D01*
X677156Y275270D01*
Y263532D01*
X676113Y262489D01*
G01X671851Y278740D02*
Y275020D01*
X672800Y274071D01*
Y272700D01*
G01X681299Y6656D02*
Y10071D01*
X683060Y11832D01*
Y13747D01*
X682013Y14794D01*
Y14848D01*
G01X688386Y6656D02*
Y10493D01*
X690102Y12209D01*
Y12502D01*
G01X695472Y6656D02*
Y9726D01*
X696053Y10307D01*
Y21829D01*
X695029Y22853D01*
G01X683661Y6656D02*
Y9791D01*
X683445Y10007D01*
Y10661D01*
X684760Y11976D01*
Y12256D01*
G01X690748Y6656D02*
Y10675D01*
X691860Y11787D01*
Y11808D01*
X692200Y12148D01*
Y15357D01*
G01X687204Y38940D02*
Y35191D01*
X685340Y33327D01*
Y31167D01*
X685700Y30807D01*
G01X684842Y38940D02*
Y34737D01*
X683270Y33165D01*
Y32117D01*
X682060Y30907D01*
X681900D01*
G01X694291Y38940D02*
Y36198D01*
X692000Y33907D01*
Y31907D01*
X693300Y30607D01*
G01X691929Y38940D02*
Y36236D01*
X690100Y34407D01*
Y30859D01*
X689624Y30383D01*
G01X684843Y246456D02*
Y251650D01*
X685100Y251908D01*
Y251918D01*
X685382Y252200D01*
G01X682481Y246456D02*
Y249781D01*
X683682Y250982D01*
Y252894D01*
X683690Y252902D01*
Y254110D01*
X682900Y254900D01*
X682800D01*
G01X691929Y246456D02*
Y255129D01*
X692250Y255450D01*
Y255700D01*
G01X689567Y246456D02*
Y249747D01*
X690420Y250600D01*
Y252980D01*
X688800Y254600D01*
G01X686024Y278740D02*
Y274024D01*
X685100Y273100D01*
G01X690748Y278740D02*
Y271848D01*
X689700Y270800D01*
G01X683662Y278740D02*
Y274162D01*
X682481Y272981D01*
Y270700D01*
G01X693110Y278740D02*
Y273562D01*
X692537Y272989D01*
G01X702559Y6656D02*
Y11848D01*
X702000Y12407D01*
Y12607D01*
G01X704921Y6656D02*
Y11431D01*
X704660Y11692D01*
Y14144D01*
X705031Y14515D01*
G01X697834Y6656D02*
Y9773D01*
X697253Y10354D01*
Y21831D01*
X698277Y22855D01*
G01X709645Y6656D02*
Y11762D01*
X709000Y12407D01*
G01X708464Y38940D02*
Y35823D01*
X709240Y35047D01*
Y30747D01*
X708900Y30407D01*
G01X701378Y38940D02*
Y35879D01*
X702640Y34617D01*
Y31647D01*
X701800Y30807D01*
G01X703740Y38940D02*
Y34003D01*
X704430Y33313D01*
G01X710827Y38940D02*
Y34122D01*
X710750Y34045D01*
Y32357D01*
X712171Y30936D01*
X712271D01*
X712400Y30807D01*
G01X706103Y246456D02*
Y250264D01*
X704178Y252189D01*
G01X713189Y246456D02*
Y249396D01*
X710650Y251935D01*
Y254322D01*
X711400Y255072D01*
G01X710827Y246456D02*
Y249503D01*
X709190Y251140D01*
Y253710D01*
X707900Y255000D01*
X707800D01*
G01X703740Y246456D02*
Y249925D01*
X703741Y249926D01*
X702478Y251189D01*
Y254220D01*
X701649Y255049D01*
G01X699016Y246456D02*
Y249510D01*
X698005Y250521D01*
Y253005D01*
X698800Y253800D01*
Y261812D01*
X699477Y262489D01*
G01X696654Y246456D02*
Y249406D01*
X696805Y249557D01*
Y253503D01*
X697600Y254298D01*
Y261081D01*
X696192Y262489D01*
G01X700197Y278740D02*
Y275803D01*
X702100Y273900D01*
Y271500D01*
X701377Y270777D01*
X701300D01*
G01X702559Y278740D02*
Y275668D01*
X704276Y273951D01*
Y272990D01*
X704277Y272989D01*
G01X707284Y278740D02*
Y275142D01*
X709400Y273026D01*
Y272600D01*
G01X709646Y278740D02*
Y275020D01*
X711300Y273366D01*
Y271300D01*
X712100Y270500D01*
X712200D01*
G01X712008Y6656D02*
Y13950D01*
X712182Y14124D01*
G01X721456Y6656D02*
Y9933D01*
X723586Y12063D01*
Y14080D01*
G01X719094Y6656D02*
Y9321D01*
X721000Y11227D01*
Y13857D01*
X720150Y14707D01*
X720100D01*
G01X726181Y6656D02*
Y10753D01*
X728010Y12582D01*
Y12857D01*
G01X715551Y38940D02*
Y35156D01*
X715351Y34956D01*
Y29558D01*
X716400Y28509D01*
Y24217D01*
X715090Y22907D01*
G01X717913Y38940D02*
Y35820D01*
X716551Y34458D01*
Y30056D01*
X717600Y29007D01*
Y23682D01*
X718375Y22907D01*
G01X725000Y38940D02*
Y34407D01*
X723565Y32972D01*
Y30137D01*
X723500Y30072D01*
Y29907D01*
G01X722638Y38940D02*
Y33845D01*
X721747Y32954D01*
G01X725000Y246456D02*
Y249300D01*
X723095Y251205D01*
Y253152D01*
X721607Y254893D01*
X721500Y255000D01*
G01X727362Y246456D02*
Y249158D01*
X725647Y250873D01*
X725245D01*
X724250Y251868D01*
Y254391D01*
X724374Y254515D01*
G01X717914Y246456D02*
Y249466D01*
X718495Y250047D01*
Y261446D01*
X717452Y262489D01*
G01X720276Y246456D02*
Y249450D01*
X719695Y250031D01*
Y261447D01*
X720737Y262489D01*
G01X723819Y278740D02*
Y275007D01*
X725200Y273626D01*
Y272900D01*
X725300Y272800D01*
G01X721457Y278740D02*
Y275743D01*
X723600Y273600D01*
Y271856D01*
X722544Y270800D01*
X722400D01*
G01X740354Y6656D02*
Y13053D01*
X739000Y14407D01*
G01X733267Y6656D02*
Y9674D01*
X733848Y10255D01*
Y22565D01*
X732806Y23607D01*
G01X735630Y6656D02*
Y9577D01*
X735048Y10159D01*
Y22564D01*
X736091Y23607D01*
G01X728543Y6656D02*
Y10985D01*
X730100Y12542D01*
Y13515D01*
X731169Y14584D01*
G01X739173Y38940D02*
Y34814D01*
X740200Y33787D01*
Y29907D01*
G01X741535Y38940D02*
Y33572D01*
X742100Y33007D01*
G01X732086Y38940D02*
Y34993D01*
X731400Y34307D01*
Y30807D01*
X730500Y29907D01*
G01X729724Y38940D02*
Y33131D01*
X727000Y30407D01*
G01X740000Y238600D02*
X738600D01*
X727400Y227400D01*
G01X740000Y238600D02*
X743800D01*
X744500Y239300D01*
G01X734449Y246456D02*
Y250377D01*
X732626Y252200D01*
X732200D01*
G01X741536Y246456D02*
Y254976D01*
X741560Y255000D01*
G01X732087Y246456D02*
Y249721D01*
X730400Y251408D01*
Y255400D01*
G01X735630Y278740D02*
Y275696D01*
X736211Y275115D01*
Y263532D01*
X735168Y262489D01*
G01X742717Y278740D02*
Y274517D01*
X741900Y273700D01*
Y271200D01*
X741200Y270500D01*
G01X728544Y278740D02*
Y274882D01*
X730337Y273089D01*
Y272913D01*
X730400Y272850D01*
G01X730906Y278740D02*
Y275020D01*
X732740Y273186D01*
Y270200D01*
G01X737992Y278740D02*
Y275744D01*
X737411Y275163D01*
Y263531D01*
X738453Y262489D01*
G01X742716Y6656D02*
Y11891D01*
X742200Y12407D01*
G01X748622Y246456D02*
Y240422D01*
X747500Y239300D01*
X744500D01*
G01X743898Y246456D02*
Y251650D01*
X744437Y252189D01*
G01X745079Y278740D02*
Y276354D01*
X744600Y273000D01*
X744200Y272600D01*
G54D103*
G01X63000Y204100D02*
X68000D01*
G01X74800Y191000D02*
X78000D01*
X81500Y194500D01*
G01X73500Y198500D02*
Y192529D01*
X72500Y191529D01*
Y185209D01*
X74500Y183209D01*
G01X68000Y204100D02*
X73500Y198600D01*
Y198500D01*
G01X69000Y225700D02*
Y223300D01*
X67700Y222000D01*
G01X71500Y256500D02*
Y252000D01*
X66750Y247250D01*
Y243345D01*
X66000Y242595D01*
Y228900D01*
X69000Y225900D01*
Y225700D01*
G01X74611Y221550D02*
Y225089D01*
X74000Y225700D01*
G01X74611Y221550D02*
X74261Y221200D01*
X72100D01*
X71300Y222000D01*
G01X68000Y234700D02*
X71333D01*
X71633Y235000D01*
G01X71500Y238700D02*
X71700Y238500D01*
Y235067D01*
X71633Y235000D01*
G01X78000Y242200D02*
X80512D01*
X81600Y241112D01*
G01X69000Y230900D02*
X74000D01*
G01D02*
X76600Y233500D01*
Y235130D01*
G01D02*
X74900Y236830D01*
Y238700D01*
G01X75400Y241700D02*
Y242000D01*
X72600Y244800D01*
G01X74900Y238700D02*
Y241200D01*
X75400Y241700D01*
G01X78000Y238800D02*
X77900Y238700D01*
X74900D01*
G01X71800Y241700D02*
X68500D01*
X68400Y241600D01*
G01X71800Y241700D02*
Y242600D01*
X69400Y245000D01*
Y246000D01*
G01X68000Y238300D02*
Y241200D01*
X68400Y241600D01*
G01X82100Y259600D02*
X79800Y261900D01*
X73871D01*
X71500Y259529D01*
Y256500D01*
G01X79000Y246900D02*
X81300Y244600D01*
X82900D01*
X85200Y242300D01*
G01X80900Y250100D02*
Y248800D01*
X79000Y246900D01*
G01X78500Y253300D02*
X80900Y250900D01*
Y250100D01*
G01X78500Y256700D02*
Y259600D01*
X78700Y259800D01*
G01X75500Y253300D02*
X73500Y251300D01*
Y249800D01*
G01D02*
Y248800D01*
X75600Y246700D01*
G01X75500Y256700D02*
Y259700D01*
X75300Y259900D01*
G01X71800Y268800D02*
X74400Y266200D01*
X79300D01*
X84200Y261300D01*
Y255500D01*
G01X81500Y194500D02*
X82100D01*
X84700Y197100D01*
G01X83500Y191000D02*
Y191329D01*
X106171Y214000D01*
X108000D01*
G01X117200Y216400D02*
X112300Y211500D01*
X106500D01*
X86900Y191900D01*
Y191000D01*
G01X82000Y202000D02*
X84496D01*
X85898Y200598D01*
G01X80563Y214700D02*
X83463Y211800D01*
X84200D01*
G01D02*
X87800D01*
G01X92800Y221300D02*
X93994D01*
X96194Y219100D01*
X96200D01*
G01X101491Y230420D02*
X97406Y226335D01*
Y222494D01*
X98600Y221300D01*
Y216098D01*
X96208Y213706D01*
X92494D01*
X91200Y215000D01*
X90812D01*
G01D02*
X90612Y215200D01*
X87800D01*
G01D02*
Y217900D01*
X88800Y218900D01*
G01X88200Y242200D02*
X83800Y246600D01*
X82400D01*
G01X81600Y241112D02*
Y237900D01*
X81500Y237800D01*
G01X82400Y246600D02*
Y247400D01*
X84200Y249200D01*
Y255500D01*
G01X88000Y253300D02*
Y249700D01*
G01D02*
Y247600D01*
X88900Y246700D01*
G01X80500Y269500D02*
X82500Y267500D01*
X84800D01*
X90750Y273450D01*
X115572D01*
X118028Y275905D01*
X146595D01*
X159500Y263000D01*
Y257800D01*
X158700Y257000D01*
G01X83900Y269500D02*
Y272900D01*
X86450Y275450D01*
X114602D01*
X117058Y277905D01*
X147424D01*
X161500Y263829D01*
Y257800D01*
X162300Y257000D01*
G01X198700Y230500D02*
X199500Y229700D01*
Y227000D01*
X193125Y220625D01*
X186802D01*
X184677Y218500D01*
X139500D01*
X138000Y220000D01*
X117300D01*
X111300Y214000D01*
X108000D01*
G01X95200Y216200D02*
X96194Y217194D01*
Y218894D01*
X96200Y218900D01*
Y219100D01*
G01X112700Y231400D02*
X110100Y234000D01*
X105071D01*
X101491Y230420D01*
G01X202300Y230500D02*
X201500Y229700D01*
Y226171D01*
X193954Y218625D01*
X187631D01*
X185506Y216500D01*
X138671D01*
X137171Y218000D01*
X118800D01*
X117200Y216400D01*
G01X169800Y181448D02*
X171885D01*
G01X169485Y186997D02*
X160403D01*
X160100Y187300D01*
G01X166000Y197500D02*
Y194500D01*
X167204Y193296D01*
X169485D01*
G01Y201170D02*
X168130D01*
X165900Y203400D01*
X165700D01*
G01D02*
Y200600D01*
X166704Y199596D01*
X169485D01*
G01X161900Y253300D02*
X162300Y253700D01*
Y257000D01*
G01X176400Y175700D02*
Y176600D01*
X178184Y178384D01*
Y181448D01*
G01X182908D02*
Y178480D01*
X184100Y177288D01*
Y173100D01*
X181500Y170500D01*
G01X186700Y175500D02*
Y172800D01*
X186300Y172400D01*
G01X184483Y181448D02*
Y179017D01*
X186700Y176800D01*
Y175500D01*
G01X178184Y203570D02*
Y207216D01*
X177500Y207900D01*
Y209500D01*
G01X184483Y203570D02*
Y205881D01*
X187000Y208398D01*
Y209500D01*
G01X173459Y203570D02*
Y206101D01*
X174739Y207381D01*
G01X175034Y203570D02*
Y207008D01*
X174739Y207303D01*
Y207381D01*
G01X191607Y186997D02*
X195900D01*
X196000Y186897D01*
G01X191607Y193296D02*
X195104D01*
X195630Y192770D01*
G01X189207Y203570D02*
Y204707D01*
X190600Y206100D01*
X191400D01*
G01D02*
X191607Y205893D01*
Y201170D01*
G01X212500Y219500D02*
Y221500D01*
X214000Y223000D01*
G01X249410Y67126D02*
X255700Y73416D01*
Y77371D01*
X257800Y79471D01*
Y80200D01*
G01X387574Y268343D02*
X390043D01*
X390500Y268800D01*
G01X726200Y105500D02*
Y111300D01*
X726500Y111600D01*
G01X729400Y102100D02*
X726200D01*
G01X722300Y116500D02*
X725200D01*
G01X728900Y116100D02*
X725600D01*
X725200Y116500D01*
G01X736300Y118000D02*
X735600D01*
X731000Y113400D01*
X728300D01*
X726500Y111600D01*
G01X718700Y112500D02*
Y116500D01*
G01X718682Y119685D02*
Y116518D01*
X718700Y116500D01*
G01X727100Y123400D02*
X726200D01*
X725200Y122400D01*
Y119900D01*
G01X722082Y119685D02*
X724985D01*
X725200Y119900D01*
G01X744600Y99600D02*
Y100295D01*
X741500Y103395D01*
Y107300D01*
X742500Y108300D01*
G01X729400Y105500D02*
X732800D01*
G01D02*
X733000Y105700D01*
Y108700D01*
G01X731500Y98600D02*
Y97890D01*
X735790Y93600D01*
X751947D01*
X762304Y103957D01*
G01X731500Y98600D02*
Y100000D01*
X729400Y102100D01*
G01X736600Y108700D02*
X736200Y108300D01*
Y105500D01*
G01X739900Y101400D02*
X738800Y102500D01*
X736200D01*
G01X739900Y101400D02*
Y100200D01*
X738200Y98500D01*
X736900D01*
G01X736200Y105500D02*
Y102500D01*
G01X732800D02*
X734200Y101100D01*
Y98019D01*
X736219Y96000D01*
X740000D01*
G01D02*
X751518D01*
X758916Y103398D01*
Y104250D01*
G01X742100Y118200D02*
X740300Y120000D01*
X734600D01*
X730700Y116100D01*
X728900D01*
G01X732900Y111900D02*
X733027D01*
X734927Y113800D01*
X735200D01*
X738300Y116900D01*
X740400D01*
X741100Y116200D01*
X742929D01*
X745100Y118371D01*
Y120440D01*
X745140Y120480D01*
G01X732900Y111900D02*
X733000Y111800D01*
Y108700D01*
G01X729400Y120200D02*
Y121100D01*
X727100Y123400D01*
G01X736600Y108700D02*
X739300D01*
G01X736600D02*
X736500Y108800D01*
Y111900D01*
G01X742500Y111700D02*
X739500Y108700D01*
X739300D01*
G01X734600Y130900D02*
X732400D01*
X731200Y129700D01*
Y129600D01*
G01X735000Y126500D02*
X734600Y126900D01*
Y130900D01*
G01X731200Y129600D02*
X730493Y128893D01*
X727448D01*
G01X734500Y137100D02*
Y134200D01*
X734600Y134100D01*
G01D02*
X730524D01*
X729400Y132976D01*
X728900D01*
G01X732000Y122700D02*
X732400Y123100D01*
X735000D01*
G01X738300Y123200D02*
X741000D01*
X742000Y124200D01*
G01X735000Y123100D02*
X738200D01*
X738300Y123200D01*
G01X727100Y123400D02*
Y123500D01*
G01X731200Y138500D02*
X733100D01*
X734500Y137100D01*
G01X749500Y101500D02*
X747472Y99472D01*
X744728D01*
X744600Y99600D01*
G01X745500Y108300D02*
Y106100D01*
X744100Y104700D01*
G01X745140Y120480D02*
X747460Y122800D01*
X749500D01*
G01D02*
X751300Y121000D01*
Y118200D01*
G01X748500Y111700D02*
Y112500D01*
X751300Y115300D01*
Y118200D01*
G01X742500Y111700D02*
X745500D01*
G01D02*
Y112500D01*
X748800Y115800D01*
G01X745500Y108300D02*
X748500D01*
G54D10*
G01X21949Y230118D02*
X16118D01*
G01X32500Y87300D02*
X28500Y83300D01*
Y81500D01*
X28400Y81400D01*
G01X62900Y79900D02*
X59700D01*
X53600Y86000D01*
X43265D01*
X42265Y85000D01*
X33900D01*
X32500Y86400D01*
Y87300D01*
G01X42000Y96000D02*
X39000Y93000D01*
X34000D01*
X32500Y91500D01*
Y90700D01*
G01X31800Y96000D02*
X31000D01*
X28500Y93500D01*
G01D02*
X31300Y90700D01*
X32500D01*
G01X30000Y136000D02*
Y129500D01*
X28700Y128200D01*
X26000D01*
G01X57600Y136900D02*
X54900D01*
X43500Y125500D01*
Y123000D01*
X42500Y122000D01*
X37000D01*
X34200Y124800D01*
X26000D01*
G01X22300Y127700D02*
X25200Y124800D01*
X26000D01*
G01X22300Y131500D02*
Y127700D01*
G01X41200Y90300D02*
X40800Y90700D01*
X35500D01*
G01X46800Y274500D02*
X50050Y277750D01*
X113790D01*
X116491Y280451D01*
X117900Y281851D01*
X168761D01*
X182285Y268327D01*
X219827D01*
X227000Y275500D01*
G01X71300Y132500D02*
X72500Y131300D01*
Y125500D01*
X67400Y120400D01*
X60700D01*
X60500Y120200D01*
G01D02*
X60300Y120400D01*
X53500D01*
G01X61000Y135300D02*
X59200D01*
X57600Y136900D01*
G01X56100Y130700D02*
X56900Y131500D01*
X60000D01*
G01X60500Y126800D02*
Y131000D01*
X60000Y131500D01*
G01X62000Y142500D02*
X62500D01*
X64300Y140700D01*
Y138500D01*
G01X58000Y141750D02*
X58750Y142500D01*
X62000D01*
G01X58487Y251713D02*
X55987D01*
G01X64200Y91000D02*
Y88000D01*
X64500Y87700D01*
G01X107000Y75000D02*
X103574Y78426D01*
X70374D01*
X64500Y84300D01*
G01X72800Y84500D02*
Y88000D01*
G01X69100Y87800D02*
X68200Y88700D01*
Y91500D01*
G01X72800Y88000D02*
X72600Y87800D01*
X69100D01*
G01X115991Y82591D02*
X114026Y80626D01*
X80074D01*
X76200Y84500D01*
G01X68200Y94900D02*
Y96600D01*
X66700Y98100D01*
X65700D01*
G01X64200Y91000D02*
Y94500D01*
G01D02*
Y96600D01*
X65700Y98100D01*
G01X75700Y94500D02*
Y91600D01*
X75800Y91500D01*
G01X85300D02*
X75800D01*
G01X69235Y99735D02*
X70900Y101400D01*
X72700D01*
G01D02*
Y97900D01*
X72300Y97500D01*
G01D02*
Y94500D01*
G01D02*
Y91600D01*
X72200Y91500D01*
G01X67700Y135500D02*
Y132600D01*
X67800Y132500D01*
G01D02*
X71300D01*
G01X70000Y127500D02*
X69500Y128000D01*
X66500D01*
G01X64300Y135500D02*
Y138500D01*
G01X64200Y132500D02*
Y135400D01*
X64300Y135500D01*
G01X106100Y158700D02*
X103526D01*
X91113Y171113D01*
X88400Y173825D01*
X79206D01*
X78240Y174791D01*
G01X85300Y91500D02*
X85600D01*
X89800Y87300D01*
G01X90000Y91000D02*
X93000Y88000D01*
X110000D01*
X119800Y97800D01*
X127500D01*
G01X86100Y97700D02*
X85200Y98600D01*
Y103500D01*
G01Y110000D02*
Y103500D01*
G01X82200Y110000D02*
X85200D01*
G01X107700Y143000D02*
X94819D01*
X87219Y135400D01*
X85500D01*
G01X107000Y75000D02*
X111936D01*
X118491Y81555D01*
Y81952D01*
X124839Y88300D01*
X131194D01*
X133558Y90664D01*
Y91779D01*
G01X107700Y143000D02*
X112350D01*
X112550Y142800D01*
G01X130315Y90533D02*
X130282Y90500D01*
X123900D01*
X115991Y82591D01*
G01X130200Y178600D02*
X126624Y182176D01*
X124878D01*
G01X122319Y200662D02*
Y203681D01*
X121000Y205000D01*
Y209300D01*
G01D02*
X119000D01*
X117000Y207300D01*
X114900D01*
G01X111900Y209000D02*
X113600Y207300D01*
X114900D01*
G01X134800Y161800D02*
X137300Y159300D01*
Y158900D01*
G01X132300Y172000D02*
X132200Y172100D01*
Y175000D01*
G01D02*
Y176600D01*
X130200Y178600D01*
G01X132200Y169000D02*
X132300Y169100D01*
Y172000D01*
G01X129003Y196537D02*
X133237D01*
X134100Y197400D01*
G01D02*
X136300Y199600D01*
Y201000D01*
G01X139300D02*
Y198053D01*
X137900Y196653D01*
Y193200D01*
X138600Y192500D01*
G01X129003Y186301D02*
X132699D01*
X132700Y186300D01*
G01D02*
Y183100D01*
G01X135200Y192500D02*
X135300Y192400D01*
Y190700D01*
X137100Y188900D01*
G01X136300Y201000D02*
X139300D01*
G01X143800Y112000D02*
X142775Y113025D01*
Y138470D01*
X142900Y138595D01*
G01X181600Y113200D02*
Y116606D01*
X189194Y124200D01*
X194900D01*
G01X178600Y113200D02*
X181600D01*
G01X207400Y87900D02*
X203800D01*
X202200Y89500D01*
G01X202000Y183068D02*
X202761Y183829D01*
Y186811D01*
G01X218100Y195000D02*
X215900D01*
X215100Y194200D01*
G01X215200Y206500D02*
Y203168D01*
X215384Y202984D01*
G01X219200Y202400D02*
Y199500D01*
X218100Y198400D01*
G01D02*
X216100D01*
X215100Y199400D01*
G01X220500Y221000D02*
X217500D01*
X216000Y219500D01*
G01X232600Y95300D02*
X230125D01*
X227850Y97575D01*
G01X224200Y180200D02*
Y178300D01*
X232895Y169605D01*
X233602D01*
X233924Y169472D01*
X236886Y166510D01*
Y122486D01*
X233452Y119052D01*
Y108588D01*
G01X264500Y73100D02*
X261400D01*
G01X261100Y76200D02*
Y73400D01*
X261400Y73100D01*
G01X258000D02*
Y75700D01*
X257500Y76200D01*
G01X263800Y70000D02*
X261100D01*
X258000Y73100D01*
G01X261400Y83000D02*
Y77000D01*
X261100Y76700D01*
Y76200D01*
G01X264100Y154800D02*
X264800Y154100D01*
X268700D01*
X269440Y153360D01*
Y152680D01*
G01X264100Y154800D02*
X262733Y156167D01*
Y171367D01*
X259200Y174900D01*
Y192200D01*
X263401Y196401D01*
Y210799D01*
X259800Y214400D01*
Y259012D01*
X259799Y259013D01*
Y260627D01*
X272755Y273583D01*
Y273584D01*
X273896Y274725D01*
X293500D01*
X293988Y274237D01*
X303337D01*
X304800Y275700D01*
X312300D01*
X316945Y280345D01*
Y281606D01*
G01X274047Y73795D02*
Y76553D01*
X275200Y77706D01*
Y78700D01*
G01X270000Y96900D02*
X268600Y95500D01*
Y85600D01*
X266600Y83600D01*
Y83000D01*
G01X272079Y84205D02*
Y85909D01*
X270800Y87188D01*
Y91500D01*
X271500Y92200D01*
G01X276016Y84205D02*
Y88084D01*
X275900Y88200D01*
G01X283100Y88100D02*
X281905Y86905D01*
X278938D01*
X277984Y85951D01*
Y84205D01*
G01X270000Y96900D02*
X271200D01*
X275500Y101200D01*
G01X271500Y92200D02*
X271600Y92300D01*
Y95300D01*
X270000Y96900D01*
G01X275880Y132540D02*
X274583D01*
X273380Y133743D01*
Y139520D01*
X271500Y141400D01*
G01X283100Y91500D02*
X280700Y89100D01*
X280100D01*
G01X288500Y90600D02*
Y94100D01*
X288400Y94200D01*
G01X289800Y119000D02*
X287400D01*
X286500Y119900D01*
G01X289800Y119000D02*
Y116000D01*
G01Y119000D02*
Y122000D01*
G01Y113000D02*
Y110000D01*
G01Y116000D02*
Y113000D01*
G01Y122000D02*
Y125000D01*
G01Y128000D02*
Y131000D01*
G01Y125000D02*
Y128000D01*
G01X293300Y212400D02*
Y210746D01*
X289500Y206946D01*
Y199700D01*
X289700Y199500D01*
G01D02*
X293300D01*
G01X285200Y233000D02*
Y223958D01*
X286333Y222825D01*
X295302D01*
X307200Y210927D01*
Y202337D01*
X305800Y200937D01*
Y195400D01*
G01X287600Y238100D02*
X285200Y235700D01*
Y233000D01*
G01X314639Y74202D02*
X311298D01*
X310200Y75300D01*
Y78100D01*
X306600Y81700D01*
X304600D01*
X304500Y81800D01*
G01D02*
X303900D01*
X299800Y85900D01*
Y85950D01*
G01X318764Y80886D02*
Y83136D01*
X317000Y84900D01*
G01D02*
X315200Y86700D01*
Y88300D01*
G01X315000Y91400D02*
X315200Y91200D01*
Y88300D01*
G01X315000Y94800D02*
Y96000D01*
X312232Y98768D01*
Y100600D01*
X312150Y100682D01*
G01X312000Y91400D02*
X315000D01*
G01X337300Y84500D02*
Y81500D01*
G01Y84500D02*
Y88000D01*
G01X337200Y78500D02*
X335461Y76761D01*
X333125D01*
G01X337300Y81500D02*
Y78600D01*
X337200Y78500D01*
G01X329000Y80886D02*
Y84700D01*
X329300Y85000D01*
G01D02*
X329700Y85400D01*
X332400D01*
G01X348000Y183700D02*
X347500Y184200D01*
Y188825D01*
X347350Y188975D01*
Y193804D01*
X348346Y194800D01*
X349600D01*
G01X384921Y271980D02*
Y274021D01*
X386100Y275200D01*
Y275300D01*
G01X382953Y271980D02*
Y275047D01*
X382700Y275300D01*
G01X387574Y258500D02*
X390977D01*
X391508Y257969D01*
G01X401400Y254500D02*
X399800D01*
X398000Y256300D01*
G01D02*
X397500Y256800D01*
X395000D01*
G01D02*
X392677D01*
X391508Y257969D01*
G01X387574Y266374D02*
X389626D01*
X391000Y265000D01*
G01X398000Y267300D02*
X402400D01*
X403000Y266700D01*
G01X395000Y267200D02*
Y264290D01*
X394650Y263940D01*
G01X387574Y262437D02*
X393147D01*
X394650Y263940D01*
G01X399300Y262400D02*
X400200Y263300D01*
X403000D01*
G01X399300Y262400D02*
X397100Y260200D01*
X395000D01*
G01D02*
X394731Y260469D01*
X387574D01*
G01X412600Y262800D02*
X413800D01*
X416128Y265128D01*
Y268872D01*
G01D02*
Y272896D01*
G01X406000Y266800D02*
X405900Y266700D01*
X403000D01*
G01X410000Y266500D02*
Y263600D01*
X409200Y262800D01*
G01X406000Y266800D02*
X409700D01*
X410000Y266500D01*
G01X403000Y263300D02*
X405900D01*
X406000Y263200D01*
G01X438940Y24640D02*
X441260Y22320D01*
X445175D01*
X445760Y22905D01*
Y23797D01*
X446883Y24920D01*
Y32972D01*
X445175Y34680D01*
X445020D01*
X443700Y36000D01*
G01X449734Y18681D02*
X449753Y18700D01*
X452119D01*
X456970Y23551D01*
Y25891D01*
X464500Y33421D01*
Y88647D01*
X472201Y96348D01*
X505131D01*
X509300Y92179D01*
Y85704D01*
X513704Y81300D01*
X635646D01*
X642823Y88477D01*
G01X506496Y6656D02*
Y12603D01*
X506800Y12907D01*
G01X510040Y246456D02*
Y250025D01*
X507817Y252248D01*
G01X520669Y6656D02*
Y11013D01*
X520160Y11522D01*
Y11584D01*
X519426Y12318D01*
G01X513582Y6656D02*
Y11639D01*
X514360Y12417D01*
G01X527756Y6656D02*
Y10222D01*
X526000Y11978D01*
Y12507D01*
G01X514764Y38940D02*
Y34171D01*
X513005Y32412D01*
G01X517126Y38940D02*
Y35614D01*
X519400Y33340D01*
G01X517126Y246456D02*
Y251674D01*
X516600Y252200D01*
G01X519488Y246456D02*
Y250563D01*
X521800Y252875D01*
G01X515945Y278740D02*
Y273904D01*
X516727Y273122D01*
G01X523032Y278740D02*
Y275632D01*
X521790Y274390D01*
Y273140D01*
G01X534842Y6656D02*
Y11065D01*
X532500Y13407D01*
G01X537204Y6656D02*
Y11541D01*
X537964Y12301D01*
Y12317D01*
G01X541929Y6656D02*
Y10208D01*
X541114Y11023D01*
Y12307D01*
G01X540748Y246456D02*
Y252148D01*
X540900Y252300D01*
G01X526575Y246456D02*
Y251275D01*
X527400Y252100D01*
G01X533662Y246456D02*
Y250162D01*
X535098Y251598D01*
Y252600D01*
G01X549015Y6656D02*
Y10092D01*
X547500Y11607D01*
Y12507D01*
G01X556102Y6656D02*
X556086Y6672D01*
Y9931D01*
X553720Y12297D01*
G01X552559Y38940D02*
Y33898D01*
X553250Y33207D01*
G01X545472Y38940D02*
Y35537D01*
X547306Y33703D01*
Y33134D01*
G01X554922Y246456D02*
Y250678D01*
X553485Y252115D01*
Y252332D01*
G01X547835Y246456D02*
Y250265D01*
X545500Y252600D01*
G01X558464Y6656D02*
Y12391D01*
X558448Y12407D01*
G01X565551Y6656D02*
Y11803D01*
X566040Y12292D01*
Y12317D01*
G01X566732Y38940D02*
Y34549D01*
X565470Y33287D01*
G01X559645Y38940D02*
Y34254D01*
X560635Y33264D01*
G01X561000Y222700D02*
X564700Y219000D01*
X607983D01*
X613083Y213900D01*
X679975D01*
X711350Y182525D01*
Y173750D01*
X718900Y166200D01*
G01X564200Y224000D02*
X567000Y221200D01*
X608895D01*
X613995Y216100D01*
X680887D01*
X713551Y183436D01*
Y175649D01*
X714038Y175162D01*
G01X564370Y246456D02*
Y249570D01*
X566151Y251351D01*
Y252115D01*
G01X571457Y246456D02*
Y251457D01*
X572150Y252150D01*
Y252200D01*
G01X557284Y246456D02*
Y249384D01*
X560300Y252400D01*
X560452D01*
X560555Y252503D01*
G01X567914Y278740D02*
Y275714D01*
X565700Y273500D01*
Y273050D01*
G01X572638Y6656D02*
X572637Y6657D01*
Y11514D01*
X573470Y12347D01*
G01X586811Y6656D02*
Y10736D01*
X585280Y12267D01*
G01X579724Y6656D02*
Y10473D01*
X578620Y11577D01*
Y12357D01*
G01X573819Y33039D02*
X573242Y32462D01*
G01X576181Y38940D02*
Y35401D01*
X573819Y33039D01*
G01Y38940D02*
Y33039D01*
G01X583267Y38940D02*
Y35740D01*
X585550Y33457D01*
Y33340D01*
G01X584449Y278740D02*
Y274006D01*
X584636Y273819D01*
Y261964D01*
X589500Y257100D01*
G01X577362Y278740D02*
Y273221D01*
X577636Y272947D01*
G01X575000Y278740D02*
Y275500D01*
X572800Y273300D01*
Y273200D01*
X572700Y273100D01*
G01X603964Y210400D02*
X606100D01*
X606700Y211000D01*
G01X676575Y6656D02*
Y11772D01*
X675990Y12357D01*
G01X678937Y6656D02*
Y10154D01*
X681240Y12457D01*
X681280D01*
G01X669488Y6656D02*
Y11490D01*
X669401Y11577D01*
Y17408D01*
X669600Y17607D01*
Y17907D01*
G01X675393Y38940D02*
Y33874D01*
X675970Y33297D01*
Y33267D01*
G01X677756Y246456D02*
Y249424D01*
X674894Y252286D01*
X674756D01*
X674636Y252406D01*
G01X670670Y246456D02*
Y249860D01*
X669930Y250600D01*
Y252150D01*
G01X686023Y6656D02*
Y10761D01*
X687469Y12207D01*
Y12306D01*
X687602Y12439D01*
G01X693110Y6656D02*
Y11290D01*
X694200Y12380D01*
Y13507D01*
G01X696653Y38940D02*
Y35960D01*
X694000Y33307D01*
X693900D01*
X693700Y33107D01*
G01X689567Y38940D02*
Y35774D01*
X687900Y34107D01*
Y33327D01*
G01X682480Y38940D02*
Y34540D01*
X681280Y33340D01*
G01X700197Y6656D02*
Y11788D01*
X699503Y12482D01*
G01X707283Y6656D02*
Y11474D01*
X706360Y12397D01*
G01X699015Y38940D02*
Y35225D01*
X700803Y33437D01*
X700843D01*
X700940Y33340D01*
G01X706102Y38940D02*
Y34388D01*
X707157Y33333D01*
G01X718900Y166200D02*
X721347Y163753D01*
Y135377D01*
X715770Y129800D01*
X714918D01*
X709700Y124582D01*
Y112090D01*
X726290Y95500D01*
X726800D01*
G01X701378Y246456D02*
X701379Y246457D01*
Y249859D01*
X699800Y251438D01*
Y252230D01*
G01X704922Y278740D02*
Y275304D01*
X706900Y273326D01*
Y273000D01*
G01X714370Y6656D02*
Y12037D01*
X714000Y12407D01*
G01X723819Y6656D02*
Y10226D01*
X725530Y11937D01*
Y12507D01*
G01X716732Y6656D02*
Y9969D01*
X719110Y12347D01*
G01X713189Y38940D02*
Y34079D01*
X712450Y33340D01*
G01X727362Y38940D02*
Y34469D01*
X725653Y32760D01*
Y32654D01*
G01X720275Y38940D02*
Y35032D01*
X718350Y33107D01*
G01X714038Y175162D02*
X723547Y165653D01*
Y134465D01*
X716682Y127600D01*
X715830D01*
X711900Y123670D01*
Y113002D01*
X726002Y98900D01*
X726370D01*
X730200Y95070D01*
Y94900D01*
G01X714000Y118500D02*
X722900Y127400D01*
G01X727800Y136600D02*
X726200Y135000D01*
Y130700D01*
X722900Y127400D01*
G01X729725Y246456D02*
Y249443D01*
X726595Y252573D01*
X725950D01*
G01X715551Y246456D02*
Y251003D01*
X716737Y252189D01*
G01X722638Y246456D02*
Y249859D01*
X721400Y251097D01*
Y252170D01*
X721395Y252175D01*
G01X737992Y6656D02*
Y11615D01*
X737300Y12307D01*
G01X730905Y6656D02*
Y11062D01*
X732110Y12267D01*
G01X736811Y38940D02*
Y34770D01*
X738487Y33094D01*
G01X734449Y38940D02*
Y34256D01*
X733533Y33340D01*
X733474D01*
G01X745078Y6656D02*
Y12185D01*
X745100Y12207D01*
Y12256D01*
G01X744800Y33007D02*
X743897Y33910D01*
Y38940D01*
X-19686Y15748D03*
Y573228D03*
X11500Y68500D03*
X12000Y279000D03*
X45669Y77185D03*
Y172460D03*
X42717Y191732D03*
Y270472D03*
X144000Y67875D03*
Y147125D03*
X200197Y282677D03*
X235630Y75590D03*
Y174016D03*
X298622Y282677D03*
X350197Y231103D03*
X498425Y22798D03*
D03*
X492520Y262598D03*
D03*
X755512D03*
D03*
X761417Y22798D03*
D03*
X816000Y280000D03*
X846455Y15748D03*
Y573228D03*
G54D104*
G01X347500Y139300D02*
Y139203D01*
X349350Y137353D01*
Y133350D01*
X350000Y132700D01*
G54D20*
X26000Y124800D03*
Y128200D03*
X61500Y268900D03*
Y272300D03*
X75500Y253300D03*
Y256700D03*
X78500Y253300D03*
Y256700D03*
X120800Y128900D03*
Y132300D03*
X124000Y209300D03*
Y212700D03*
X140500Y78800D03*
Y82200D03*
X143500Y85800D03*
Y89200D03*
X160000Y60900D03*
Y64300D03*
X157000Y60900D03*
Y64300D03*
X170800Y64400D03*
Y67800D03*
X163000Y164800D03*
Y168200D03*
X186500Y60900D03*
Y64300D03*
X173800Y64400D03*
Y67800D03*
X178600Y109800D03*
Y113200D03*
X181600Y109800D03*
Y113200D03*
X189500Y60900D03*
Y64300D03*
X207400Y84500D03*
Y87900D03*
X257800Y86800D03*
Y90200D03*
Y80200D03*
Y83600D03*
X277000Y49300D03*
Y52700D03*
X271000Y180300D03*
Y183700D03*
X277500Y208800D03*
Y212200D03*
X269500Y240800D03*
Y244200D03*
X278700Y237800D03*
Y241200D03*
X283100Y88100D03*
Y91500D03*
X290200Y151000D03*
Y154400D03*
X309000Y91400D03*
Y94800D03*
X304500Y144300D03*
Y147700D03*
X298500Y241800D03*
Y245200D03*
X324500Y94800D03*
Y98200D03*
X321500Y94800D03*
Y98200D03*
X315000Y91400D03*
Y94800D03*
X312000Y91400D03*
Y94800D03*
X319000Y257300D03*
X322500D03*
X315500D03*
X319000Y260700D03*
X322500D03*
X315500D03*
X339500Y247300D03*
Y250700D03*
X344840Y100940D03*
Y104340D03*
X341840Y100940D03*
Y104340D03*
X347500Y135900D03*
X350000Y129300D03*
Y132700D03*
X347500Y139300D03*
X348000Y180300D03*
Y183700D03*
X363500Y51300D03*
Y54700D03*
X377500Y143300D03*
Y146700D03*
X393500Y84600D03*
Y88000D03*
X396496Y105863D03*
Y109263D03*
X395000Y256800D03*
Y260200D03*
X398000Y267300D03*
Y270700D03*
X403000Y263300D03*
Y266700D03*
X414500Y60800D03*
Y64200D03*
X403500Y105863D03*
Y109263D03*
X434000Y50800D03*
Y54200D03*
X479000Y269000D03*
Y272400D03*
X475500Y269000D03*
Y272400D03*
X510000Y234300D03*
Y237700D03*
X520000Y234300D03*
Y237700D03*
X701000Y165800D03*
Y169200D03*
X726200Y102100D03*
Y105500D03*
X729400Y102100D03*
Y105500D03*
X735000Y123100D03*
Y126500D03*
X751500Y108300D03*
Y111700D03*
X748500Y108300D03*
Y111700D03*
G54D11*
G01X37500Y264000D02*
X35117Y266383D01*
Y273621D01*
X42946Y281450D01*
X112257D01*
X115119Y284312D01*
X116366Y285551D01*
X170449D01*
X183500Y272500D01*
X218500D01*
X225100Y279100D01*
X240900D01*
X253000Y267000D01*
G01X346500Y78300D02*
Y74600D01*
X345700Y73800D01*
Y73700D01*
X345089Y73089D01*
X-11600Y33200D03*
X18400Y76200D03*
X22000Y168500D03*
X24000Y280000D03*
X130000Y72000D03*
X165000Y211500D03*
X394100Y57700D03*
X799500Y10500D03*
X833100Y564800D03*
X842500Y35000D03*
G54D105*
G01X16844Y203100D02*
Y201956D01*
X18210Y200590D01*
X21949D01*
G01X37900Y195300D02*
X38400D01*
X40200Y197100D01*
X42033D01*
X55500Y210567D01*
Y215400D01*
X56300Y216200D01*
X62400D01*
X64200Y218000D01*
G01X57400Y210700D02*
Y209900D01*
X51674Y204174D01*
Y201574D01*
G01X60800Y218000D02*
X60700Y217900D01*
X55772D01*
X54381Y219291D01*
X51674D01*
G01X60800Y218000D02*
X61100Y218300D01*
Y221800D01*
G01X75500Y59500D02*
Y64081D01*
X78919Y67500D01*
X79700D01*
G01X94000Y63300D02*
X97700D01*
X100000Y61000D01*
G01X87000Y61500D02*
X88900D01*
X90600Y63200D01*
G01X107300Y53200D02*
Y57600D01*
X109700Y60000D01*
G01X97900Y76200D02*
X101400Y72700D01*
X117800D01*
X123500Y67000D01*
X134800D01*
G01X94500Y76200D02*
X99950Y70750D01*
X116450D01*
X122150Y65050D01*
X133750D01*
X134800Y64000D01*
G01X106000Y61200D02*
X108500Y63700D01*
X109600D01*
G01X124100Y53300D02*
Y44800D01*
X120000Y40700D01*
G01X125787Y78813D02*
Y76487D01*
X124700Y75400D01*
G01X124084Y84009D02*
X124100Y84025D01*
Y84300D01*
X126000Y86200D01*
G01X121295Y77502D02*
Y76134D01*
X119940Y74779D01*
G01X133786Y134700D02*
X131600Y132514D01*
Y130000D01*
X128625Y127025D01*
X122691D01*
X122687Y127021D01*
X122679D01*
X120800Y128900D01*
G01X144995Y57995D02*
X143416D01*
X139722Y54301D01*
G01X140031Y47317D02*
Y47769D01*
X138000Y49800D01*
G01X138200Y64000D02*
X144969D01*
X147900Y66931D01*
Y73300D01*
G01X159515Y73450D02*
Y76879D01*
X156122Y80272D01*
X149330D01*
X145358Y76300D01*
X144000D01*
X138400Y70700D01*
G01X138200Y67000D02*
Y70500D01*
X138400Y70700D01*
G01X132836Y83507D02*
Y84736D01*
X134200Y86100D01*
G01X128348Y81804D02*
Y83948D01*
X129300Y84900D01*
G01X133300Y77100D02*
X133888Y76512D01*
X137138D01*
G01X143500Y78800D02*
X140500D01*
G01X137005Y80930D02*
X139135Y78800D01*
X140500D01*
G01X132900Y103700D02*
X135277D01*
X136500Y104923D01*
G01X133200Y110800D02*
X134360D01*
X136540Y108620D01*
G01X125500Y132600D02*
X127900D01*
X130300Y135000D01*
G01X127200Y158700D02*
Y155300D01*
X129125Y153375D01*
X148125D01*
X152500Y149000D01*
X157475D01*
X157500Y149025D01*
G01X153300Y61100D02*
Y64900D01*
X154725Y66325D01*
Y68657D01*
X154294Y69088D01*
Y76506D01*
G01X150894Y76497D02*
Y67167D01*
X145777Y62050D01*
X143550D01*
X142000Y60500D01*
G01X157545Y73450D02*
Y75696D01*
X156019Y77221D01*
X154918Y78322D01*
X150138D01*
X147900Y76084D01*
Y73300D01*
G01X143500Y78800D02*
X146922Y82222D01*
X157778D01*
X161485Y78515D01*
Y73450D01*
G01X151080Y99344D02*
X148892D01*
X147329Y100907D01*
G01X154600Y111200D02*
X152352D01*
X150152Y109000D01*
X147200D01*
G01X163455Y101750D02*
Y104900D01*
X160832Y107523D01*
X160380D01*
X156703Y111200D01*
X154600D01*
G01X147200Y109000D02*
Y112000D01*
G01X157493Y124795D02*
X153705D01*
X153693Y124807D01*
G01X140800Y158900D02*
X143647Y161747D01*
X147018D01*
G01X150800Y162000D02*
X150547Y161747D01*
X147018D01*
G01X150800Y171500D02*
Y168600D01*
X150200Y168000D01*
G01X141500Y167976D02*
Y171150D01*
X142351Y172001D01*
X150299D01*
X150800Y171500D01*
G01D02*
Y172778D01*
X153997Y175975D01*
G01X150500Y176700D02*
X147824D01*
X141500Y183024D01*
G01X163600Y184597D02*
X162800Y183797D01*
Y182200D01*
X158800Y178200D01*
X152000D01*
X150500Y176700D01*
G01X154200Y171500D02*
X154400Y171700D01*
X160000D01*
G01X146980Y200580D02*
Y194720D01*
X147200Y194500D01*
G01X151800Y192000D02*
X149300Y194500D01*
X147200D01*
G01X155200Y195300D02*
X157250D01*
X158950Y193600D01*
X159000D01*
G01X155200Y192000D02*
X157074Y190126D01*
X163226D01*
G01X151800Y195300D02*
X150525Y196575D01*
X150399D01*
X149125Y197849D01*
Y204383D01*
X151125Y206383D01*
Y208975D01*
X150000Y210100D01*
G01X155200Y198300D02*
X161456D01*
X161897Y197859D01*
G01X151800Y198300D02*
X151075Y199025D01*
Y203575D01*
X153075Y205575D01*
Y209575D01*
X153500Y210000D01*
G01X163000Y164800D02*
X166865D01*
X167581Y164084D01*
G01X169485Y183848D02*
X168248D01*
X167700Y183300D01*
Y180400D01*
X164300Y177000D01*
X162900D01*
X161300Y175400D01*
Y173000D01*
X160000Y171700D01*
G01X163000Y168200D02*
Y170900D01*
X163900Y171800D01*
Y174700D01*
G01X173459Y181448D02*
Y179846D01*
X172586Y178973D01*
X169473D01*
X167250Y176750D01*
X165950D01*
X163900Y174700D01*
G01X163600Y184597D02*
X164425Y185422D01*
X169485D01*
G01Y191722D02*
X166678D01*
X164200Y194200D01*
Y195556D01*
X161897Y197859D01*
G01X169485Y190147D02*
X166353D01*
X162900Y193600D01*
X159000D01*
G01X169485Y188572D02*
X164728D01*
X163300Y190000D01*
Y190052D01*
X163226Y190126D01*
G01X171300Y213000D02*
Y209000D01*
G01X171885Y203570D02*
Y208115D01*
X171300Y208700D01*
Y209000D01*
G01X177245Y73450D02*
Y69655D01*
X179800Y67100D01*
Y65700D01*
G01X182500Y63000D02*
X179800Y65700D01*
G01X175275Y73450D02*
Y69725D01*
X176900Y68100D01*
Y67500D01*
G01X181600Y109800D02*
Y109674D01*
X179215Y107289D01*
Y101750D01*
G01X178600Y109800D02*
Y108200D01*
X177245Y106845D01*
Y101750D01*
G01X184600Y109800D02*
X181600D01*
G01X175600D02*
X178600D01*
G01X181700Y213000D02*
Y209900D01*
X181300Y209500D01*
G01X179759Y203570D02*
Y207959D01*
X181300Y209500D01*
G01X193005Y73450D02*
Y69195D01*
X193500Y68700D01*
G01D02*
Y65300D01*
X193100Y64900D01*
G01X191035Y73450D02*
Y69635D01*
X190100Y68700D01*
G01X187095Y101750D02*
Y106095D01*
X187500Y106500D01*
G01X193005Y97155D02*
Y101750D01*
G01X194975D02*
Y99325D01*
X196500Y97800D01*
Y95811D01*
X195989Y95300D01*
G01X207400Y91100D02*
X205260D01*
X198915Y97445D01*
Y101750D01*
G01X189000Y109300D02*
Y108000D01*
X187500Y106500D01*
G01X195000Y172700D02*
Y175228D01*
X193672Y176556D01*
G01X189207Y181448D02*
Y179693D01*
X190987Y177913D01*
X192315D01*
X193672Y176556D01*
G01X200300Y195000D02*
Y194400D01*
X196922Y191022D01*
X194600D01*
X193900Y191722D01*
X191607D01*
G01X213976Y22892D02*
Y35693D01*
X213500Y36169D01*
Y43000D01*
X215000Y44500D01*
G01X210039Y22892D02*
Y38961D01*
X209000Y40000D01*
Y44500D01*
G01X212000Y48300D02*
X212200D01*
X215000Y45500D01*
Y44500D01*
G01X209000Y48300D02*
Y44500D01*
G01Y51700D02*
Y52000D01*
X210800Y53800D01*
X216899D01*
X219899Y56800D01*
G01X205100Y50900D02*
X205900Y51700D01*
X209000D01*
G01X212000D02*
X213500D01*
X216000Y49200D01*
G01D02*
X219375D01*
X223475Y53300D01*
G01X207400Y84500D02*
X203700D01*
X202855Y83655D01*
Y73450D01*
G01X229724Y22892D02*
Y34176D01*
X229655Y34245D01*
Y39155D01*
X230500Y40000D01*
X237500D01*
X242016Y44516D01*
Y47325D01*
G01X235000Y47000D02*
X233000Y45000D01*
X228600D01*
X225994Y42394D01*
Y36806D01*
X225787Y36599D01*
Y22892D01*
G01X229200Y48820D02*
Y48100D01*
X220200Y39100D01*
X219900D01*
G01X221400Y64500D02*
Y58100D01*
X225300Y54200D01*
Y51600D01*
X221800Y48100D01*
G01X226640Y56180D02*
Y59840D01*
X226800Y60000D01*
G01X226640Y56180D02*
Y55360D01*
X228600Y53400D01*
X235700D01*
X236500Y54200D01*
G01X226800Y60000D02*
X228000Y61200D01*
Y64400D01*
X230000Y66400D01*
G01X230875Y106300D02*
Y105125D01*
X239000Y97000D01*
Y89000D01*
X242355Y85645D01*
Y75437D01*
X241375Y74457D01*
Y70625D01*
X242125Y69875D01*
Y55875D01*
X243000Y55000D01*
G01X239500Y50800D02*
X242016Y48284D01*
Y47325D01*
G01X244400Y50600D02*
X246000Y49000D01*
X247500D01*
G01X239500Y54200D02*
X236500D01*
G01Y50800D02*
Y48500D01*
X235000Y47000D01*
G01X246689Y196687D02*
Y191931D01*
X242385Y187627D01*
Y173385D01*
X238900Y169900D01*
Y120900D01*
X236287Y118287D01*
Y106812D01*
X235075Y105600D01*
G01X240100Y191000D02*
X244025Y194925D01*
Y215430D01*
X255550Y226955D01*
Y262550D01*
X257500Y264500D01*
Y266645D01*
G01X253300Y189834D02*
Y194300D01*
X256675Y197675D01*
Y205000D01*
X254175Y207500D01*
X249975D01*
X245975Y211500D01*
Y214622D01*
X257500Y226147D01*
Y261630D01*
X260500Y264630D01*
G01X251758Y83071D02*
X257271D01*
X257800Y83600D01*
G01Y86800D02*
Y83600D01*
G01X265500Y87931D02*
X258931D01*
X257800Y86800D01*
G01X259820Y103454D02*
X260666Y104300D01*
X271200D01*
G01X278811Y121089D02*
X274188D01*
X271777Y123500D01*
X266998D01*
X262600Y127902D01*
Y135666D01*
X265900Y138966D01*
Y141914D01*
X262200Y145614D01*
Y146300D01*
G01X264100Y151400D02*
X262200Y149500D01*
Y146300D01*
G01X261300Y188300D02*
X261700Y187900D01*
Y178748D01*
X266425Y174023D01*
Y172343D01*
X265500Y171418D01*
Y165000D01*
X266320Y164180D01*
G01X277500Y208800D02*
X270527D01*
X263425Y215902D01*
Y219210D01*
X287400Y243185D01*
Y251100D01*
X285525Y252975D01*
Y255300D01*
X287425Y257200D01*
Y261390D01*
X295197Y269162D01*
X306538D01*
X309000Y266700D01*
G01X265425Y260000D02*
Y251943D01*
X263600Y250118D01*
Y239850D01*
G01X266200Y48731D02*
Y48000D01*
X269400Y44800D01*
X269800D01*
G01X277000Y49300D02*
Y46500D01*
X278700Y44800D01*
G01X309000Y114700D02*
Y114104D01*
X298147Y103251D01*
X286705D01*
X280631Y109325D01*
X277125D01*
X272100Y104300D01*
X271200D01*
G01X281475Y116475D02*
Y118425D01*
X278811Y121089D01*
G01X283279Y103321D02*
X279100Y107500D01*
X278500D01*
G01X276600Y128700D02*
X275700D01*
X271860Y132540D01*
X268520D01*
G01X276600Y128700D02*
X277200D01*
X281000Y132500D01*
X283000D01*
G01X279800Y135500D02*
X279400Y135100D01*
X275880D01*
G01X278600Y145900D02*
Y142500D01*
X278000Y141900D01*
G01X265600Y146300D02*
X265900D01*
X267575Y147975D01*
X270325D01*
X272000Y146300D01*
Y145320D01*
G01X282130Y147600D02*
X280430Y149300D01*
X278600D01*
G01D02*
X276000D01*
X274560Y147860D01*
Y145320D01*
G01X274900Y141400D02*
X276900Y139400D01*
X278800D01*
X279700Y138500D01*
G01X276800Y158700D02*
X274298Y156198D01*
X273900D01*
G01X270500Y163200D02*
X267300D01*
X266320Y164180D01*
G01X274000Y182800D02*
X275800D01*
X277400Y181200D01*
G01D02*
X281300Y177300D01*
X282500D01*
G01X268283Y173035D02*
X268400D01*
X269000Y173635D01*
Y175706D01*
X264875Y179831D01*
Y190585D01*
X266140Y191850D01*
G01X271000Y183700D02*
X273100D01*
X274000Y182800D01*
G01Y186200D02*
X273060Y187140D01*
Y189374D01*
G01X280500Y208800D02*
X277500D01*
G01X334700Y174100D02*
X332447Y171847D01*
X327411D01*
X325911Y173347D01*
Y176317D01*
X325048Y177180D01*
X324297D01*
X321417Y180060D01*
Y181135D01*
X320553Y181999D01*
X320244D01*
X318500Y183743D01*
Y185130D01*
X310330Y193300D01*
X303114D01*
X301375Y195039D01*
Y209267D01*
X294142Y216500D01*
X281533D01*
X278808Y219225D01*
X272066D01*
X269500Y216659D01*
G01X265259D02*
X269500D01*
G01X311400Y269200D02*
X309788Y270812D01*
X292569D01*
X292106Y271275D01*
X276320D01*
X265425Y260380D01*
Y260000D01*
G01X327854Y130434D02*
X326918Y129498D01*
Y126727D01*
X325091Y124900D01*
X323322D01*
X318422Y120000D01*
X317663D01*
X312900Y115237D01*
Y113800D01*
X312100Y113000D01*
X310300D01*
X298876Y101576D01*
X285024D01*
X283279Y103321D01*
G01X293200Y110000D02*
X296225Y113025D01*
X297600D01*
G01X338320Y141300D02*
Y140340D01*
X336990Y139010D01*
Y137560D01*
X336083Y136653D01*
X334266D01*
X330543Y132930D01*
X327061D01*
X326358Y132227D01*
X321912D01*
X321286Y132853D01*
X315853D01*
X313825Y130825D01*
X312941D01*
X309716Y127600D01*
X306298D01*
X300950Y122252D01*
Y118124D01*
X297976Y115150D01*
X295350D01*
X293200Y113000D01*
G01X335514Y138220D02*
X334630D01*
X332313Y135903D01*
X328606D01*
X327880Y135177D01*
X325135D01*
X323656Y133698D01*
X321726D01*
X321721Y133703D01*
X315500D01*
X313647Y131850D01*
X311550D01*
X308764Y129064D01*
X306441D01*
X305681Y129824D01*
X303538D01*
X302500Y128786D01*
Y125005D01*
X300100Y122605D01*
Y118477D01*
X297623Y116000D01*
X293200D01*
G01Y119000D02*
X297100D01*
X297500Y118600D01*
G01X293200Y128000D02*
X296064D01*
X296564Y127500D01*
G01X293200Y122000D02*
X294600D01*
X296200Y123600D01*
X297200D01*
G01X291400Y134686D02*
X297614D01*
X298800Y133500D01*
X301000D01*
X306575Y139075D01*
X312875D01*
X315325Y141525D01*
X316254D01*
X317529Y142800D01*
X322050D01*
X322829Y143579D01*
X332761D01*
X332765Y143575D01*
X337817D01*
X341897Y147655D01*
X345015D01*
X346450Y149090D01*
Y149120D01*
G01X286400Y132500D02*
X288586Y134686D01*
X291400D01*
G01X298500Y129500D02*
Y126900D01*
X297400Y125800D01*
X294000D01*
X293200Y125000D01*
G01X279700Y138500D02*
X279800Y138400D01*
Y135500D01*
G01X293200Y151000D02*
X294700Y152500D01*
X297500D01*
X299064Y154064D01*
X299065D01*
G01X293200Y144500D02*
Y141500D01*
G01D02*
X294900Y139800D01*
X301900D01*
X302700Y140600D01*
G01X315900Y156921D02*
X315825Y156996D01*
X305004D01*
X295500Y147492D01*
X293208D01*
X293200Y147500D01*
G01X290200Y151000D02*
Y150500D01*
X293200Y147500D01*
G01X310300Y163300D02*
X310215Y163385D01*
X308856D01*
X307905Y162434D01*
X306557D01*
X304491Y164500D01*
X300349D01*
X297924Y162075D01*
X296575D01*
X295000Y160500D01*
X293700D01*
G01X290300Y164000D02*
Y163900D01*
X293700Y160500D01*
G01Y157500D02*
X297300D01*
G01X293700Y171000D02*
X297700D01*
X301000Y167700D01*
X312330D01*
X316259Y163771D01*
G01X282500Y177300D02*
X286300D01*
X288525Y179525D01*
X295075D01*
X296900Y177700D01*
X309300D01*
X322953Y164047D01*
X327339D01*
X329275Y162111D01*
Y159571D01*
X330300Y158546D01*
G01X298000Y181500D02*
X293700D01*
G01Y174000D02*
X297794D01*
X297797Y173997D01*
G01X293700Y177500D02*
X295078Y176122D01*
X298678D01*
X300000Y174800D01*
Y173366D01*
X302165Y171201D01*
X303639D01*
G01X286500Y184000D02*
X285600D01*
X282950Y181350D01*
G01X290300Y181500D02*
X287800Y184000D01*
X286500D01*
G01X286300Y199500D02*
Y198002D01*
X288500Y195802D01*
G01X284300Y214225D02*
X288076D01*
X289525Y212776D01*
Y210411D01*
X287114Y208000D01*
X286900D01*
G01X280500Y212200D02*
X282525Y214225D01*
X284300D01*
G01X292100Y206000D02*
X294400D01*
X297000Y203400D01*
G01X286900Y204000D02*
Y200100D01*
X286300Y199500D01*
G01X295800Y228000D02*
X295000D01*
X291225Y231775D01*
Y255272D01*
X295814Y259861D01*
X298272D01*
X298486Y260075D01*
X307869D01*
X324525Y276731D01*
Y278575D01*
X321600Y281500D01*
Y282500D01*
G01X325100Y281476D02*
Y280758D01*
X326475Y279383D01*
Y275923D01*
X308677Y258125D01*
X299294D01*
X299080Y257911D01*
X296622D01*
X293175Y254464D01*
Y233625D01*
X295800Y231000D01*
G01X343146Y128473D02*
X343017D01*
X339500Y124956D01*
Y124433D01*
X338442Y123375D01*
X333116D01*
X330890Y121149D01*
Y119312D01*
X330026Y118448D01*
X323972D01*
X322622Y117098D01*
X320808D01*
X316900Y113190D01*
Y110214D01*
X314911Y108225D01*
X309158D01*
X304694Y103761D01*
Y101956D01*
G01D02*
Y101806D01*
X305200Y101300D01*
Y98001D01*
X304074Y96875D01*
X301425D01*
X301300Y97000D01*
G01D02*
X301175Y96875D01*
X296425D01*
X295700Y97600D01*
G01X297600Y113025D02*
X301800Y117225D01*
Y121899D01*
X306651Y126750D01*
X311850D01*
X314300Y129200D01*
G01X332478Y138255D02*
X330976Y136753D01*
X328253D01*
X327609Y136109D01*
X324864D01*
X323303Y134548D01*
X322079D01*
X321712Y134915D01*
X311919D01*
X311404Y134400D01*
X306911D01*
X301600Y129089D01*
Y125308D01*
X299250Y122958D01*
Y120350D01*
X297500Y118600D01*
G01X297200Y123600D02*
X300750Y127150D01*
Y129442D01*
X306558Y135250D01*
X311051D01*
X311566Y135765D01*
X319904D01*
X321637Y137498D01*
X323303D01*
X323842Y136959D01*
X326933D01*
X328202Y138228D01*
X329421D01*
G01X296564Y136311D02*
X299089D01*
X299600Y135800D01*
G01X298500Y129500D02*
X300500Y131500D01*
X301605D01*
X306230Y136125D01*
X310723D01*
X311298Y136700D01*
X319636D01*
X321284Y138348D01*
X326236D01*
X326322Y138434D01*
G01X324588Y150794D02*
X324519Y150725D01*
X321371D01*
X318310Y153786D01*
X313539D01*
X312029Y155296D01*
X305710D01*
X302875Y152461D01*
Y140775D01*
X302700Y140600D01*
G01X297500Y142800D02*
X297982D01*
X298032Y142850D01*
X300700D01*
G01X341390Y153991D02*
X340060Y155321D01*
X334888D01*
X333660Y154093D01*
Y153195D01*
X332796Y152331D01*
X327886D01*
X327199Y151644D01*
X324235D01*
X324166Y151575D01*
X321724D01*
X318663Y154636D01*
X313892D01*
X312382Y156146D01*
X305357D01*
X300600Y151389D01*
Y149400D01*
G01X297500Y146200D02*
X300600Y149300D01*
Y149400D01*
G01X313300Y148000D02*
X309510D01*
X309350Y147840D01*
G01D02*
X309290D01*
X309150Y147700D01*
X304500D01*
G01D02*
Y150400D01*
X305050Y150950D01*
Y151150D01*
G01X307800Y151300D02*
Y152878D01*
X306961Y153717D01*
G01X323000Y153900D02*
X322200D01*
X317054Y159046D01*
X313014D01*
X311779Y160281D01*
X306281D01*
X304371Y158371D01*
Y158304D01*
X300367Y154300D01*
X299301D01*
X299065Y154064D01*
G01X326234Y153969D02*
X324803Y155400D01*
X322545D01*
X318049Y159896D01*
X313367D01*
X312088Y161175D01*
X306613D01*
X305413Y162375D01*
X303492D01*
G01X300700Y157500D02*
Y159583D01*
X303492Y162375D01*
G01X297300Y157500D02*
Y159900D01*
X297000Y160200D01*
G01X305091Y173888D02*
X305957Y174754D01*
X308506D01*
X308559Y174807D01*
G01X298000Y181500D02*
X300800Y178700D01*
X309503D01*
X323306Y164897D01*
X327703D01*
X330900Y161700D01*
G01X297797Y173997D02*
X302944Y168850D01*
X315744D01*
X323478Y161116D01*
Y161111D01*
X324342Y160247D01*
X325253D01*
X328429Y157071D01*
X331771D01*
X333000Y158300D01*
G01X303639Y171201D02*
X303699D01*
X305200Y169700D01*
X316097D01*
X322600Y163197D01*
X326103D01*
X327800Y161500D01*
G01X324029Y166384D02*
X314877Y175536D01*
Y182920D01*
X313367Y184430D01*
X298670D01*
X296600Y186500D01*
Y189100D01*
G01X296700Y193500D02*
Y189200D01*
X296600Y189100D01*
G01X296700Y199500D02*
X297700D01*
X299500Y197700D01*
Y187660D01*
X301000Y186160D01*
X314240D01*
X316577Y183823D01*
Y178471D01*
X318324Y176724D01*
G01X345900Y161700D02*
X344696D01*
X340147Y166249D01*
X326251D01*
X324641Y167859D01*
X323954D01*
X315727Y176086D01*
Y183273D01*
X313690Y185310D01*
X300350D01*
X298621Y187039D01*
Y194579D01*
X296700Y196500D01*
G01X305800Y191000D02*
X311427D01*
X317427Y185000D01*
Y180628D01*
X327058Y170997D01*
X332964D01*
X333925Y170036D01*
Y168989D01*
X334789Y168125D01*
X340677D01*
X344777Y164025D01*
X346865D01*
X347521Y163369D01*
X350230D01*
X351600Y162000D01*
X352000D01*
G01X305800Y191000D02*
X303900D01*
X300500Y194400D01*
Y199900D01*
X297000Y203400D01*
G01X315500Y247300D02*
X313700D01*
X305575Y239175D01*
Y235625D01*
X313260Y227940D01*
Y205325D01*
X312810Y204875D01*
X309900D01*
X309300Y204275D01*
Y203225D01*
X309900Y202625D01*
X312810D01*
X313260Y202175D01*
Y200825D01*
X312810Y200375D01*
X308100D01*
X307500Y199775D01*
Y198725D01*
X308100Y198125D01*
X312810D01*
X313260Y197675D01*
Y193500D01*
G01X303500Y228000D02*
X306494D01*
X308129Y226365D01*
X308435D01*
X309900Y224900D01*
G01X299200Y228000D02*
X303500D01*
G01X299200Y231000D02*
X306500D01*
X309010Y228490D01*
G01D02*
X311525Y225975D01*
Y224226D01*
X310574Y223275D01*
X309226D01*
X307601Y224900D01*
X307300D01*
G01X319000Y247300D02*
Y246000D01*
X316000Y243000D01*
X311946D01*
X307375Y238429D01*
Y236525D01*
X315300Y228600D01*
Y210900D01*
X317060Y209140D01*
Y202500D01*
G01X336023Y22892D02*
Y39500D01*
X334875Y40648D01*
Y42025D01*
X333900Y43000D01*
X326000D01*
X320400Y48600D01*
G01X335000Y46575D02*
X326201D01*
X324176Y48600D01*
G01X322075Y100650D02*
Y101425D01*
X320500Y103000D01*
G01X321500Y98200D02*
Y100075D01*
X322075Y100650D01*
G01X324500Y98200D02*
Y100050D01*
X325081Y100631D01*
G01X327026Y102576D02*
X325081Y100631D01*
G01X321500Y94800D02*
Y94399D01*
X319520Y92419D01*
G01X324500Y94800D02*
X323120Y93420D01*
Y92400D01*
G01X325100Y106500D02*
X321700D01*
G01X325100D02*
X331500D01*
X332807Y105193D01*
X334807D01*
X336300Y103700D01*
G01X335303Y135178D02*
X333750Y133625D01*
X332591D01*
X331036Y132070D01*
X327404D01*
X326711Y131377D01*
X321559D01*
X320933Y132003D01*
X317103D01*
X314300Y129200D01*
G01X320600Y126100D02*
X324169D01*
X325418Y127349D01*
G01X315000Y144550D02*
X321282D01*
X322061Y145329D01*
X324732D01*
X326986Y147583D01*
X327954D01*
X328067Y147696D01*
X331724D01*
X333470Y145950D01*
X333750D01*
G01X311300Y144200D02*
X311650Y144550D01*
X315000D01*
G01X320300Y146700D02*
X322121Y148521D01*
X323912D01*
X324589Y147844D01*
X326044D01*
X327306Y149106D01*
X327390D01*
G01X316700Y148000D02*
X318000Y146700D01*
X320300D01*
G01X314800Y151661D02*
X315632Y150829D01*
X320013D01*
X321142Y149700D01*
X324819D01*
X325200Y149319D01*
G01X311200Y151300D02*
X311561Y151661D01*
X314800D01*
G01X319704Y162804D02*
X317226D01*
X316259Y163771D01*
G01X341400Y156700D02*
X341100Y156400D01*
X334764D01*
X333685Y155321D01*
X327685D01*
X326706Y156300D01*
X322848D01*
X318402Y160746D01*
X314754D01*
X312200Y163300D01*
X310300D01*
G01X315900Y156921D02*
X317581D01*
X322077Y152425D01*
X323813D01*
X323882Y152494D01*
X326846D01*
X328182Y153830D01*
X329161D01*
G01X317060Y202500D02*
Y197881D01*
X318319Y196622D01*
Y189981D01*
X324933Y183367D01*
Y181681D01*
X327189Y179425D01*
X334912D01*
X336915Y177423D01*
G01X310579Y182800D02*
Y182103D01*
X312217Y180465D01*
Y179443D01*
X312070Y179296D01*
G01X348700Y161700D02*
X347987D01*
X346512Y163175D01*
X344424D01*
X340500Y167099D01*
X326604D01*
X323241Y170462D01*
X322554D01*
X321690Y171326D01*
Y173358D01*
X318324Y176724D01*
G01X319423Y228577D02*
X321200Y226800D01*
Y213800D01*
X321800Y213200D01*
X325400D01*
X326000Y212600D01*
Y205800D01*
X323100Y202900D01*
Y201300D01*
X324975Y199425D01*
Y195100D01*
X324375Y194500D01*
X322081D01*
X321481Y193900D01*
Y188338D01*
X323659Y186160D01*
X327400D01*
X328000Y185560D01*
Y182892D01*
X327400Y182292D01*
X326408D01*
G01X313260Y193500D02*
Y193340D01*
X323121Y183479D01*
Y182913D01*
G01X322500Y247300D02*
Y240700D01*
X321900Y240100D01*
X312525D01*
X311925Y239500D01*
Y236075D01*
X319423Y228577D01*
G01X322192Y234136D02*
Y231533D01*
X323725Y230000D01*
Y217461D01*
X330186Y211000D01*
X330703Y210466D01*
Y199120D01*
X329617Y198034D01*
X329361D01*
X328497Y197170D01*
Y192947D01*
X329313Y192131D01*
Y188000D01*
G01X322192Y234136D02*
X324300Y236244D01*
Y242700D01*
X326500Y244900D01*
G01X322500Y250700D02*
Y254200D01*
G01Y257300D02*
Y254200D01*
G01X319000Y250700D02*
Y254200D01*
G01Y257300D02*
Y254200D01*
G01X315500Y250700D02*
Y254100D01*
G01Y257300D02*
Y254100D01*
G01X460400Y275200D02*
Y278284D01*
X457208Y281476D01*
X325100D01*
G01Y281500D02*
Y281476D01*
G01X464000Y275200D02*
Y277442D01*
X458016Y283426D01*
X322526D01*
X321600Y282500D01*
G01X472400Y275100D02*
X460174Y287326D01*
X316426D01*
X311300Y282200D01*
Y277800D01*
G01X469000Y275200D02*
X458824Y285376D01*
X317276D01*
X313824Y281924D01*
Y280255D01*
G01X347835Y22892D02*
Y34835D01*
X348900Y35900D01*
Y43750D01*
X345200Y47450D01*
X337575D01*
X336700Y46575D01*
X335000D01*
G01X336300Y103700D02*
X338210D01*
X342050Y107540D01*
Y109179D01*
X343957Y111086D01*
X344605D01*
X348075Y114556D01*
Y121711D01*
X346311Y123475D01*
X345719D01*
X344475Y124719D01*
Y127425D01*
X346495Y129445D01*
Y130000D01*
G01X339547Y108043D02*
X340924Y109420D01*
Y109915D01*
X343570Y112561D01*
G01X336000Y107300D02*
X338804D01*
X339547Y108043D01*
G01X336000Y110700D02*
Y111903D01*
X337897Y113800D01*
X338400D01*
G01D02*
X339969D01*
X341200Y112569D01*
G01X328100Y115500D02*
X329165Y116565D01*
X334665D01*
X336300Y118200D01*
G01X343000Y121100D02*
X340113D01*
X338768Y119755D01*
G01X336300Y118200D02*
X337855Y119755D01*
X338768D01*
G01X343000Y115900D02*
X339623D01*
X338768Y116755D01*
G01X330500Y109000D02*
X330446D01*
X328100Y111346D01*
Y112100D01*
G01X338768Y116755D02*
X338255D01*
X330500Y109000D01*
G01X333800Y125000D02*
Y127501D01*
X333977Y127678D01*
G01X334400Y131000D02*
Y128101D01*
X333977Y127678D01*
G01X329523Y128134D02*
X333521D01*
X333977Y127678D01*
G01X337200Y125000D02*
Y127300D01*
X336900Y127600D01*
G01X343890Y131430D02*
X340030D01*
X339600Y131000D01*
G01X336900Y127600D02*
Y128300D01*
X339600Y131000D01*
G01X330163Y142008D02*
X332502D01*
X333270Y141240D01*
G01X344500Y135900D02*
X342817Y137583D01*
Y138890D01*
X339491Y142216D01*
Y143163D01*
G01X338360Y150400D02*
X337385Y149425D01*
X334525D01*
X333800Y148700D01*
G01D02*
Y148200D01*
X335870Y146130D01*
X336920D01*
G01X339784Y161847D02*
X339150Y161213D01*
Y159000D01*
G01X342750Y159200D02*
X342550Y159000D01*
X339150D01*
G01X336500Y183000D02*
X334600D01*
X332500Y180900D01*
G01X330280D02*
X330300Y180920D01*
Y183510D01*
X330155Y183655D01*
G01X342200Y200100D02*
X339575Y197475D01*
Y180075D01*
X338400Y178900D01*
Y175000D01*
X339300Y174100D01*
G01X334500Y207500D02*
Y206600D01*
X336500Y204600D01*
G01X339500Y247300D02*
Y245274D01*
X335663Y241437D01*
Y222552D01*
X333411Y220300D01*
Y212989D01*
X334500Y211900D01*
Y207500D01*
G01X330500Y240800D02*
X331400D01*
X335500Y244900D01*
G01D02*
X331775Y248625D01*
Y252075D01*
X333700Y254000D01*
G01X326500Y244900D02*
X331500D01*
G01X333500Y250100D02*
X336700D01*
X339500Y247300D01*
G01X354800Y50200D02*
Y47700D01*
X356432Y46068D01*
Y43657D01*
G01X363500Y54700D02*
X359300D01*
X354800Y50200D01*
G01X344840Y104340D02*
Y107760D01*
X345040Y107960D01*
G01X341840Y104340D02*
X342900Y105400D01*
Y108826D01*
X344310Y110236D01*
X344958D01*
X348925Y114203D01*
Y122278D01*
X347371Y123832D01*
Y124829D01*
X346600Y125600D01*
G01X345040Y107960D02*
Y109115D01*
X349775Y113850D01*
Y122631D01*
X349149Y123257D01*
Y124141D01*
G01D02*
X351075Y126067D01*
Y128225D01*
X350000Y129300D01*
G01X346600Y125600D02*
Y127340D01*
X347970Y128710D01*
Y133150D01*
X347641Y133479D01*
G01X347500Y135900D02*
Y133620D01*
X347641Y133479D01*
G01X353000Y152800D02*
X352292D01*
X351092Y151600D01*
X349090D01*
X347480Y153210D01*
X347476D01*
G01X344500Y139300D02*
Y141700D01*
G01X342300Y143400D02*
X342800D01*
X344500Y141700D01*
G01X355400Y152900D02*
X355300Y152800D01*
X353000D01*
G01X351600Y164300D02*
X354201D01*
X354899Y164998D01*
G01X356000Y168600D02*
Y166099D01*
X354899Y164998D01*
G01X350700Y155600D02*
Y158100D01*
X349400Y159400D01*
G01X346150Y159200D02*
Y157569D01*
X346944Y156775D01*
G01X345500Y166500D02*
X346776D01*
X348432Y164844D01*
G01X344600Y173066D02*
X345866Y171800D01*
X349500D01*
G01D02*
Y171700D01*
X351600Y169600D01*
G01X342692Y177534D02*
X342475Y177317D01*
Y172185D01*
X343719Y170941D01*
X344777D01*
X346218Y169500D01*
X347500D01*
G01X342692Y177534D02*
Y179608D01*
X341300Y181000D01*
G01X351000Y180300D02*
X348000D01*
G01D02*
X347200Y179500D01*
Y174300D01*
G01X358996Y203763D02*
X354500D01*
G01X423600Y246700D02*
X421700Y248600D01*
X417116D01*
X408091Y239575D01*
X408075D01*
X402825Y234325D01*
X379125D01*
X363930Y219130D01*
Y209388D01*
X360930Y206388D01*
X348488D01*
X342200Y200100D01*
G01X359646Y22892D02*
Y50000D01*
G01X371457Y22892D02*
Y37642D01*
G01X367520Y22892D02*
Y37642D01*
G01X363500Y51300D02*
X360800D01*
X359646Y50146D01*
Y50000D01*
G01X361396Y199563D02*
Y197409D01*
X359782Y195795D01*
Y190089D01*
X360646Y189225D01*
X362179D01*
X364600Y186804D01*
Y186138D01*
G01X364792Y188743D02*
X363420Y190115D01*
Y195820D01*
X363600Y196000D01*
G01X364796Y199563D02*
Y197196D01*
X363600Y196000D01*
G01X358996Y203763D02*
X361396Y201363D01*
Y199563D01*
G01X364196Y203763D02*
X364796Y203163D01*
Y199563D01*
G01X384921Y50782D02*
Y47379D01*
X385300Y47000D01*
G01X374200Y149494D02*
X374606D01*
X377400Y146700D01*
X377500D01*
G01X372500Y151700D02*
Y151194D01*
X374200Y149494D01*
G01X396000Y210700D02*
X395700Y211000D01*
Y213600D01*
G01X396000Y203700D02*
X393800Y205900D01*
Y227500D01*
G01X397200D02*
X397800Y226900D01*
Y222600D01*
G01D02*
Y215700D01*
X395700Y213600D01*
G01X430200Y248400D02*
X427969D01*
X422825Y243256D01*
Y243236D01*
X410489Y230900D01*
X397200D01*
X393800Y227500D01*
G01X402820Y54500D02*
Y53180D01*
X404820Y51180D01*
X410524D01*
X417000Y44704D01*
Y23385D01*
X423500Y16885D01*
G01X402820Y59440D02*
Y54500D01*
G01X423000Y43900D02*
X414790Y52110D01*
G01D02*
X413700Y53200D01*
X409100D01*
X406800Y55500D01*
G01D02*
Y59200D01*
X404000Y62000D01*
X402820D01*
G01X414500Y60800D02*
X424825Y50475D01*
Y42725D01*
X422986Y40886D01*
Y40350D01*
G01X410180Y64560D02*
X410740D01*
X414500Y60800D01*
G01X413100Y121800D02*
X415539Y124239D01*
X429523D01*
X430000Y123763D01*
X433000D01*
G01X412462Y126300D02*
Y128738D01*
X411500Y129700D01*
G01X410000Y126763D02*
X410649Y126114D01*
X412276D01*
X412462Y126300D01*
G01X407700Y208000D02*
X409700Y206000D01*
X410700D01*
X412000Y204700D01*
Y200200D01*
X410900Y199100D01*
Y194000D01*
X412200Y192700D01*
Y192600D01*
G01X412100Y190400D02*
X412200D01*
X414000Y192200D01*
Y197213D01*
X414075Y197288D01*
Y199025D01*
X413000Y200100D01*
Y205415D01*
X410700Y207715D01*
Y208000D01*
G01X419565Y233465D02*
X416865D01*
X410000Y226600D01*
Y214500D01*
X407700Y212200D01*
Y208000D01*
G01X428272Y237872D02*
X427672D01*
X413850Y224050D01*
Y214200D01*
X410700Y211050D01*
Y208000D01*
G01X621100Y124900D02*
X613295Y117095D01*
X545331D01*
X543281Y115045D01*
X479779D01*
X455800Y91066D01*
Y63092D01*
X433975Y41267D01*
Y28999D01*
X431825Y26849D01*
Y26602D01*
X427431Y22208D01*
X424543D01*
G01X487000Y138400D02*
Y124600D01*
X454150Y91750D01*
Y65150D01*
X432325Y43325D01*
Y29683D01*
X430000Y27358D01*
G01X434000Y50800D02*
X429025Y45825D01*
Y39289D01*
X424536Y34800D01*
G01X439000Y54000D02*
Y52500D01*
X430675Y44175D01*
Y37414D01*
X428175Y34914D01*
Y32583D01*
X430000Y30758D01*
G01X440800Y127063D02*
X440263Y126526D01*
X435763D01*
X433000Y123763D01*
G01X426600Y244450D02*
Y240500D01*
X419565Y233465D01*
G01X430000Y244450D02*
Y239600D01*
X428272Y237872D01*
G01X714370Y278740D02*
Y284560D01*
X711905Y287025D01*
X487025D01*
X471030Y271030D01*
X468273D01*
X466970Y269727D01*
Y268270D01*
X461100Y262400D01*
Y251391D01*
X458109Y248400D01*
X430200D01*
G01X434900Y6925D02*
X438025Y3800D01*
X453800D01*
X467500Y17500D01*
X468880D01*
G01X441281Y17025D02*
X442206Y16100D01*
X452749D01*
X459195Y22546D01*
Y24969D01*
X467000Y32774D01*
Y88000D01*
X473123Y94123D01*
X504209D01*
X507075Y91257D01*
Y84782D01*
X512782Y79075D01*
X636568D01*
X644648Y87155D01*
Y104352D01*
X641600Y107400D01*
X638000D01*
G01X446100Y18700D02*
X447985Y20585D01*
Y22285D01*
X449308Y23608D01*
Y53842D01*
X457750Y62284D01*
Y89923D01*
X480922Y113095D01*
X613206D01*
X629794Y129683D01*
X705022D01*
X713675Y138336D01*
Y142625D01*
X701000Y155300D01*
Y165800D01*
G01X433500Y24200D02*
Y26141D01*
X435625Y28266D01*
Y30425D01*
X436100Y30900D01*
G01X444060Y24820D02*
X442180D01*
X436100Y30900D01*
G01X438940Y32180D02*
Y31130D01*
X441390Y28680D01*
G01X439300Y39600D02*
X437206D01*
X436106Y38500D01*
Y34506D01*
G01X439300Y39600D02*
X440300Y38600D01*
Y36000D01*
G01D02*
X441500Y34800D01*
Y32180D01*
G01X439000Y54000D02*
Y56172D01*
X452500Y69672D01*
Y92600D01*
X484775Y124875D01*
Y140775D01*
X497425Y153425D01*
Y185341D01*
X505684Y193600D01*
X525200D01*
X527300Y191500D01*
G01X438500Y279000D02*
X456300D01*
X458450Y276850D01*
Y274391D01*
X460041Y272800D01*
X466500D01*
G01X450200Y9800D02*
X455360D01*
X460500Y14940D01*
X461520D01*
G01X502500Y6200D02*
X471784D01*
X470075Y7909D01*
Y11575D01*
X474500Y16000D01*
Y27256D01*
X472256Y29500D01*
G01X498500Y88995D02*
X497758Y88253D01*
X475253D01*
X472256Y85256D01*
Y29500D01*
G01X472000Y258200D02*
Y258900D01*
X479000Y265900D01*
G01X468500Y258200D02*
Y258900D01*
X475500Y265900D01*
G01X501772Y278740D02*
Y273772D01*
X499500Y271500D01*
X490000D01*
X486900Y274600D01*
X477700D01*
X475500Y272400D01*
G01D02*
X472100Y269000D01*
X469390D01*
X469195Y268805D01*
G01X504134Y278740D02*
Y273376D01*
X500258Y269500D01*
X489242D01*
X486342Y272400D01*
X479000D01*
G01Y265900D02*
Y269000D01*
G01X475500Y265900D02*
Y269000D01*
G01X527300Y188500D02*
X526125D01*
X523000Y191625D01*
X506043D01*
X499075Y184657D01*
Y152575D01*
X487000Y140500D01*
Y138400D01*
G01X482400Y266200D02*
X483750Y267550D01*
X501550D01*
X506496Y272496D01*
Y272500D01*
G01X509000Y101200D02*
X510300D01*
X513300Y98200D01*
X513700D01*
X515000Y96900D01*
G01X507677Y246456D02*
Y243738D01*
X509260Y242155D01*
X520545D01*
X525000Y237700D01*
G01X502953Y246456D02*
Y242547D01*
X507800Y237700D01*
X510000D01*
G01X520000Y234300D02*
X516600Y237700D01*
X510000D01*
G01X506496Y278740D02*
Y272500D01*
G01X518902Y88987D02*
Y95398D01*
X517300Y97000D01*
Y101800D01*
X517000Y102100D01*
G01X516500Y92600D02*
Y89996D01*
X515502Y88998D01*
G01X522800Y93000D02*
Y90330D01*
X522280Y89810D01*
G01X513000Y102100D02*
Y107000D01*
X516000Y110000D01*
X517000D01*
G01X520800Y107500D02*
Y105900D01*
X517000Y102100D01*
G01X515000Y96900D02*
X516500Y95400D01*
Y92600D01*
G01X521000Y96500D02*
X522800Y94700D01*
Y93000D01*
G01X520800Y110500D02*
X520300Y110000D01*
X517000D01*
G01X536500Y231500D02*
X535500D01*
X529300Y237700D01*
X525000D01*
G01X518500Y230500D02*
X520000Y232000D01*
Y234300D01*
G01X538300Y15200D02*
X539539Y13961D01*
Y6684D01*
X539567Y6656D01*
G01X528985Y89975D02*
X526200Y92760D01*
Y93000D01*
G01D02*
Y96600D01*
G01X536400Y119500D02*
Y121258D01*
X548642Y133500D01*
X591000D01*
X596657Y139157D01*
X702257D01*
X703000Y139900D01*
G01X545800Y119500D02*
X541000D01*
G01X533000D02*
X534825Y117675D01*
X539175D01*
X541000Y119500D01*
G01X534750Y183600D02*
Y183700D01*
X534700Y183750D01*
Y187450D01*
G01X530700Y188500D02*
X533650D01*
X534700Y187450D01*
G01X541550Y183550D02*
Y183700D01*
X541500Y183750D01*
Y187100D01*
X541100Y187500D01*
G01X530700Y191500D02*
X537100D01*
X541100Y187500D01*
G01X538500Y235300D02*
Y233000D01*
X537000Y231500D01*
X536500D01*
G01X549200Y119500D02*
X554400Y124700D01*
X588600D01*
G01X553800Y179000D02*
Y181554D01*
X551754Y183600D01*
G01X626100Y186400D02*
X617769D01*
X610044Y194125D01*
X597309D01*
X596309Y193125D01*
X571030D01*
X570630Y192725D01*
X563016D01*
X555500Y185209D01*
Y183500D01*
G01X551300Y187500D02*
Y184054D01*
X551754Y183600D01*
G01X634600Y189300D02*
X617628D01*
X611853Y195075D01*
X570222D01*
X569822Y194675D01*
X561875D01*
X554700Y187500D01*
G01X548300Y209700D02*
X552178Y205822D01*
G01D02*
X553925Y204075D01*
X595575D01*
X599200Y207700D01*
X601200D01*
G01X573500Y178700D02*
Y179267D01*
X569467Y183300D01*
X569395D01*
G01X570200Y176000D02*
X570800D01*
X573500Y178700D01*
G01X570200Y179000D02*
X566897Y182303D01*
Y183405D01*
G01X607500Y188300D02*
X607425Y188375D01*
X598595D01*
X596450Y188529D01*
X596151Y188550D01*
X595500Y189200D01*
X595250Y189450D01*
X591135D01*
X589623Y187938D01*
X575080D01*
X571991Y184849D01*
X570872D01*
X569400Y183377D01*
Y183305D01*
X569395Y183300D01*
G01X561900Y183600D02*
Y184100D01*
X560300Y185700D01*
Y187000D01*
G01X570300D02*
Y186808D01*
X566897Y183405D01*
G01X570300Y190000D02*
X573500D01*
X573600Y190100D01*
G01X576700Y92500D02*
Y91000D01*
X575000Y89300D01*
Y89100D01*
G01X576700Y96100D02*
Y92500D01*
G01X609345Y190100D02*
Y192750D01*
X608995Y193100D01*
X606060D01*
X605710Y192750D01*
Y189650D01*
X605385Y189325D01*
X603785D01*
X603460Y189650D01*
Y192750D01*
X603110Y193100D01*
X601635D01*
X601285Y192750D01*
Y189950D01*
X600935Y189600D01*
X597850D01*
X597500Y189950D01*
Y190825D01*
X597150Y191175D01*
X594860D01*
X594085Y190400D01*
X593060D01*
X592285Y191175D01*
X589661D01*
X589211Y190725D01*
Y189150D01*
X588949Y188888D01*
X587223D01*
X586961Y189150D01*
Y190725D01*
X586511Y191175D01*
X585161D01*
X584711Y190725D01*
Y189250D01*
X584361Y188900D01*
X582811D01*
X582461Y189250D01*
Y190725D01*
X582011Y191175D01*
X580061D01*
X579611Y190725D01*
Y189338D01*
X579161Y188888D01*
X577811D01*
X577361Y189338D01*
Y190725D01*
X576911Y191175D01*
X574675D01*
X573600Y190100D01*
G01X576295Y183400D02*
X578933Y186038D01*
X589866D01*
X589904Y186000D01*
X602423D01*
X607523Y180900D01*
X634138D01*
X637408Y177630D01*
X678130D01*
X679871Y179371D01*
G01X591850Y187725D02*
X591113Y186988D01*
X576533D01*
X572845Y183300D01*
G01X666446Y202037D02*
X666158Y202325D01*
X660357D01*
X659907Y202775D01*
Y203750D01*
X659457Y204200D01*
X658107D01*
X657657Y203750D01*
Y202775D01*
X657207Y202325D01*
X655257D01*
X654807Y202775D01*
Y203900D01*
X654307Y204400D01*
X653057D01*
X652557Y203900D01*
Y202775D01*
X652107Y202325D01*
X650757D01*
X650307Y202775D01*
Y203900D01*
X649807Y204400D01*
X648557D01*
X648057Y203900D01*
Y202775D01*
X647607Y202325D01*
X646257D01*
X645807Y202775D01*
Y203900D01*
X645307Y204400D01*
X644057D01*
X643557Y203900D01*
Y202775D01*
X643107Y202325D01*
X641757D01*
X641307Y202775D01*
Y204000D01*
X640807Y204500D01*
X639557D01*
X639057Y204000D01*
Y202775D01*
X638607Y202325D01*
X637257D01*
X636807Y202775D01*
Y204000D01*
X636307Y204500D01*
X635057D01*
X634557Y204000D01*
Y202775D01*
X634107Y202325D01*
X632757D01*
X632307Y202775D01*
Y204000D01*
X631807Y204500D01*
X630557D01*
X630057Y204000D01*
Y202775D01*
X629607Y202325D01*
X627657D01*
X626807Y201475D01*
X621744D01*
X615219Y208000D01*
X603659D01*
X601322Y210337D01*
X583437D01*
X580350Y207250D01*
G01X591363Y208387D02*
X584987D01*
X583800Y207200D01*
G01X699858Y131908D02*
X595808D01*
X588600Y124700D01*
G01X593475Y183275D02*
Y183217D01*
X615192Y161500D01*
X641000D01*
G01X612000Y172250D02*
X601750Y182500D01*
G01X602650Y177250D02*
X609875Y170025D01*
X684072D01*
X689547Y175500D01*
G01X599150Y180300D02*
X602200Y177250D01*
X602650D01*
G01X594350Y187725D02*
X602633Y187134D01*
X605383Y184384D01*
X609643Y183771D01*
X624500Y183000D01*
X637338Y183738D01*
X642761D01*
X670382Y180685D01*
X672055Y180500D01*
X673100Y179455D01*
G01X602800Y203225D02*
X603070Y202955D01*
X613096D01*
X622126Y193925D01*
X650322D01*
X655616Y188631D01*
X673801D01*
X674395Y189225D01*
X687456D01*
X691498Y185183D01*
X692100Y184582D01*
Y179200D01*
X694000Y177300D01*
Y175000D01*
G01X591363Y208387D02*
X593753D01*
X594965Y207175D01*
G01X612000Y172250D02*
X612275Y171975D01*
X682475D01*
X689400Y178900D01*
G01X642600Y186400D02*
X626100D01*
G01X650500Y155000D02*
X644000Y161500D01*
X641000D01*
G01X646000Y186400D02*
X643100Y189300D01*
X634600D01*
G01X660397Y191100D02*
Y191125D01*
X657722Y193800D01*
G01X687456Y183944D02*
X684444D01*
X679871Y179371D01*
G01X694000Y169100D02*
Y175000D01*
G01X698000Y169200D02*
X694100D01*
X694000Y169100D01*
G01X699858Y131908D02*
X704489D01*
X711725Y139144D01*
Y141275D01*
X709500Y143500D01*
G01X709900Y139900D02*
X703000D01*
G01X698000Y169200D02*
X701000D01*
G01X718847Y143500D02*
Y143553D01*
X718200Y144200D01*
Y147000D01*
G01X718300Y159300D02*
Y155978D01*
X718825Y155453D01*
G01X715900Y270000D02*
X715112Y270788D01*
Y274013D01*
X714370Y274756D01*
Y278740D01*
G01X738200Y46507D02*
X741500D01*
G01X746260Y38940D02*
Y41883D01*
X741636Y46507D01*
X741500D01*
G01X745000Y23000D02*
X747000Y21000D01*
Y15950D01*
X752165Y10785D01*
Y6656D01*
G01X744900Y20500D02*
Y16278D01*
X749803Y11375D01*
Y6656D01*
G01X747441D02*
Y12534D01*
X743325Y16650D01*
Y25525D01*
X747441Y29641D01*
Y33007D01*
G01X750984Y38940D02*
Y43023D01*
X748200Y45807D01*
Y46507D01*
G01X748100Y50007D02*
Y46607D01*
X748200Y46507D01*
G01X775000Y16700D02*
Y16000D01*
X776125Y14875D01*
X780760D01*
X784369Y18484D01*
G01X786500Y13500D02*
Y16353D01*
X784369Y18484D01*
G01X778000Y16700D02*
X778700D01*
X782900Y20900D01*
X786600D01*
X790500Y17000D01*
Y14500D01*
G01X778000Y20100D02*
Y28007D01*
X779825Y29832D01*
Y32063D01*
X778756Y33132D01*
X776325D01*
X774500Y31307D01*
G01X775000Y20100D02*
Y28307D01*
X778000Y31307D01*
G01X790500Y14500D02*
Y11000D01*
G54D30*
X58500Y191000D03*
X61500D03*
X79500Y51500D03*
X67500Y191000D03*
X64500D03*
X68000Y238000D03*
X82500Y51500D03*
X88500D03*
X85500D03*
X85200Y242000D03*
X103250Y51500D03*
X100250D03*
X105500Y195000D03*
X119000Y51500D03*
X116000D03*
X134800D03*
X131800D03*
X132700Y189600D03*
X150515Y51500D03*
X147515D03*
X166263D03*
X163263D03*
X160100Y187000D03*
X182000Y51500D03*
X179000D03*
X178000Y167500D03*
X201500Y68500D03*
X204500D03*
X237000Y60300D03*
X268000Y55000D03*
X271000D03*
X275500Y244500D03*
X272500D03*
X290000Y55000D03*
X287000D03*
X286100Y80700D03*
X305000Y54500D03*
X308000D03*
X310500Y63500D03*
X304500Y222000D03*
X302000Y245100D03*
X305000D03*
X316000Y54500D03*
X319000D03*
X334000Y58500D03*
X354000Y66000D03*
X353000Y143500D03*
X364500Y131500D03*
X370300Y134500D03*
X365000Y149500D03*
X359000Y143000D03*
Y177000D03*
X377500Y134500D03*
X374500D03*
X386500Y171500D03*
X378220Y173540D03*
X395500Y78000D03*
X392000D03*
X393496Y109063D03*
X389500Y159263D03*
X390000Y165100D03*
Y171500D03*
X398000Y256000D03*
X410000Y109063D03*
X407000D03*
X416000D03*
X413000D03*
X406000Y266500D03*
X422000Y109063D03*
X419000D03*
X421142Y184024D03*
X436000Y110563D03*
X434900Y149500D03*
X441000Y143000D03*
X601100Y236500D03*
X617800Y236400D03*
X613200Y236100D03*
X610200D03*
X620800Y236400D03*
X623800D03*
X744500Y239000D03*
G54D21*
X23000Y138500D03*
X61000Y251500D03*
Y254500D03*
Y261700D03*
Y264800D03*
X72100Y241700D03*
X122500Y175000D03*
X129000Y172000D03*
X150500Y168000D03*
X257800Y76200D03*
X269000Y126300D03*
X278400Y153200D03*
X280000Y138500D03*
X326000Y85000D03*
X315500Y88300D03*
X353650Y131700D03*
Y134700D03*
X367000Y103000D03*
Y100000D03*
Y106000D03*
X362100Y121500D03*
X363500Y118500D03*
X371000Y146000D03*
X358400Y151900D03*
X376500Y77500D03*
X380500Y139500D03*
X383500Y152500D03*
X373280Y184610D03*
X400000Y131063D03*
X401542Y169124D03*
X405000Y134063D03*
X405012Y140238D03*
X405000Y137063D03*
X405200Y176063D03*
Y173063D03*
X411000Y208000D03*
X434000Y188500D03*
X441000Y114563D03*
Y111563D03*
X434500Y200063D03*
X463500Y24000D03*
X510000Y50507D03*
X512000Y126000D03*
Y122500D03*
X525000Y125500D03*
X541500Y179000D03*
X543000Y96000D03*
Y93000D03*
X567000Y92500D03*
X588000Y179000D03*
X596000Y142000D03*
X641500Y285000D03*
X719000Y116500D03*
X733200Y111900D03*
X733300Y108700D03*
X734900Y130900D03*
X734800Y137100D03*
X802000Y121500D03*
Y125000D03*
X802200Y155300D03*
X802900Y166700D03*
G54D12*
G01X80118Y22892D02*
Y35654D01*
X82211Y37747D01*
G01X76181Y22892D02*
Y35461D01*
X74000Y37642D01*
G01X91929Y22892D02*
Y35782D01*
X89862Y37849D01*
G01X95866Y22892D02*
Y35008D01*
X98500Y37642D01*
G01X107677Y22892D02*
Y35809D01*
X105794Y37692D01*
G01X111614Y22892D02*
Y35674D01*
X113605Y37665D01*
G01X123425Y22892D02*
Y35717D01*
X121500Y37642D01*
G01X127362Y22892D02*
Y35678D01*
X129336Y37652D01*
G01X139173Y22892D02*
Y35819D01*
X139123D01*
X137300Y37642D01*
G01X154921Y22892D02*
Y35820D01*
X153088Y37653D01*
G01X143110Y22892D02*
Y35682D01*
X145070Y37642D01*
G01X158858Y22892D02*
Y35664D01*
X160898Y37704D01*
G01X170669Y22892D02*
Y35819D01*
X168799Y37689D01*
X168791D01*
G01X174606Y22892D02*
Y35665D01*
X176640Y37699D01*
G01X186417Y22892D02*
Y35783D01*
X184500Y37700D01*
G01X190354Y22892D02*
Y35596D01*
X192400Y37642D01*
G01X202165Y22892D02*
Y35777D01*
X200300Y37642D01*
G01X217913Y22892D02*
Y35821D01*
X216085Y37649D01*
G01X206102Y22892D02*
Y36144D01*
X207600Y37642D01*
G01X233661Y22892D02*
Y35812D01*
X231782Y37691D01*
X231780D01*
G01X221850Y22892D02*
Y35668D01*
X223868Y37686D01*
G01X249409Y22892D02*
Y35733D01*
X247500Y37642D01*
G01X237598Y22892D02*
Y35672D01*
X239599Y37673D01*
G01X253346Y22892D02*
Y35988D01*
X255000Y37642D01*
G01X265157Y22892D02*
Y35643D01*
X263100Y37700D01*
G01X269094Y22892D02*
Y35894D01*
X271000Y37800D01*
G01X280905Y22892D02*
Y35895D01*
X279100Y37700D01*
X278800D01*
G01X284842Y22892D02*
Y35742D01*
X286900Y37800D01*
G01X296653Y22892D02*
Y35819D01*
X294572Y37900D01*
X294500D01*
G01X300590Y22892D02*
X300661Y22963D01*
Y36061D01*
X302400Y37800D01*
X302600D01*
G01X312401Y22892D02*
Y35819D01*
X310348Y37872D01*
Y37900D01*
G01X316338Y22892D02*
Y35990D01*
X318048Y37700D01*
G01X328149Y22892D02*
Y35819D01*
X326096Y37872D01*
Y37900D01*
G01X332086Y22892D02*
Y36386D01*
X333700Y38000D01*
G01X385500Y41500D02*
X387205Y39795D01*
Y22892D01*
G01X383268D02*
Y36768D01*
G01X379331Y37431D02*
Y22892D01*
G01X375394D02*
Y37194D01*
X375400Y37200D01*
Y37700D01*
G01X380000Y38100D02*
X379331Y37431D01*
X14000Y104500D03*
X14400Y98000D03*
X14000Y109500D03*
X15400Y118000D03*
X10900D03*
X13000Y137000D03*
X15500Y122800D03*
X15000Y127500D03*
X11000Y122800D03*
X10500Y127500D03*
X13000Y141500D03*
X13100Y150600D03*
X13000Y146000D03*
X11500Y163700D03*
Y159000D03*
X7000Y163700D03*
Y159000D03*
X14500Y198000D03*
X4500Y228900D03*
X4600Y223100D03*
X4500Y234800D03*
X4400Y245100D03*
Y256700D03*
X5000Y275000D03*
X12600Y266900D03*
X15300Y285800D03*
X4900Y285700D03*
X23400Y81550D03*
X25000Y77300D03*
X20000Y90500D03*
X33000Y105000D03*
X28500Y93500D03*
X25500Y105000D03*
X25700Y135000D03*
X22300Y127700D03*
X30200Y145000D03*
Y149200D03*
X19500Y139000D03*
X34000Y161500D03*
X30300Y157600D03*
X30200Y153400D03*
X27400Y173600D03*
X24173Y178154D03*
X25200Y286000D03*
X37500Y105000D03*
X42000D03*
X45500Y118000D03*
X34100Y147300D03*
X37500Y264000D03*
X63500Y43500D03*
Y57500D03*
Y48000D03*
Y52500D03*
X60500Y83500D03*
X60000Y131500D03*
X62000Y142500D03*
X50500Y160000D03*
X64500Y180500D03*
X63200Y194900D03*
X61100Y221800D03*
X60500Y258100D03*
X68500Y47500D03*
X73500Y48000D03*
X68000Y52500D03*
X68800Y58400D03*
X75500Y59500D03*
X69100Y87800D03*
X80000Y96500D03*
X65700Y98100D03*
X79000Y106400D03*
X72700Y101400D03*
X66000Y114000D03*
X71300Y132500D03*
X70000Y127500D03*
X73900Y138500D03*
X76200Y187200D03*
X70900Y193800D03*
X73500Y198500D03*
X74500Y213500D03*
X74611Y221550D03*
X71633Y235000D03*
X76600Y235130D03*
X68400Y241600D03*
X71500Y256500D03*
X73500Y249800D03*
X93867Y57700D03*
X87000Y61500D03*
X95500Y93500D03*
X85300Y91500D03*
X85200Y103500D03*
X94000Y137500D03*
Y133000D03*
X82000Y177500D03*
X86500D03*
X90700Y177050D03*
X81500Y194500D03*
X84722Y184222D03*
X93500Y208000D03*
X82000Y202000D03*
X86000Y206000D03*
X84200Y211800D03*
X81600Y241112D03*
X84200Y255500D03*
X80900Y250100D03*
X88000Y249700D03*
X92800Y285600D03*
X107300Y53200D03*
X107000Y75000D03*
X106000Y61200D03*
X99500Y91500D03*
Y96000D03*
X104000Y106600D03*
Y92000D03*
Y96500D03*
X96000Y98000D03*
X104000Y115500D03*
Y111000D03*
X102000Y119500D03*
X105775Y137349D03*
X103175Y134050D03*
X98500Y137500D03*
X109000Y134050D03*
X98500Y133000D03*
X107700Y143000D03*
X102500Y165500D03*
X108000Y214000D03*
X104500Y199500D03*
X96200Y219100D03*
X101491Y230420D03*
X109200Y246700D03*
X100000Y267400D03*
X100700Y262900D03*
X97500Y285450D03*
X102000D03*
X106500Y285550D03*
X110700D03*
X112017Y56988D03*
X124100Y53300D03*
X124700Y75400D03*
X119940Y74779D03*
X124084Y84009D03*
X115991Y82591D03*
X119400Y106700D03*
X123800Y102500D03*
X123900Y106700D03*
X119400Y102300D03*
X113500Y102000D03*
X121500Y93000D03*
X119400Y115900D03*
Y111200D03*
X123900Y115900D03*
Y111200D03*
X114500Y134050D03*
X113200Y146700D03*
X113100Y151000D03*
X117500Y146950D03*
X119000Y159100D03*
X114700Y158800D03*
X113500Y177500D03*
X116500Y211200D03*
X124300Y205600D03*
X114900Y207300D03*
X122250Y228750D03*
X122500Y224000D03*
X117200Y216400D03*
X122250Y233000D03*
Y237300D03*
Y241500D03*
X139722Y54301D03*
X140031Y47317D03*
X138400Y70700D03*
X132836Y83507D03*
X128348Y81804D03*
X133300Y77100D03*
X137005Y80930D03*
X134100Y96600D03*
X132900Y103700D03*
X133200Y110800D03*
X128500Y165000D03*
X134800Y161800D03*
X130200Y178600D03*
X132700Y183100D03*
X134100Y197400D03*
X133941Y208863D03*
X131003Y205766D03*
X138100Y208100D03*
X129500Y252500D03*
Y255800D03*
X129000Y268000D03*
X136500Y272500D03*
X153300Y61100D03*
X142000Y60500D03*
X147900Y73300D03*
X147329Y100907D03*
X154600Y111200D03*
X150700Y106800D03*
X149819Y155225D03*
X147018Y161747D03*
X153997Y175975D03*
X151600Y187200D03*
X146000Y228100D03*
X148551Y238551D03*
X157493Y124795D03*
X165500Y157500D03*
X160000Y171700D03*
X163900Y174700D03*
X163600Y184597D03*
X161897Y197859D03*
X159000Y193600D03*
X163226Y190126D03*
X158700Y213800D03*
X171300Y209000D03*
X166500Y241000D03*
X163200D03*
X161900Y253300D03*
X182500Y63000D03*
X185200Y159100D03*
X186700Y175500D03*
X181300Y209500D03*
X180500Y223500D03*
X186500Y276500D03*
Y281000D03*
X195500Y49500D03*
X193100Y64900D03*
X189000Y87700D03*
X188750Y119937D03*
X202122Y107429D03*
X192500Y161900D03*
X192600Y166700D03*
X201200Y164200D03*
X193672Y176556D03*
X202000Y183068D03*
X192000Y234000D03*
X203100Y252900D03*
X191100Y276600D03*
X190900Y280800D03*
X215000Y44500D03*
X209000D03*
X205100Y50900D03*
X216000Y49200D03*
X216261Y74846D03*
X212300Y157300D03*
X212600Y161500D03*
X214000Y223000D03*
X211900Y253000D03*
X207500D03*
X217000Y252900D03*
X217200Y258000D03*
X212400Y281200D03*
X217000Y281000D03*
X212500Y277000D03*
X208000D03*
X226900Y133300D03*
X219200Y202400D03*
X222500Y227500D03*
X220500Y221000D03*
X234525Y239250D03*
X229700Y234700D03*
X225300Y239200D03*
X234525Y243450D03*
X229725D03*
X225300Y243400D03*
X234525Y234800D03*
X225300D03*
X229675Y239000D03*
X233500Y258958D03*
X228000Y259000D03*
X221300Y255400D03*
X242016Y47325D03*
X247500Y49000D03*
X235000Y47000D03*
X243000Y55000D03*
X240130Y77300D03*
X236400Y95100D03*
X240565Y113365D03*
X249350Y199400D03*
X248300Y213500D03*
X247500Y239250D03*
X243300Y235050D03*
X247500Y243450D03*
X243300D03*
X238900D03*
X243300Y239250D03*
X247500Y235050D03*
X238925Y235000D03*
Y239200D03*
X248000Y259000D03*
X238500D03*
X243000D03*
X258400Y65600D03*
X257000Y213500D03*
X252350Y202350D03*
X252700Y213500D03*
X260500Y206000D03*
X251700Y239250D03*
Y243450D03*
X262300Y232500D03*
X252500Y259000D03*
X251500Y253500D03*
X253000Y267000D03*
X266200Y48731D03*
X270900Y61700D03*
X275500Y101200D03*
X277700Y96900D03*
X271200Y104300D03*
X278811Y121089D03*
X276600Y128700D03*
X276800Y158700D03*
X266320Y164180D03*
X279900Y168000D03*
X274500Y215000D03*
X279046Y222063D03*
X269500Y216659D03*
X266000Y244200D03*
X277800Y249400D03*
X265425Y260000D03*
X278200Y281350D03*
X289000Y66000D03*
X286700Y86600D03*
X294800Y94100D03*
X291400Y134686D03*
X282130Y147600D03*
X286600Y163600D03*
X282500Y177300D03*
X290100Y190900D03*
X288500Y195802D03*
X286500Y184000D03*
X284300Y214225D03*
X285200Y233000D03*
X282686Y281336D03*
X310310Y68000D03*
X304694Y101956D03*
X297600Y113025D03*
X297200Y123600D03*
X299600Y135800D03*
X302700Y140600D03*
X300600Y149400D03*
X309350Y147840D03*
X299065Y154064D03*
X310300Y163300D03*
X303492Y162375D03*
X298500Y167100D03*
X308559Y174807D03*
X298000Y181500D03*
X297797Y173997D03*
X303639Y171201D03*
X305800Y191000D03*
X303500Y228000D03*
X309010Y228490D03*
X299600Y238200D03*
X301100Y248600D03*
X309300Y249700D03*
X321300Y88200D03*
X312100Y84800D03*
X317000Y84900D03*
X320500Y103000D03*
X317352Y116648D03*
X322500Y114500D03*
X320600Y126100D03*
X315000Y144550D03*
X320300Y146700D03*
X314800Y151661D03*
X316259Y163771D03*
X315900Y156921D03*
X312070Y179296D03*
X318324Y176724D03*
X313260Y193500D03*
X317060Y202500D03*
X319423Y228577D03*
X322192Y234136D03*
X335000Y46575D03*
X339638Y67138D03*
X340200Y71400D03*
X337300Y88000D03*
X332400Y85400D03*
X340500Y95500D03*
X327026Y102576D03*
X336300Y103700D03*
X339547Y108043D03*
X338400Y113800D03*
X336300Y118200D03*
X330500Y109000D03*
X329523Y128134D03*
X333800Y148700D03*
X339150Y159000D03*
X336500Y183000D03*
X330155Y183655D03*
X334500Y207500D03*
X330500Y240800D03*
X334500Y266300D03*
X334300Y270500D03*
X335700Y278751D03*
X331500D03*
X353100Y56151D03*
X354800Y50200D03*
X345089Y73089D03*
X353500Y71900D03*
X357000Y69500D03*
X349300Y83000D03*
X345100D03*
X354200Y76400D03*
X356000Y121000D03*
X345040Y107960D03*
X343890Y131430D03*
X346600Y125600D03*
X342300Y143400D03*
X345500Y166500D03*
X347476Y153210D03*
X354899Y164998D03*
X344600Y173066D03*
X342692Y177534D03*
X354500Y203763D03*
X342200Y200100D03*
X355000Y260200D03*
X347000Y260000D03*
X343600Y270500D03*
X371400Y42500D03*
X371500Y47000D03*
X359646Y50000D03*
X359800Y72700D03*
X362700Y69600D03*
X365500Y76000D03*
X372500Y151700D03*
X370000Y183000D03*
X363600Y196000D03*
X365700Y240300D03*
X380000Y38100D03*
X375600Y42500D03*
X380300D03*
X375700Y47000D03*
X380295Y46779D03*
X384921Y50782D03*
X377850Y63500D03*
X384500Y62000D03*
X373800Y80600D03*
X385300Y94300D03*
X387100Y103100D03*
X376900Y128100D03*
X376800Y138500D03*
X373700Y171100D03*
X379561Y197939D03*
X387400Y184700D03*
X402820Y54500D03*
X400296Y78300D03*
X400000Y106100D03*
X401800Y177800D03*
X389480Y197040D03*
X392300Y203000D03*
X397800Y222600D03*
X392500Y245000D03*
X391508Y257969D03*
X391499Y253169D03*
X396000Y274092D03*
X394650Y263940D03*
X399300Y262400D03*
X414790Y52110D03*
X412350Y175550D03*
X414827Y238668D03*
X416128Y268872D03*
X410000Y266500D03*
X419565Y233465D03*
X428272Y237872D03*
X430200Y248400D03*
X439300Y39600D03*
X439000Y54000D03*
X444500Y71500D03*
X441500Y62500D03*
X435500Y156500D03*
X445500Y215500D03*
X443500Y235500D03*
X443800Y246100D03*
X452000Y107000D03*
X458700Y255600D03*
X451500Y251150D03*
X455500Y269500D03*
X474000Y9000D03*
X467200Y4400D03*
X472256Y29500D03*
X469195Y268805D03*
X481500Y8900D03*
X489600Y8800D03*
X487000Y138400D03*
X497100Y8800D03*
X505200Y215000D03*
X496711Y248999D03*
X526200Y96600D03*
X516500Y92600D03*
X521000Y96500D03*
X517000Y110000D03*
X521261Y162739D03*
X527000Y225500D03*
X518500Y230500D03*
X541000Y119500D03*
X541757Y158048D03*
X536634Y169866D03*
X534700Y187450D03*
X541100Y187500D03*
X538400Y209500D03*
X536500Y231500D03*
X552178Y205822D03*
X547600Y227300D03*
X568900Y196900D03*
X576700Y96100D03*
X582100Y140000D03*
X584702Y173402D03*
X602650Y177250D03*
X594965Y207175D03*
X600900Y230200D03*
X598814Y240095D03*
X607900Y97900D03*
X612000Y172250D03*
X615700Y230200D03*
X615100Y238900D03*
X630000Y55300D03*
X627500Y174300D03*
X626100Y186400D03*
X634600Y189300D03*
X623400Y230100D03*
X623900Y239600D03*
X646000Y46007D03*
X640000D03*
X640500Y55000D03*
X638000Y103000D03*
X641000Y161500D03*
X655133Y55833D03*
X654500Y46107D03*
X653000Y93000D03*
X655300Y100900D03*
X650726Y125724D03*
X664212Y147993D03*
X660397Y191100D03*
X658800Y200100D03*
X659811Y260757D03*
X657500Y258400D03*
X661308Y263698D03*
X655500Y270500D03*
X657787Y264179D03*
X656000Y261400D03*
X655523Y266616D03*
X658667Y267622D03*
X678400Y114500D03*
X670500Y111900D03*
X668411Y148089D03*
X678500Y141500D03*
X667061Y175239D03*
X679871Y179371D03*
X692500Y106000D03*
X693500Y148000D03*
X690000Y159000D03*
X694500D03*
X694000Y175000D03*
X693600Y219300D03*
X700089Y91411D03*
X701600Y104900D03*
X701400Y98400D03*
X699858Y131908D03*
X703000Y139900D03*
X710200Y201700D03*
X725632Y49600D03*
X721950Y51950D03*
X721200Y65100D03*
X722000Y74500D03*
X717000D03*
X715000Y80300D03*
X714500Y85500D03*
X726500Y111600D03*
X718700Y112500D03*
X722900Y127400D03*
X727100Y123500D03*
X718847Y143500D03*
X718300Y159300D03*
X718900Y166200D03*
X714038Y175162D03*
X732000Y63500D03*
X739500Y75500D03*
X736000Y62000D03*
X731000Y88000D03*
X731500Y98600D03*
X739900Y101400D03*
X740000Y96000D03*
X728900Y116100D03*
X731200Y129600D03*
X742000Y124200D03*
X731200Y138500D03*
X729700Y146900D03*
X733000Y185100D03*
X753500Y24007D03*
Y20007D03*
Y28507D03*
X755500Y16000D03*
X744600Y99600D03*
X744100Y104700D03*
X745140Y120480D03*
X758003Y141303D03*
X757000Y149000D03*
X770500Y13007D03*
X767500Y24007D03*
X760500Y29000D03*
X761000Y16007D03*
X767500Y28507D03*
Y19507D03*
X764200Y44200D03*
X767500Y33207D03*
X759000Y37507D03*
X764500Y54000D03*
X764300Y49200D03*
X769500Y50000D03*
X761000Y58500D03*
X764500Y84800D03*
X760400Y88700D03*
X768100Y89000D03*
X761300Y95700D03*
X772547Y135627D03*
X762200Y135200D03*
X763600Y168000D03*
X770600Y153700D03*
X764000Y188000D03*
Y197500D03*
Y192810D03*
Y202310D03*
X769500Y234500D03*
X769400Y252700D03*
X785500Y8000D03*
X784369Y18484D03*
X781500Y51000D03*
X777000Y93100D03*
X774300Y102500D03*
X778500D03*
Y107000D03*
X787500Y93000D03*
X783000D03*
X774300Y107000D03*
X783000Y113000D03*
Y118500D03*
Y123000D03*
X785297Y128876D03*
X785324Y133676D03*
X785100Y139900D03*
X785831Y164500D03*
X785453Y154214D03*
X785831Y159000D03*
X786000Y171856D03*
X785830Y188700D03*
X785400Y202800D03*
X789000Y204979D03*
X789200Y214200D03*
Y209800D03*
X784500Y222500D03*
X789000Y223500D03*
X789200Y218700D03*
X786000Y228000D03*
Y232400D03*
X786200Y236900D03*
X786300Y241500D03*
X785000Y245800D03*
Y250200D03*
Y254900D03*
X786500Y276000D03*
X788955Y265773D03*
X783078Y266246D03*
X790500Y14500D03*
X792000Y83000D03*
X796500D03*
X792000Y87700D03*
X796500D03*
X804000Y86500D03*
X799200Y98600D03*
X803100Y106000D03*
X799200Y102800D03*
X804000Y97500D03*
X799000Y107100D03*
X803500Y116700D03*
Y112500D03*
X799000Y116100D03*
Y111900D03*
X792000Y119465D03*
X792123Y177595D03*
X789910Y187679D03*
X794110D03*
X798310Y187779D03*
X793500Y204979D03*
Y223500D03*
X793200Y228400D03*
Y232600D03*
Y237200D03*
Y242400D03*
X793300Y247200D03*
X795300Y260800D03*
X795400Y251700D03*
X795300Y256500D03*
X789000Y245500D03*
X795300Y265000D03*
X791366Y270866D03*
X792000Y280800D03*
X808900Y179500D03*
X810500Y196500D03*
Y192300D03*
X809200Y209500D03*
Y213700D03*
Y218400D03*
X809100Y228600D03*
Y224400D03*
X808700Y238300D03*
Y234100D03*
Y242900D03*
X809500Y251500D03*
Y257000D03*
X808700Y247100D03*
X810100Y275000D03*
X812035Y271067D03*
X810100Y267339D03*
X812000Y263500D03*
X809700Y285900D03*
X820500Y6500D03*
X821900Y273100D03*
X821600Y285500D03*
G54D106*
G01X143500Y89200D02*
X142250Y90450D01*
X140940D01*
X138650Y92740D01*
Y141650D01*
X134525Y145775D01*
X123225D01*
X115225Y153775D01*
X102615D01*
X87690Y168700D01*
X70290D01*
X57940Y181050D01*
X51840D01*
X49040Y183850D01*
X14740D01*
X9450Y189140D01*
Y210460D01*
X15019Y216029D01*
X18700D01*
X19009Y216338D01*
X21949D01*
G01X143500Y92800D02*
X142500Y91800D01*
X141500D01*
X140000Y93300D01*
Y142210D01*
X135085Y147125D01*
X123785D01*
X115785Y155125D01*
X103175D01*
X88250Y170050D01*
X79093D01*
X78303Y170840D01*
X76653D01*
X75863Y170050D01*
X70850D01*
X58500Y182400D01*
X52400D01*
X49600Y185200D01*
X15300D01*
X10800Y189700D01*
Y200140D01*
X11590Y200930D01*
Y202580D01*
X10800Y203370D01*
Y205020D01*
X11590Y205810D01*
Y207460D01*
X10800Y208250D01*
Y209900D01*
X12128Y211228D01*
X13246D01*
X14412Y212395D01*
Y213512D01*
X15579Y214679D01*
X18821D01*
X19130Y214370D01*
X21949D01*
G01Y239960D02*
X18044D01*
X17735Y239651D01*
X8810D01*
X7600Y240861D01*
G01X21949Y237992D02*
X18044D01*
X17735Y238301D01*
X8810D01*
X7600Y237091D01*
G01X21949Y232086D02*
X19253D01*
X19000Y232339D01*
X14300D01*
X13090Y231129D01*
G01X21949Y234055D02*
X19366D01*
X19000Y233689D01*
X14300D01*
X13090Y234899D01*
G01X21949Y243897D02*
X18044D01*
X17791Y244150D01*
X14800D01*
X13590Y242940D01*
G01X21949Y249803D02*
X18044D01*
X17735Y250112D01*
X8810D01*
X7600Y248902D01*
G01X21949Y251771D02*
X18044D01*
X17735Y251462D01*
X8810D01*
X7600Y252672D01*
G01X21949Y245866D02*
X18045D01*
X17679Y245500D01*
X14800D01*
X13590Y246710D01*
G01X21949Y257677D02*
X19166D01*
X18800Y257311D01*
X14800D01*
X13590Y258521D01*
G01X21949Y255708D02*
X19253D01*
X19000Y255961D01*
X14800D01*
X13590Y254751D01*
G01X21949Y263582D02*
X18044D01*
X17735Y263273D01*
X8810D01*
X7600Y264483D01*
G01X21949Y261614D02*
X18044D01*
X17735Y261923D01*
X8810D01*
X7600Y260713D01*
G01X34800Y208300D02*
X33450Y209650D01*
X32390D01*
X31000Y211040D01*
Y221900D01*
X26410Y226490D01*
X25090D01*
X24781Y226181D01*
X21949D01*
G01X34800Y212200D02*
X33600Y211000D01*
X32950D01*
X32350Y211600D01*
Y222460D01*
X26970Y227840D01*
X24860D01*
X24551Y228149D01*
X21949D01*
G01X32000Y199300D02*
X30650Y200650D01*
X28440D01*
X27000Y202090D01*
Y219700D01*
X26116Y220584D01*
X25084D01*
X24775Y220275D01*
X21949D01*
G01X32000Y203200D02*
X30800Y202000D01*
X29000D01*
X28350Y202650D01*
Y220260D01*
X26676Y221934D01*
X25066D01*
X24756Y222244D01*
X21949D01*
G01X68307Y22892D02*
Y33257D01*
X69600Y34550D01*
Y41100D01*
X72500Y44000D01*
X79590D01*
X80350Y44760D01*
Y47350D01*
X79500Y48200D01*
G01X72244Y22892D02*
Y33256D01*
X70950Y34550D01*
Y40540D01*
X73060Y42650D01*
X80150D01*
X81700Y44200D01*
Y47400D01*
X82500Y48200D01*
G01X79500Y51800D02*
X80325Y52625D01*
Y59769D01*
X79115Y60979D01*
G01X87992Y22892D02*
Y33256D01*
X86698Y34550D01*
Y41198D01*
X87700Y42200D01*
Y47400D01*
X88500Y48200D01*
G01X84055Y22892D02*
Y33257D01*
X85348Y34550D01*
Y41758D01*
X86350Y42760D01*
Y47350D01*
X85500Y48200D01*
G01Y51800D02*
Y54200D01*
X85300Y54400D01*
G01X88500Y51800D02*
Y54200D01*
X88700Y54400D01*
G01X82500Y51800D02*
X81675Y52625D01*
Y59769D01*
X82885Y60979D01*
G01X103740Y22892D02*
Y33256D01*
X102446Y34550D01*
Y47396D01*
X103250Y48200D01*
G01X99803Y22892D02*
Y33257D01*
X101096Y34550D01*
Y47354D01*
X100250Y48200D01*
G01X103250Y51800D02*
Y54200D01*
X103450Y54400D01*
G01X100250Y51800D02*
Y54200D01*
X100050Y54400D01*
G01X119488Y22892D02*
Y33256D01*
X118194Y34550D01*
Y47394D01*
X119000Y48200D01*
G01X115551Y22892D02*
Y33257D01*
X116844Y34550D01*
Y47356D01*
X116000Y48200D01*
G01X112017Y56988D02*
Y66383D01*
X111200Y67200D01*
G01X119000Y51800D02*
X118175Y52625D01*
Y56375D01*
X119200Y57400D01*
G01X116000Y51800D02*
X116825Y52625D01*
Y56375D01*
X115800Y57400D01*
G01X131299Y22892D02*
Y33257D01*
X132592Y34550D01*
Y47408D01*
X131800Y48200D01*
G01X135236Y22892D02*
Y33256D01*
X133942Y34550D01*
Y47342D01*
X134800Y48200D01*
G01Y51800D02*
X133975Y52625D01*
Y56375D01*
X135000Y57400D01*
G01X131800Y51800D02*
X132625Y52625D01*
Y56375D01*
X131600Y57400D01*
G01X147047Y22892D02*
Y33257D01*
X148340Y34550D01*
Y47375D01*
X147515Y48200D01*
G01X150984Y22892D02*
Y33256D01*
X149690Y34550D01*
Y47375D01*
X150515Y48200D01*
G01Y51800D02*
Y54200D01*
X150715Y54400D01*
G01X147515Y51800D02*
Y54200D01*
X147315Y54400D01*
G01X155290Y48610D02*
X156500Y49820D01*
Y53410D01*
X157825Y54735D01*
Y56375D01*
X156700Y57500D01*
G01X150200Y89500D02*
X151025Y90325D01*
X153675D01*
X160000Y84000D01*
X181500D01*
X187450Y78050D01*
Y76250D01*
X187095Y75895D01*
Y73450D01*
G01X150200Y92500D02*
X151025Y91675D01*
X154235D01*
X160560Y85350D01*
X182060D01*
X188800Y78610D01*
Y76200D01*
X189065Y75935D01*
Y73450D01*
G01X146800Y89500D02*
X143800D01*
X143500Y89200D01*
G01X146800Y92500D02*
X143800D01*
X143500Y92800D01*
G01X150670Y115500D02*
X149670Y116500D01*
X147840D01*
X146000Y118340D01*
Y125610D01*
X162590Y142200D01*
X178500D01*
X188600Y152300D01*
Y173200D01*
X189200Y173800D01*
Y176298D01*
X186058Y179440D01*
Y181448D01*
G01X187633D02*
Y179775D01*
X190550Y176858D01*
Y173240D01*
X189950Y172640D01*
Y151740D01*
X179060Y140850D01*
X171162D01*
X170372Y140060D01*
X168722D01*
X167932Y140850D01*
X163150D01*
X161183Y138883D01*
Y137766D01*
X160017Y136599D01*
X158899D01*
X157733Y135433D01*
Y134315D01*
X156566Y133149D01*
X155449D01*
X154282Y131982D01*
Y130865D01*
X153115Y129698D01*
X151998D01*
X147350Y125050D01*
Y118900D01*
X148400Y117850D01*
X149620D01*
X150670Y118900D01*
G01X166732Y22892D02*
Y33256D01*
X165438Y34550D01*
Y47375D01*
X166263Y48200D01*
G01X162795Y22892D02*
Y33257D01*
X164088Y34550D01*
Y47375D01*
X163263Y48200D01*
G01X170700Y61300D02*
X171500Y60500D01*
Y50810D01*
X170290Y49600D01*
G01X166263Y51800D02*
Y54200D01*
X166463Y54400D01*
G01X163263Y51800D02*
Y54200D01*
X163063Y54400D01*
G01X157000Y60900D02*
Y57800D01*
X156700Y57500D01*
G01X159060Y48610D02*
X157850Y49820D01*
Y52850D01*
X159175Y54175D01*
Y56375D01*
X160300Y57500D01*
G01X160000Y60900D02*
Y57800D01*
X160300Y57500D01*
G01X157000Y64300D02*
X157825Y65125D01*
Y66960D01*
X159477Y68612D01*
X162602D01*
X163765Y69775D01*
Y70635D01*
X163455Y70945D01*
Y73450D01*
G01X170800Y67800D02*
X171645Y68645D01*
Y70700D01*
X171335Y71010D01*
Y73450D01*
G01X170800Y64400D02*
Y61400D01*
X170700Y61300D01*
G01X160000Y64300D02*
X159175Y65125D01*
Y66400D01*
X160037Y67262D01*
X163162D01*
X165115Y69215D01*
Y70615D01*
X165425Y70925D01*
Y73450D01*
G01X164900Y106700D02*
X165425Y106175D01*
Y101750D01*
G01X167900Y106700D02*
X167395Y106195D01*
Y101750D01*
G01X164800Y113200D02*
X165725Y114125D01*
Y127425D01*
X173000Y134700D01*
X179300D01*
X182826Y131174D01*
X195964D01*
X203950Y123188D01*
Y117360D01*
X205010Y116300D01*
X208129D01*
X209259Y117430D01*
G01X164900Y110100D02*
Y113100D01*
X164800Y113200D01*
G01X167900Y110100D02*
Y113100D01*
X168000Y113200D01*
G01X209259Y113771D02*
X208080Y114950D01*
X204450D01*
X202600Y116800D01*
Y122628D01*
X195404Y129824D01*
X192026D01*
X191236Y129034D01*
X189586D01*
X188796Y129824D01*
X187146D01*
X186356Y129034D01*
X184706D01*
X183916Y129824D01*
X182266D01*
X178740Y133350D01*
X173560D01*
X167075Y126865D01*
Y125215D01*
X167865Y124425D01*
Y122775D01*
X167075Y121985D01*
Y120335D01*
X167865Y119545D01*
Y117895D01*
X167075Y117105D01*
Y114125D01*
X168000Y113200D01*
G01X175034Y181448D02*
Y179966D01*
X175147Y179853D01*
Y179157D01*
X173940Y177950D01*
X169940D01*
X168350Y176360D01*
Y175050D01*
X167140Y173840D01*
G01X176609Y181448D02*
Y180112D01*
X176497Y180000D01*
Y178597D01*
X174500Y176600D01*
X170500D01*
X169700Y175800D01*
Y175050D01*
X170910Y173840D01*
G01X178543Y22892D02*
Y33257D01*
X179836Y34550D01*
Y47364D01*
X179000Y48200D01*
G01X182480Y22892D02*
Y33256D01*
X181186Y34550D01*
Y47386D01*
X182000Y48200D01*
G01X173900Y61300D02*
X172850Y60250D01*
Y50810D01*
X174060Y49600D01*
G01X182000Y51800D02*
Y54200D01*
X181800Y54400D01*
G01X179000Y51800D02*
Y54400D01*
G01X186500Y60900D02*
Y57800D01*
X186200Y57500D01*
G01D02*
X187375Y56325D01*
Y54810D01*
X186865Y54300D01*
G01X173800Y64400D02*
Y61400D01*
X173900Y61300D01*
G01X173800Y67800D02*
X172995Y68605D01*
Y70700D01*
X173305Y71010D01*
Y73450D01*
G01X189500Y64300D02*
X188675Y65125D01*
Y66960D01*
X187172Y68463D01*
X181912D01*
X180875Y69500D01*
Y70900D01*
X181185Y71210D01*
Y73450D01*
G01X186500Y64300D02*
X187325Y65125D01*
Y66400D01*
X186612Y67113D01*
X181352D01*
X179525Y68940D01*
Y70775D01*
X179215Y71085D01*
Y73450D01*
G01X179759Y181448D02*
Y178259D01*
X178371Y176871D01*
Y174112D01*
X177159Y172900D01*
G01X181333Y181448D02*
Y178646D01*
X181109Y178422D01*
Y177699D01*
X179721Y176311D01*
Y174195D01*
X180931Y172985D01*
G01X186058Y203570D02*
Y205758D01*
X192350Y212050D01*
X219743D01*
X224000Y207793D01*
Y185500D01*
X220500Y182000D01*
Y176910D01*
X225577Y171833D01*
Y169893D01*
X230427Y165043D01*
Y146350D01*
X229687Y145610D01*
Y143023D01*
X230860Y141850D01*
X233665D01*
X234875Y143060D01*
G01X182908Y203570D02*
Y205968D01*
X185225Y208285D01*
Y210525D01*
X189300Y214600D01*
X220800D01*
X226750Y208650D01*
Y190340D01*
X235390Y181700D01*
X238800D01*
X239900Y180600D01*
G01X181333Y203570D02*
Y206303D01*
X183875Y208845D01*
Y211085D01*
X188740Y215950D01*
X221360D01*
X228100Y209210D01*
Y190900D01*
X235950Y183050D01*
X239176D01*
X240119Y183993D01*
G01X194291Y22892D02*
Y33257D01*
X195584Y34550D01*
Y39256D01*
X194445Y40395D01*
G01X198228Y22892D02*
Y33256D01*
X196934Y34550D01*
Y39256D01*
X198073Y40395D01*
G01X189500Y60900D02*
Y57800D01*
X189800Y57500D01*
G01D02*
X188725Y56425D01*
Y55275D01*
X189700Y54300D01*
G01X194975Y73450D02*
Y75975D01*
X195285Y76285D01*
Y79150D01*
X194075Y80360D01*
G01X196945Y73450D02*
Y76055D01*
X196635Y76365D01*
Y79150D01*
X197845Y80360D01*
G01X201899Y134200D02*
X203200Y135501D01*
Y139800D01*
X201800Y141200D01*
Y161200D01*
X203550Y162950D01*
Y180392D01*
X209900Y186742D01*
Y189173D01*
X207650Y191423D01*
Y194750D01*
X204050Y198350D01*
X199150D01*
X195783Y194983D01*
X194521D01*
X194409Y194871D01*
X191607D01*
G01Y183848D02*
X193742D01*
X197550Y180040D01*
Y173950D01*
X198950Y172550D01*
Y168250D01*
X195050Y164350D01*
Y157550D01*
X193150Y155650D01*
Y152740D01*
X194623Y151267D01*
Y149723D01*
G01X191607Y185422D02*
X194078D01*
X198900Y180600D01*
Y174510D01*
X200300Y173110D01*
Y167690D01*
X196400Y163790D01*
Y156990D01*
X194500Y155090D01*
Y153300D01*
X195790Y152010D01*
X197140D01*
G01X191607Y188572D02*
X191707Y188672D01*
X198316D01*
X199441Y187547D01*
G01X205380Y134200D02*
X204550Y135030D01*
Y140360D01*
X203150Y141760D01*
Y160640D01*
X204900Y162390D01*
Y179832D01*
X211250Y186182D01*
Y189733D01*
X209000Y191983D01*
Y195310D01*
X204610Y199700D01*
X198590D01*
X195223Y196333D01*
X194521D01*
X194408Y196446D01*
X191607D01*
G01Y198021D02*
X193797D01*
X198026Y202250D01*
X205700D01*
X211550Y196400D01*
Y193040D01*
X213800Y190790D01*
Y185125D01*
X207450Y178775D01*
Y161333D01*
X205700Y159583D01*
Y143200D01*
X208000Y140900D01*
Y140250D01*
X206790Y139040D01*
G01X191607Y190147D02*
X191732Y190022D01*
X198467D01*
X199392Y190947D01*
G01X187633Y203570D02*
Y205423D01*
X192910Y210700D01*
X219183D01*
X222650Y207233D01*
Y186060D01*
X219150Y182560D01*
Y176350D01*
X224227Y171273D01*
Y169333D01*
X229077Y164483D01*
Y146910D01*
X228337Y146170D01*
Y142463D01*
X230300Y140500D01*
X233665D01*
X234875Y139290D01*
G01X191607Y199596D02*
X193462D01*
X197466Y203600D01*
X206260D01*
X212900Y196960D01*
Y193600D01*
X215150Y191350D01*
Y184565D01*
X208800Y178215D01*
Y160773D01*
X207050Y159023D01*
Y143760D01*
X209350Y141460D01*
Y140225D01*
X210547Y139028D01*
G01X245472Y22892D02*
Y33257D01*
X244229Y34500D01*
Y39201D01*
X245385Y40357D01*
G01X241535Y22892D02*
Y33256D01*
X242879Y34600D01*
Y39243D01*
X241765Y40357D01*
G01X261220Y22892D02*
Y33257D01*
X259927Y34550D01*
Y47192D01*
X261175Y48440D01*
Y50875D01*
X262000Y51700D01*
G01X257283Y22892D02*
Y33256D01*
X258577Y34550D01*
Y47752D01*
X259825Y49000D01*
Y50875D01*
X259000Y51700D01*
G01Y55300D02*
Y57800D01*
G01X262000Y55300D02*
Y57800D01*
G01X262700Y120200D02*
X261875Y119375D01*
X261025D01*
X257284Y123116D01*
X255800D01*
X254900Y124016D01*
X251758D01*
G01Y111417D02*
X254600D01*
X255400Y110617D01*
X261817D01*
X262700Y111500D01*
G01Y117200D02*
X261875Y118025D01*
X260465D01*
X256724Y121766D01*
X255800D01*
X254900Y120866D01*
X251758D01*
G01Y108268D02*
X254601D01*
X255600Y109267D01*
X261933D01*
X262700Y108500D01*
G01X273031Y22892D02*
Y33256D01*
X274325Y34550D01*
Y38900D01*
X272045Y41180D01*
Y45745D01*
X269050Y48740D01*
Y50650D01*
X268000Y51700D01*
G01X276968Y22892D02*
Y33257D01*
X275675Y34550D01*
Y39460D01*
X273395Y41740D01*
Y46305D01*
X270400Y49300D01*
Y51100D01*
X271000Y51700D01*
G01X268000Y55300D02*
Y57500D01*
G01X271000Y55300D02*
Y57500D01*
G01X304075Y115900D02*
Y113880D01*
X296746Y106551D01*
X288072D01*
X281373Y113250D01*
X275450D01*
X270675Y118025D01*
X267125D01*
X266300Y117200D01*
G01Y108500D02*
X267150Y109350D01*
X271202D01*
X272200Y108352D01*
G01X302725Y115900D02*
Y114440D01*
X296186Y107901D01*
X288632D01*
X281933Y114600D01*
X276010D01*
X271235Y119375D01*
X267125D01*
X266300Y120200D01*
G01Y111500D02*
X267100Y110700D01*
X271054D01*
X272185Y111831D01*
G01X288779Y22892D02*
Y33257D01*
X290072Y34550D01*
Y45018D01*
X287825Y47265D01*
Y50875D01*
X287000Y51700D01*
G01X292716Y22892D02*
Y33256D01*
X291422Y34550D01*
Y45578D01*
X289175Y47825D01*
Y50875D01*
X290000Y51700D01*
G01X287000Y55300D02*
Y57700D01*
X286800Y57900D01*
G01X290000Y55300D02*
Y57700D01*
X290200Y57900D01*
G01X304527Y22892D02*
Y33257D01*
X305820Y34550D01*
Y50380D01*
X305000Y51200D01*
G01X308464Y22892D02*
Y33256D01*
X307170Y34550D01*
Y50370D01*
X308000Y51200D01*
G01X305000Y54800D02*
Y57200D01*
X304800Y57400D01*
G01X308000Y54800D02*
Y57200D01*
X308200Y57400D01*
G01X320275Y22892D02*
Y33256D01*
X321569Y34550D01*
Y39521D01*
X316800Y44290D01*
Y50400D01*
X316000Y51200D01*
G01X324212Y22892D02*
Y33257D01*
X322919Y34550D01*
Y40081D01*
X318150Y44850D01*
Y50350D01*
X319000Y51200D01*
G01X351772Y22892D02*
Y33257D01*
X353065Y34550D01*
Y43435D01*
X346150Y50350D01*
X326850D01*
X325100Y52100D01*
Y53800D01*
X324000Y54900D01*
G01X319000Y54800D02*
Y57200D01*
X319200Y57400D01*
G01X316000Y54800D02*
Y57200D01*
X315800Y57400D01*
G01X355709Y22892D02*
Y33256D01*
X354415Y34550D01*
Y43995D01*
X346710Y51700D01*
X327410D01*
X326450Y52660D01*
Y53950D01*
X327400Y54900D01*
G54D22*
X26000Y138500D03*
X64000Y251500D03*
Y254500D03*
Y261700D03*
Y264800D03*
X75100Y241700D03*
X125500Y175000D03*
X132000Y172000D03*
X153500Y168000D03*
X260800Y76200D03*
X272000Y126300D03*
X283000Y138500D03*
X281400Y153200D03*
X318500Y88300D03*
X329000Y85000D03*
X356650Y131700D03*
Y134700D03*
X370000Y103000D03*
Y100000D03*
Y106000D03*
X365100Y121500D03*
X366500Y118500D03*
X361400Y151900D03*
X379500Y77500D03*
X383500Y139500D03*
X374000Y146000D03*
X386500Y152500D03*
X376280Y184610D03*
X403000Y131063D03*
X408000Y134063D03*
X408012Y140238D03*
X408000Y137063D03*
X408200Y176063D03*
Y173063D03*
X404542Y169124D03*
X414000Y208000D03*
X444000Y114563D03*
Y111563D03*
X437000Y188500D03*
X437500Y200063D03*
X466500Y24000D03*
X513000Y50507D03*
X515000Y126000D03*
Y122500D03*
X528000Y125500D03*
X546000Y96000D03*
Y93000D03*
X544500Y179000D03*
X570000Y92500D03*
X599000Y142000D03*
X591000Y179000D03*
X644500Y285000D03*
X722000Y116500D03*
X736200Y111900D03*
X736300Y108700D03*
X737900Y130900D03*
X737800Y137100D03*
X805000Y121500D03*
Y125000D03*
X805200Y155300D03*
X805900Y166700D03*
G54D40*
X119760Y191419D03*
X323882Y71643D03*
G54D13*
X18500Y111500D03*
X25100D03*
X25600Y149700D03*
X19000D03*
X25600Y156800D03*
X19000D03*
X103300Y174000D03*
X96700D03*
X103300Y181500D03*
X96700D03*
X275600Y60900D03*
X273100Y68000D03*
X279700D03*
X282200Y60900D03*
X305800Y64400D03*
X299200D03*
X305800Y71600D03*
X299200D03*
X365300Y247000D03*
X358700D03*
X365300Y254500D03*
X358700D03*
X426700Y85000D03*
X433300D03*
X431200Y205500D03*
X437800D03*
X787200Y101000D03*
Y108500D03*
X781700Y230600D03*
X775100D03*
X781700Y238000D03*
X775100D03*
X793800Y101000D03*
Y108500D03*
X797800Y229400D03*
X804400D03*
X797800Y222300D03*
X804400D03*
X797800Y239000D03*
X804400D03*
X797800Y246200D03*
X804400D03*
X803300Y279500D03*
X796700D03*
G54D31*
X58500Y188000D03*
X61500D03*
X79500Y48500D03*
X67500Y188000D03*
X64500D03*
X68000Y235000D03*
X82500Y48500D03*
X88500D03*
X85500D03*
X85200Y239000D03*
X103250Y48500D03*
X100250D03*
X105500Y192000D03*
X119000Y48500D03*
X116000D03*
X134800D03*
X131800D03*
X132700Y186600D03*
X150515Y48500D03*
X147515D03*
X166263D03*
X163263D03*
X160100Y184000D03*
X182000Y48500D03*
X179000D03*
X178000Y164500D03*
X201500Y65500D03*
X204500D03*
X237000Y57300D03*
X268000Y52000D03*
X271000D03*
X275500Y241500D03*
X272500D03*
X290000Y52000D03*
X287000D03*
X286100Y77700D03*
X305000Y51500D03*
X308000D03*
X310500Y60500D03*
X304500Y219000D03*
X302000Y242100D03*
X305000D03*
X316000Y51500D03*
X319000D03*
X334000Y55500D03*
X354000Y63000D03*
X353000Y140500D03*
X364500Y128500D03*
X370300Y131500D03*
X365000Y146500D03*
X359000Y140000D03*
Y174000D03*
X377500Y131500D03*
X374500D03*
X386500Y168500D03*
X378220Y170540D03*
X395500Y75000D03*
X392000D03*
X393496Y106063D03*
X389500Y156263D03*
X390000Y162100D03*
Y168500D03*
X398000Y253000D03*
X410000Y106063D03*
X407000D03*
X416000D03*
X413000D03*
X406000Y263500D03*
X422000Y106063D03*
X419000D03*
X421142Y181024D03*
X436000Y107563D03*
X434900Y146500D03*
X441000Y140000D03*
X601100Y233500D03*
X617800Y233400D03*
X613200Y233100D03*
X610200D03*
X620800Y233400D03*
X623800D03*
X744500Y236000D03*
G54D107*
G01X606890Y246456D02*
Y249500D01*
X607190Y249800D01*
Y252590D01*
X609500Y254900D01*
G01X609252Y246456D02*
Y249415D01*
X608640Y250027D01*
Y251493D01*
X609253Y252106D01*
X609937D01*
G01X608071Y278740D02*
Y275700D01*
X607771Y275400D01*
Y272771D01*
X605100Y270100D01*
G01X605709Y278740D02*
Y275791D01*
X606321Y275179D01*
Y273921D01*
X605367Y272967D01*
X605065D01*
G01X645866Y6656D02*
Y9907D01*
X646166Y10207D01*
Y13256D01*
X648400Y15490D01*
G01X648228Y6656D02*
Y9616D01*
X647616Y10228D01*
Y11714D01*
X648609Y12707D01*
X648800D01*
G01X647047Y38940D02*
Y36181D01*
X646135Y35269D01*
Y33674D01*
X645475Y33014D01*
Y31682D01*
X644100Y30307D01*
G01X644685Y38940D02*
Y34275D01*
X643700Y33290D01*
G54D41*
X141500Y167976D03*
Y183024D03*
G54D50*
X219502Y78346D03*
Y81496D03*
Y84646D03*
Y87795D03*
Y90945D03*
Y94094D03*
Y97244D03*
Y100394D03*
Y103543D03*
Y106693D03*
Y109842D03*
Y112992D03*
Y116142D03*
Y119291D03*
Y122441D03*
Y125590D03*
Y128740D03*
Y131890D03*
Y147638D03*
Y150787D03*
Y153937D03*
Y157086D03*
Y160236D03*
Y163386D03*
Y166535D03*
Y169685D03*
X251758Y79921D03*
Y83071D03*
Y86220D03*
Y89370D03*
Y92520D03*
Y95669D03*
Y98819D03*
Y101968D03*
Y105118D03*
Y108268D03*
Y111417D03*
Y114567D03*
Y117716D03*
Y120866D03*
Y124016D03*
Y127165D03*
Y130315D03*
Y133464D03*
Y149212D03*
Y152362D03*
Y155512D03*
Y158661D03*
Y161811D03*
Y164960D03*
Y168110D03*
Y171260D03*
G54D14*
X19000Y174931D03*
Y180069D03*
X265500Y87931D03*
Y93069D03*
G54D23*
X21949Y194685D03*
Y196653D03*
Y198622D03*
Y200590D03*
Y202559D03*
Y212401D03*
Y214370D03*
Y216338D03*
Y218307D03*
Y220275D03*
Y222244D03*
Y224212D03*
Y226181D03*
Y228149D03*
Y230118D03*
Y232086D03*
Y234055D03*
Y236023D03*
Y237992D03*
Y239960D03*
Y241929D03*
Y243897D03*
Y249803D03*
Y251771D03*
Y253740D03*
Y255708D03*
Y245866D03*
Y247834D03*
Y257677D03*
Y259645D03*
Y261614D03*
Y263582D03*
Y265551D03*
Y267519D03*
X51674Y195669D03*
Y197637D03*
Y199606D03*
Y201574D03*
Y211417D03*
Y213385D03*
Y215354D03*
Y217322D03*
Y219291D03*
Y221259D03*
Y223228D03*
Y225196D03*
Y227165D03*
Y229133D03*
Y231102D03*
Y233071D03*
Y235039D03*
Y237008D03*
Y238976D03*
Y240945D03*
Y242913D03*
Y250787D03*
Y252756D03*
Y254724D03*
Y256693D03*
Y244882D03*
Y246850D03*
Y248819D03*
Y258661D03*
Y260630D03*
Y262598D03*
Y264567D03*
Y266535D03*
G54D32*
X70760Y174791D03*
X78240D03*
X74500Y183209D03*
X268260Y168291D03*
X275740D03*
X272000Y176709D03*
X456760Y259791D03*
X464240D03*
X460500Y268209D03*
G54D108*
G01X586811Y278740D02*
Y274516D01*
X586161Y273866D01*
Y263839D01*
X590111Y259889D01*
X590837D01*
G01X602166Y246456D02*
Y249945D01*
X601362Y250749D01*
Y257172D01*
X598400Y260134D01*
Y260197D01*
X598398Y260199D01*
G01X599803Y246456D02*
Y254686D01*
X596462Y258027D01*
Y263325D01*
X598300Y265163D01*
Y265400D01*
G01X592717Y246456D02*
Y250787D01*
X593317Y251387D01*
Y256600D01*
X592712Y257205D01*
Y262890D01*
X590769Y264833D01*
X590700D01*
G01X597441Y246456D02*
Y255138D01*
X594600Y257979D01*
Y260000D01*
G01X596260Y278740D02*
Y275466D01*
X598015Y273711D01*
Y268367D01*
X594848Y265200D01*
X594500D01*
G01X617519Y6656D02*
Y10096D01*
X618532Y11109D01*
Y16375D01*
X615852Y19055D01*
Y19807D01*
G01X619882Y6656D02*
Y16935D01*
X617782Y19035D01*
Y23333D01*
X616259Y24856D01*
X615907D01*
G01X613977Y246456D02*
Y255449D01*
X611691Y257735D01*
Y259372D01*
X611706Y259387D01*
G01X616339Y246456D02*
Y257239D01*
X617507Y258407D01*
Y261710D01*
X617305Y261912D01*
Y263466D01*
X619100Y265261D01*
Y265300D01*
G01X618701Y246456D02*
Y255653D01*
X619382Y256334D01*
Y260089D01*
G01X615158Y278740D02*
Y274753D01*
X615568Y274343D01*
Y271709D01*
X615417Y271558D01*
Y269969D01*
X613555Y268107D01*
Y261436D01*
X615002Y259989D01*
X615243D01*
X615532Y259700D01*
G01X612796Y278740D02*
Y275205D01*
X614218Y273783D01*
Y272269D01*
X613150Y271201D01*
X613149D01*
X611536Y269588D01*
Y264385D01*
G01X617520Y278740D02*
Y270162D01*
X615537Y268179D01*
Y264789D01*
G01X626968Y6656D02*
Y14897D01*
X625357Y16507D01*
Y23339D01*
X624257Y24439D01*
X624223D01*
X623555Y25107D01*
G01X622244Y6656D02*
Y11368D01*
X622025Y11587D01*
Y17389D01*
X619607Y19807D01*
G01X629330Y6656D02*
Y17902D01*
X627325Y19907D01*
X627231D01*
G01X631693Y6656D02*
Y11414D01*
X631525Y11582D01*
Y13225D01*
X632882Y14582D01*
Y23484D01*
X631159Y25207D01*
X630955D01*
G01X621063Y38940D02*
Y30394D01*
X619730Y29061D01*
Y24864D01*
G01X628149Y38940D02*
Y30556D01*
X627662Y30069D01*
Y25514D01*
X627255Y25107D01*
G01X630512Y38940D02*
Y30309D01*
X629130Y28927D01*
Y23186D01*
X629132Y23184D01*
Y21930D01*
X630655Y20407D01*
X630700D01*
X631000Y20107D01*
G01X625787Y38940D02*
Y34297D01*
X626075Y34009D01*
Y31782D01*
X621605Y27312D01*
Y21787D01*
X623385Y20007D01*
X623532D01*
G01X625788Y246456D02*
Y254588D01*
X626157Y254957D01*
Y259775D01*
X626682Y260300D01*
G01X623425Y246456D02*
Y255087D01*
X624807Y256469D01*
Y262210D01*
X624805Y262212D01*
Y263466D01*
X623082Y265189D01*
X622899D01*
G01X628150Y246456D02*
Y254925D01*
X632332Y259107D01*
Y263609D01*
X630809Y265132D01*
X630723D01*
X630455Y265400D01*
G01X632874Y246456D02*
Y254895D01*
X634207Y256228D01*
Y260300D01*
G01X626969Y278740D02*
Y268430D01*
X628580Y266821D01*
Y262057D01*
X630432Y260205D01*
Y260100D01*
G01X631693Y278740D02*
Y274028D01*
X631912Y273809D01*
Y267700D01*
X634280Y265332D01*
G01X624607Y278740D02*
Y267494D01*
X626501Y265600D01*
X626540D01*
X626651Y265489D01*
G01X622244Y278740D02*
Y274256D01*
X622412Y274088D01*
Y267612D01*
X621055Y266255D01*
Y261912D01*
X622778Y260189D01*
X622933D01*
G01X634055Y278740D02*
Y268245D01*
X636155Y266145D01*
Y262063D01*
X637876Y260342D01*
X638032D01*
G01X636417Y6656D02*
Y15234D01*
X638400Y17217D01*
Y20607D01*
G01X638779Y6656D02*
Y10771D01*
X638520Y11030D01*
Y15427D01*
X640382Y17289D01*
Y23960D01*
X638668Y25674D01*
X638290D01*
G01X641141Y6656D02*
Y10319D01*
X639870Y11590D01*
Y13277D01*
X642401Y15808D01*
Y20657D01*
X642451Y20707D01*
G01X635236Y38940D02*
Y34197D01*
X635424Y34009D01*
Y29931D01*
X634555Y29062D01*
Y25307D01*
G01X637598Y38940D02*
Y30195D01*
X636430Y29027D01*
Y23686D01*
X636632Y23484D01*
Y21930D01*
X635109Y20407D01*
X634957D01*
X634757Y20207D01*
G01X639960Y38940D02*
Y29947D01*
X642246Y27661D01*
Y25807D01*
G01X636418Y278740D02*
Y275818D01*
X635413Y274813D01*
Y268887D01*
X638085Y266215D01*
Y265345D01*
X638090Y265340D01*
G01X657677Y6656D02*
Y9930D01*
X655922Y11685D01*
Y17029D01*
X659367Y20474D01*
X659400D01*
G01X654134Y38940D02*
Y29317D01*
X657475Y25976D01*
Y21982D01*
X655718Y20225D01*
X655700D01*
G01X651771Y38940D02*
Y35234D01*
X652275Y34730D01*
Y28524D01*
X655576Y25223D01*
X655602D01*
G01X667126Y6656D02*
Y10880D01*
X668000Y11754D01*
Y16707D01*
X665125Y19582D01*
Y24269D01*
X663421Y25973D01*
X663202D01*
G01X656496Y38940D02*
Y35499D01*
X655484Y34487D01*
Y30524D01*
X659400Y26608D01*
Y25907D01*
G01X661220Y38940D02*
Y35027D01*
X659878Y33685D01*
Y32371D01*
X659875Y32368D01*
Y29032D01*
X661225Y27682D01*
Y22682D01*
X662951Y20956D01*
X663200D01*
G54D60*
X286900Y208000D03*
Y204000D03*
X292100Y206000D03*
G54D42*
X157545Y73450D03*
X159515D03*
X161485D03*
X163455D03*
X165425D03*
X167395D03*
X169365D03*
X171335D03*
X169365Y101750D03*
X167395D03*
X165425D03*
X163455D03*
X161485D03*
X159515D03*
X157545D03*
X171335D03*
X173305Y73450D03*
X175275D03*
X177245D03*
X179215D03*
X181185D03*
X183155D03*
X185125D03*
X187095D03*
Y101750D03*
X185125D03*
X183155D03*
X181185D03*
X179215D03*
X177245D03*
X175275D03*
X173305D03*
X191035Y73450D03*
X193005D03*
X194975D03*
X196945D03*
X198915D03*
X200885D03*
X189065D03*
X200885Y101750D03*
X198915D03*
X196945D03*
X194975D03*
X193005D03*
X191035D03*
X189065D03*
X202855Y73450D03*
Y101750D03*
G54D51*
X231760Y48820D03*
Y56180D03*
X226640D03*
Y48820D03*
X229200D03*
X274560Y145320D03*
Y152680D03*
X269440D03*
Y145320D03*
X272000D03*
X438940Y24820D03*
X444060D03*
X438940Y32180D03*
X444060D03*
X441500D03*
G54D33*
X69000Y225700D03*
X74000D03*
X69000Y230900D03*
X74000D03*
X156100Y181900D03*
Y187100D03*
X185000Y163400D03*
X174000Y163900D03*
X185000Y168600D03*
X174000Y169100D03*
X297000Y208600D03*
Y203400D03*
X326500Y244900D03*
Y250100D03*
X371500Y208100D03*
Y202900D03*
X414000Y72900D03*
Y78100D03*
X507000Y224600D03*
Y219400D03*
X596000Y236100D03*
Y230900D03*
X606000Y236100D03*
Y230900D03*
X628000Y236100D03*
Y230900D03*
X694000Y163900D03*
Y169100D03*
X742000Y67100D03*
Y61900D03*
X740000Y238600D03*
Y233400D03*
G54D24*
X25000Y190354D03*
Y271850D03*
G54D15*
G01X10636Y-27865D02*
G02I-12000J0D01*
G01X14636D02*
X-17364D01*
G01X5486D02*
G02I-6850J0D01*
G01X-1364Y-43865D02*
Y-11865D01*
G01X14636Y-43865D02*
Y-123865D01*
G01D02*
X1309236D01*
G01X14636Y-79365D02*
X1309236D01*
G01X14636Y-43865D02*
X1309236D01*
G01X66500Y37642D02*
X65542Y38600D01*
X62600D01*
X60433Y36433D01*
Y22892D01*
G01X64370Y26342D02*
Y35512D01*
X66500Y37642D01*
G01X60800Y87500D02*
Y83800D01*
X60500Y83500D01*
G01X60800Y87500D02*
Y91000D01*
G01X91500Y84000D02*
X84500D01*
X80500Y88000D01*
X76200D01*
G01X73900Y138500D02*
X86500D01*
X98500Y150500D01*
X112600D01*
X113100Y151000D01*
G01X67700Y138500D02*
X73900D01*
G01X121500Y93000D02*
X121481D01*
X111807Y83326D01*
X92174D01*
X91500Y84000D01*
G01X110166Y239500D02*
X110000D01*
X109200Y240300D01*
Y246700D01*
G01D02*
Y255000D01*
G01D02*
Y258000D01*
X109500Y258300D01*
G01X134100Y96600D02*
X131000Y93500D01*
X122000D01*
X121500Y93000D01*
G01X120800Y132300D02*
Y135400D01*
X120700Y135500D01*
G01X129000Y161000D02*
X130100Y159900D01*
Y157423D01*
X131623Y155900D01*
X149144D01*
X149819Y155225D01*
G01X129500Y252500D02*
Y255800D01*
G01X143500Y85800D02*
X151311D01*
X152811Y84300D01*
G01X143800Y109000D02*
Y106100D01*
X143700Y106000D01*
G01D02*
Y98700D01*
X143500Y98500D01*
Y96200D01*
G01D02*
X143600Y96300D01*
X157630D01*
X158105Y96775D01*
G01X154900Y157500D02*
X152625Y155225D01*
X149819D01*
G01X150500Y183000D02*
X155000D01*
X156100Y181900D01*
G01X148100Y190500D02*
X151400Y187200D01*
X151600D01*
G01X156100Y187100D02*
X151700D01*
X151600Y187200D01*
G01X157000Y207100D02*
Y212100D01*
X158700Y213800D01*
G01X153000Y201900D02*
X157000D01*
G01X146000Y231000D02*
Y228100D01*
G01X155300Y257000D02*
Y254000D01*
G01X171400Y113200D02*
X175600D01*
G01X171400D02*
Y126200D01*
X171800Y126600D01*
G01X165500Y157500D02*
X168177D01*
X170400Y159723D01*
Y166900D01*
X172600Y169100D01*
X174000D01*
G01X165500Y157500D02*
X160100D01*
G01X165700Y257000D02*
Y254000D01*
G01X174000Y169100D02*
X174600Y168500D01*
X177300D01*
X178000Y167800D01*
G01X189000Y112700D02*
Y115500D01*
X188363Y116137D01*
G01X192900Y120200D02*
Y115200D01*
G01Y120200D02*
X189013D01*
X188750Y119937D01*
G01X198100Y115200D02*
Y110200D01*
G01X195300Y230500D02*
Y233700D01*
X195000Y234000D01*
G01X213558Y98500D02*
X213584Y98526D01*
Y105484D01*
X214793Y106693D01*
X219502D01*
G01X210100Y135800D02*
Y134197D01*
X212407Y131890D01*
X219502D01*
G01X212500Y172800D02*
X213850Y174150D01*
Y179850D01*
G01X205700Y230500D02*
Y233700D01*
X206000Y234000D01*
G01X219502Y81496D02*
X225496D01*
X227000Y83000D01*
X229036D01*
G01X226500Y125416D02*
X223525Y122441D01*
X219502D01*
G01X247500Y60000D02*
Y65216D01*
X249410Y67126D01*
G01X251758Y114567D02*
X246167D01*
X244600Y113000D01*
Y107200D01*
X246682Y105118D01*
X251758D01*
G01X244463Y130655D02*
Y120989D01*
X247736Y117716D01*
X251758D01*
G01X244463Y130655D02*
X244808Y131000D01*
Y135208D01*
X251758Y142158D01*
Y149212D01*
G01Y127165D02*
X247736D01*
X246308Y128593D01*
Y128810D01*
X244463Y130655D01*
G01X251758Y149212D02*
X245288D01*
X242950Y151550D01*
Y155800D01*
G01X249410Y182480D02*
X244810Y177880D01*
Y172380D01*
X241325Y168895D01*
Y157425D01*
X242950Y155800D01*
G01X251758Y158661D02*
X247361D01*
X244500Y155800D01*
X242950D01*
G01X264189Y98252D02*
X261161D01*
X257208Y102205D01*
Y103690D01*
X255780Y105118D01*
X251758D01*
G01X285100Y129510D02*
X281190Y125600D01*
X273000D01*
X272300Y126300D01*
G01X268700D02*
X268900Y126500D01*
Y129386D01*
G01X278300Y173300D02*
X277941D01*
X276000Y171359D01*
X273973D01*
X272500Y169886D01*
Y164900D01*
X274100Y163300D01*
G01X278300Y173300D02*
X278446Y173154D01*
X287071D01*
G01X310500Y60200D02*
Y60000D01*
X311598Y58902D01*
Y57522D01*
G01X299800Y82300D02*
Y78300D01*
X300400Y77700D01*
G01X363583Y22892D02*
Y37642D01*
G01X376500Y202900D02*
X371500D01*
G01X380500Y68463D02*
X383500D01*
X388000Y72963D01*
G01X380500Y68463D02*
X375996D01*
X375596Y68063D01*
G01D02*
Y65404D01*
X377500Y63500D01*
X377850D01*
G01X376200Y77500D02*
Y73800D01*
X375600Y73200D01*
G01X421400Y78500D02*
X414400D01*
X414000Y78100D01*
G01X451300Y21700D02*
X452200Y22600D01*
Y52880D01*
X461000Y61680D01*
Y89319D01*
X470729Y99048D01*
X506930D01*
X507378Y98600D01*
X508200D01*
X509000Y97800D01*
G01D02*
X512000Y94800D01*
Y86823D01*
X514823Y84000D01*
X527633D01*
X533267Y89634D01*
G01X510000Y234300D02*
X512900D01*
X513100Y234500D01*
G01X507250Y241250D02*
X508200Y240300D01*
X517400D01*
X520000Y237700D01*
G01X505315Y268500D02*
X504000Y267185D01*
Y253000D01*
G01X521736Y-43865D02*
Y-123865D01*
G01X528300Y151500D02*
Y155700D01*
X521261Y162739D01*
G01D02*
X518200Y165800D01*
Y183400D01*
G01X525000Y234300D02*
X529200D01*
X536200Y227300D01*
X547600D01*
G01X520000Y237700D02*
X520800D01*
X524200Y234300D01*
X525000D01*
G01X552900Y89100D02*
Y97000D01*
X549900Y100000D01*
X536267D01*
X533267Y97000D01*
Y89634D01*
G01X528400Y145041D02*
X528300Y144941D01*
Y125500D01*
G01Y148500D02*
Y151500D01*
G01Y148500D02*
Y145141D01*
X528400Y145041D01*
G01X528300Y151500D02*
X585978D01*
X591400Y146078D01*
Y145800D01*
X592200Y145000D01*
G01X566000Y89100D02*
Y88500D01*
X563900Y86400D01*
X554900D01*
X552900Y88400D01*
Y89100D01*
G01X561196Y227366D02*
X547666D01*
X547600Y227300D01*
G01X566000Y89100D02*
X568600Y86500D01*
X576077D01*
X578400Y88823D01*
Y89100D01*
G01X586800Y213200D02*
X582200D01*
X579000Y210000D01*
X558300D01*
G01D02*
X557996Y210304D01*
Y224166D01*
X561196Y227366D01*
G01X624726Y107395D02*
X622831Y105500D01*
X599998D01*
X583598Y89100D01*
X578400D01*
G01X610300Y211000D02*
Y211605D01*
X605605Y216300D01*
X589900D01*
X586800Y213200D01*
G01X599500Y87500D02*
X624000D01*
X634000Y97500D01*
G01X608300Y144890D02*
X605393Y147797D01*
X594540D01*
X592900Y146157D01*
Y145700D01*
X592200Y145000D01*
G01X648500Y144000D02*
X647000Y142500D01*
X610690D01*
X608300Y144890D01*
G01X622873Y204200D02*
X616073Y211000D01*
X610300D01*
G01X635000Y110500D02*
X627831D01*
X624726Y107395D01*
G01X622873Y204200D02*
X625678D01*
X631678Y210200D01*
X674977D01*
X678638Y206539D01*
G01X640677Y91115D02*
X641300Y91738D01*
Y98200D01*
X638000Y101500D01*
Y103000D01*
G01D02*
X635000Y106000D01*
Y110500D01*
G01X656200Y144000D02*
X648500D01*
G01X659236Y-43865D02*
Y-123865D01*
G01X663800Y199900D02*
X664600Y199100D01*
X671199D01*
X678638Y206539D01*
G01D02*
X700445Y184732D01*
Y184600D01*
X701245Y183800D01*
G01X740300Y164700D02*
X733000Y172000D01*
Y176200D01*
G01X758003Y141303D02*
X754500Y137800D01*
Y118500D01*
X761000Y112000D01*
X765500D01*
G01X751500Y111700D02*
X754000Y114200D01*
Y115100D01*
G01X751500Y108300D02*
X754200D01*
X756400Y110500D01*
G01X767500Y128800D02*
X762000D01*
X757900Y124700D01*
G01X762000Y144400D02*
X761100D01*
X758003Y141303D01*
G01X757000Y149000D02*
X761400D01*
X762000Y149600D01*
G01X743100Y195500D02*
X747700D01*
X767700Y175500D01*
X773300D01*
X777800Y171000D01*
G01X767500Y122200D02*
Y115000D01*
X768500Y114000D01*
G01X772547Y135627D02*
Y131447D01*
X769900Y128800D01*
X767500D01*
G01X762200Y135200D02*
X759400Y132400D01*
Y131000D01*
G01X769800Y133000D02*
X767600Y135200D01*
X762200D01*
G01X762000Y144400D02*
X768700D01*
G01X762000Y149600D02*
X766700D01*
G01X762000D02*
Y154669D01*
G01X770700Y149600D02*
X774300D01*
X777000Y146900D01*
G01X771300Y140200D02*
X772500Y139000D01*
X775300D01*
G01X770700Y149600D02*
Y153600D01*
X770600Y153700D01*
G01X774236Y-43865D02*
Y-123865D01*
G01X775800Y133000D02*
Y133822D01*
X777878Y135900D01*
X780900D01*
X782000Y137000D01*
G01X775800Y129500D02*
Y133000D01*
G01Y126000D02*
Y129500D01*
G01Y122500D02*
Y126000D01*
G01X777000Y146900D02*
X775300Y145200D01*
Y139000D01*
G01X777800Y165000D02*
Y162000D01*
G01Y168000D02*
Y165000D01*
G01Y171000D02*
Y168000D01*
G01X801700Y121500D02*
X799000D01*
G01X801700Y125000D02*
X799500D01*
X799000Y125500D01*
G01X801900Y155300D02*
Y156500D01*
X800400Y158000D01*
Y158500D01*
G01X802600Y166700D02*
X802000D01*
X799900Y168800D01*
G01X793000Y174500D02*
X794100Y173400D01*
X797000D01*
G01X803200Y179500D02*
X797900D01*
X797000Y178600D01*
G01X803200Y179500D02*
X808900D01*
G01X803300Y279500D02*
X805000D01*
X809500Y275000D01*
X810100D01*
G01X815200Y156300D02*
X812300Y153400D01*
X807400D01*
X805500Y155300D01*
G01X941736Y-43865D02*
Y-123865D01*
G01X1111736Y-43865D02*
Y-123865D01*
G01X1309236Y-43865D02*
Y-123865D01*
G01X1341236Y-27865D02*
X1309236D01*
G01X1337236D02*
G02I-12000J0D01*
G01X1332086D02*
G02I-6850J0D01*
G01X1325236Y-43865D02*
Y-11865D01*
X17500Y190200D03*
X17301Y212401D03*
X16844Y203100D03*
X17300Y218307D03*
X10000Y229500D03*
X16400Y224212D03*
X16118Y230118D03*
X10194Y243106D03*
X9500Y234200D03*
X13090Y231129D03*
Y234899D03*
X7600Y240861D03*
Y237091D03*
X16899Y241929D03*
X16300Y236023D03*
X13590Y242940D03*
X10190Y258510D03*
X10194Y254917D03*
X10190Y246699D03*
X16899Y247834D03*
Y253740D03*
X13590Y254751D03*
X7600Y252672D03*
X16899Y259645D03*
X7600Y248902D03*
Y260713D03*
X13590Y258521D03*
Y246710D03*
X16900Y269000D03*
X7600Y264483D03*
Y268100D03*
X16899Y265551D03*
X28400Y81400D03*
X32800Y120400D03*
X25800Y120300D03*
X29200D03*
X30000Y136000D03*
X29700Y141200D03*
X26500Y181800D03*
X33500Y178100D03*
X33150Y181500D03*
X29400Y180000D03*
X23100Y181800D03*
X30000Y196200D03*
X33500Y196100D03*
X21900Y205400D03*
X31500Y207500D03*
X32000Y203200D03*
Y199300D03*
X41200Y90300D03*
X42000Y96000D03*
X41500Y100800D03*
X40500Y127700D03*
Y124300D03*
X38500Y148000D03*
X48500D03*
X41000Y152300D03*
Y143300D03*
X46000D03*
Y152300D03*
X43500Y148000D03*
Y138500D03*
X48500D03*
X38500D03*
X45800Y158100D03*
X37600Y198800D03*
X34800D03*
X37900Y195300D03*
X40400Y212700D03*
X34800Y208300D03*
X40400Y207800D03*
X34800Y203700D03*
X37600Y212700D03*
X34800Y212200D03*
X37600Y207800D03*
Y203700D03*
X34500Y216000D03*
X40400Y217100D03*
X40700Y224000D03*
X44861Y227261D03*
X37900Y219000D03*
Y222500D03*
Y229500D03*
Y226000D03*
X40200Y238300D03*
Y231300D03*
X37900Y240000D03*
Y243500D03*
X40200Y245300D03*
X37900Y233000D03*
X38000Y236500D03*
X44400Y250400D03*
X40500Y260000D03*
X37900Y257500D03*
Y254000D03*
X40600Y252500D03*
X37900Y247000D03*
X38000Y250500D03*
X46800Y274500D03*
X62900Y79900D03*
X60800Y87500D03*
X52500Y96500D03*
Y106500D03*
X57500Y96500D03*
X60000Y101500D03*
X50000D03*
X55000D03*
X57500Y106500D03*
X53500Y120400D03*
X60000Y111300D03*
X50000D03*
X55000D03*
X57600Y136900D03*
X56100Y130700D03*
X52643Y130800D03*
X58000Y141750D03*
X58800Y177000D03*
X54700Y192200D03*
X52700Y184800D03*
X62800Y184300D03*
X51860Y187640D03*
Y191410D03*
X59379Y184380D03*
X55720D03*
X57600Y214200D03*
X57400Y210700D03*
X57009Y230009D03*
X57600Y226600D03*
X57500Y223200D03*
X57287Y219806D03*
X56724Y243300D03*
X56800Y249613D03*
X58102Y246471D03*
X57800Y253900D03*
X50000Y270000D03*
X57800Y264100D03*
X64700Y272500D03*
X57800Y267500D03*
X80031Y40357D03*
X76411D03*
X74000Y37642D03*
X66500D03*
X79700Y67500D03*
X79115Y60979D03*
X78300Y64300D03*
X69235Y99735D03*
X68200Y94900D03*
Y91500D03*
X66500Y128000D03*
X65500Y123800D03*
X74800Y191000D03*
X72137Y210237D03*
X79500Y230000D03*
X72600Y244800D03*
X78700Y259800D03*
X75600Y246700D03*
X79000Y246900D03*
X69400Y246000D03*
X67600Y255800D03*
X75300Y259900D03*
X66300Y259300D03*
X78200Y275600D03*
X71800Y268800D03*
X66800Y275200D03*
X74000Y271400D03*
X67000Y263200D03*
X82211Y37747D03*
X92159Y40357D03*
X89862Y37849D03*
X89400Y58200D03*
X83600Y57600D03*
X88700Y54400D03*
X85300D03*
X90600Y63200D03*
X94000Y63300D03*
X82885Y60979D03*
X90000Y91000D03*
X91500Y84000D03*
X94500Y76200D03*
X89800Y87300D03*
X86100Y97700D03*
X90500Y101000D03*
X86500Y113500D03*
X80500D03*
X85500Y135400D03*
X83500Y191000D03*
X86900D03*
X84700Y197100D03*
X92900Y204008D03*
X89500Y204000D03*
X85898Y200598D03*
X95200Y216200D03*
X90812Y215000D03*
X80563Y214700D03*
X84500Y230000D03*
X89500D03*
X84500Y225000D03*
Y235000D03*
X88900Y246700D03*
X82400Y246600D03*
X82100Y259600D03*
X80500Y269500D03*
X91400Y270300D03*
X83900Y269500D03*
X95779Y40357D03*
X98500Y37642D03*
X107907Y40357D03*
X105794Y37692D03*
X109700Y60000D03*
X104400Y57700D03*
X96800Y53300D03*
X103450Y54400D03*
X100050D03*
X109600Y63700D03*
X96200Y60700D03*
X97900Y76200D03*
X106100Y158700D03*
X95700Y197200D03*
X97100Y189200D03*
X110000Y201900D03*
X107740Y204460D03*
X102000Y203200D03*
X99600Y225700D03*
X100600Y221100D03*
X110166Y239500D03*
X99328Y235370D03*
X109000Y231400D03*
X109500Y258300D03*
X97600Y246500D03*
X104900Y248800D03*
X120000Y40700D03*
X113605Y37665D03*
X121500Y37642D03*
X123655Y40357D03*
X111527D03*
X121400Y60100D03*
X120200Y45610D03*
X119200Y57400D03*
X115800D03*
X111200Y67200D03*
X114800Y60700D03*
X121170Y80900D03*
X121295Y77502D03*
X126000Y86200D03*
X125787Y78813D03*
X120700Y135500D03*
X118500Y125500D03*
X112550Y142800D03*
X119600Y143300D03*
X120500Y139000D03*
X125000Y178000D03*
X119760Y191419D03*
X115760D03*
X123760D03*
X111900Y209000D03*
X112800Y225400D03*
X112700Y221200D03*
Y231400D03*
X136600Y44800D03*
X139403Y40357D03*
X129336Y37652D03*
X127275Y40357D03*
X137300Y37642D03*
X138000Y49800D03*
X138574Y57924D03*
X131600Y57400D03*
X135000D03*
X136400Y60600D03*
X130400D03*
X136469Y89902D03*
X130315Y90533D03*
X134200Y86100D03*
X137138Y76512D03*
X129300Y84900D03*
X136600Y93300D03*
X133558Y91779D03*
X136500Y104923D03*
Y101523D03*
X130000Y121000D03*
X136770Y113000D03*
X136540Y108620D03*
X133975Y129141D03*
X130563Y125200D03*
X127500Y129180D03*
X126950Y125200D03*
X133786Y134700D03*
X130300Y135000D03*
X136500Y126300D03*
X135412Y141400D03*
X138600Y146300D03*
X131500Y149000D03*
X136156Y138025D03*
X131762Y141796D03*
X127200Y158700D03*
X137300Y158900D03*
X132700Y158600D03*
X140800Y158900D03*
X140000Y195500D03*
X137100Y188900D03*
X128000Y203300D03*
X143023Y40357D03*
X153088Y37653D03*
X145070Y37642D03*
X155151Y40357D03*
X144995Y57995D03*
X143700Y54503D03*
X154615Y54500D03*
X155290Y48610D03*
X143688Y48350D03*
X147400Y60400D03*
X147315Y54400D03*
X150715D03*
X153000Y67800D03*
X152811Y84300D03*
X150894Y76497D03*
X154294Y76506D03*
X150670Y102720D03*
X154550Y106200D03*
X151080Y99344D03*
X154550Y102800D03*
X157175Y115462D03*
X150670Y115500D03*
Y118900D03*
Y112100D03*
X157229Y119218D03*
X150670Y122300D03*
X153693Y124807D03*
X147808Y145208D03*
X142900Y138595D03*
X146400D03*
X150804Y158896D03*
X144500Y158900D03*
X150500Y183000D03*
X157000Y169194D03*
X146980Y200580D03*
X153000Y201900D03*
X153500Y210000D03*
X146396Y207675D03*
X142997Y207891D03*
X150000Y210100D03*
X146500Y236500D03*
X146000Y231000D03*
X155300Y254000D03*
X144200Y270700D03*
X168791Y37689D03*
X158771Y40357D03*
X170899D03*
X160898Y37704D03*
X169600Y53000D03*
X159957Y51932D03*
X159060Y48610D03*
X170290Y49600D03*
X166463Y54400D03*
X163063D03*
X167500Y68000D03*
X164000Y65000D03*
X158105Y96775D03*
X172199Y91591D03*
X172300Y107189D03*
X158305Y112180D03*
X171800Y126600D03*
X157500Y149025D03*
X162900Y152200D03*
X158500Y161820D03*
X161900Y161700D03*
X167602Y160684D03*
X167581Y164084D03*
X170910Y173840D03*
X167140D03*
X165900Y181500D03*
X163700Y178900D03*
X169800Y181448D03*
X165700Y203400D03*
X162000Y226000D03*
X167000D03*
Y221500D03*
X162000D03*
Y230500D03*
X167000D03*
X162000Y235000D03*
X165700Y254000D03*
X174519Y40357D03*
X176640Y37699D03*
X184500Y37700D03*
X186647Y40357D03*
X185000Y51600D03*
X175758Y52879D03*
X174060Y49600D03*
X186865Y54300D03*
X181800Y54400D03*
X179000D03*
X179800Y65700D03*
X176900Y67500D03*
X180700Y78500D03*
X184300D03*
X174900Y77700D03*
X183726Y106353D03*
X187500Y106500D03*
X173000Y97000D03*
X183344Y94056D03*
X179400Y94200D03*
X181732Y97500D03*
X178000Y97300D03*
X175787Y127000D03*
X177200Y130575D03*
X187597Y133697D03*
X176700Y144875D03*
X177200Y148700D03*
X181000Y167500D03*
X180931Y172985D03*
X177159Y172900D03*
X176400Y175700D03*
X186300Y172400D03*
X185546Y192509D03*
X180546D03*
X175546D03*
X174739Y207381D03*
X177500Y209500D03*
X187000D03*
X176800Y241600D03*
X198073Y40395D03*
X194445D03*
X192400Y37642D03*
X200300D03*
X190267Y40357D03*
X191700Y52100D03*
X201500Y54500D03*
X189700Y54300D03*
X197700Y54400D03*
X194700D03*
X190100Y68700D03*
X196900D03*
X193500D03*
X194075Y80360D03*
X197845D03*
X202200Y89500D03*
X198500Y83800D03*
X193485Y83724D03*
X191500Y94100D03*
X188900Y91800D03*
X202500Y97000D03*
X193005Y97155D03*
X195989Y95300D03*
X189106Y97235D03*
X188363Y116137D03*
X201650Y111200D03*
X201899Y134200D03*
X194900Y124200D03*
X197140Y152010D03*
X194623Y149723D03*
X201252Y137766D03*
X192237Y147300D03*
X199900Y154200D03*
X191200Y181068D03*
X200900Y177000D03*
X199441Y187547D03*
X199392Y190947D03*
X202761Y186811D03*
X195630Y192770D03*
X202800Y191400D03*
X196000Y186897D03*
X198198Y206374D03*
X194800Y206100D03*
X201596Y206504D03*
X191400Y206100D03*
X195000Y234000D03*
X207600Y37642D03*
X216085Y37649D03*
X210900Y57600D03*
X205300Y54900D03*
X208700D03*
X214942Y67242D03*
X211600Y82100D03*
X212300Y85500D03*
X207200Y106000D03*
X213558Y98500D03*
X205689Y112879D03*
X205850Y118175D03*
X209259Y113771D03*
Y117430D03*
X206605Y121741D03*
X209900Y120900D03*
X205380Y134200D03*
X210100Y135800D03*
X210547Y139028D03*
X206790Y139040D03*
X213850Y179850D03*
X215100Y194200D03*
X207861Y188540D03*
X215100Y199400D03*
X205000Y206500D03*
X215384Y202984D03*
X205920Y221550D03*
X216000Y219500D03*
X208800D03*
X212500D03*
X206000Y234000D03*
X229300Y42950D03*
X232591Y43057D03*
X219900Y39100D03*
X223868Y37686D03*
X231780Y37691D03*
X223475Y53300D03*
X219899Y56800D03*
X233981Y59125D03*
X221400Y64500D03*
X230400Y63000D03*
X223800Y61700D03*
X230000Y66400D03*
X229036Y83000D03*
X226500Y94450D03*
X227850Y97575D03*
X230875Y106300D03*
X227894Y104600D03*
X232600Y95300D03*
X227800Y101200D03*
X233452Y108588D03*
X228000Y108304D03*
X231562Y143827D03*
X231611Y138336D03*
X226452Y147300D03*
X228000Y139700D03*
X232921Y167505D03*
X233350Y180700D03*
X227870Y170252D03*
X224200Y180200D03*
X232225Y193275D03*
X232560Y204250D03*
X227000Y275500D03*
X236211Y43057D03*
X239599Y37673D03*
X245385Y40357D03*
X241765D03*
X247500Y37642D03*
X244400Y50600D03*
X238800Y45300D03*
X240200Y59275D03*
X247500Y60000D03*
X235400Y63400D03*
X240297D03*
X243200Y73700D03*
X240300Y67200D03*
X246600Y73700D03*
X244759Y85200D03*
X236700Y88500D03*
X241200Y94900D03*
X244800Y100700D03*
X235075Y105600D03*
X244463Y130655D03*
X234875Y139290D03*
Y143060D03*
X244715Y159785D03*
X242950Y155800D03*
X239900Y180600D03*
X247596Y174667D03*
X236477Y179357D03*
X240119Y183993D03*
X240100Y191000D03*
X236861Y184967D03*
X246689Y196687D03*
X254600Y41100D03*
X261900Y44900D03*
X265140Y40490D03*
X255000Y37642D03*
X263100Y37700D03*
X264700Y59400D03*
X256200Y59200D03*
X259000Y57800D03*
X250500Y57900D03*
X262000Y57800D03*
X253500Y57900D03*
X264500Y73100D03*
X253700Y75875D03*
X250300Y73800D03*
X264125Y79350D03*
X264189Y98252D03*
X259820Y103454D03*
X262131Y100959D03*
X258634Y95850D03*
X263775Y140327D03*
X257977Y163423D03*
X264600Y173100D03*
X257687Y169870D03*
X253500Y174360D03*
X261300Y188300D03*
X253300Y189834D03*
X262700Y191500D03*
X261200Y209700D03*
X263600Y239850D03*
Y252700D03*
X257500Y266645D03*
X260500Y264630D03*
X269800Y44800D03*
X275300Y44900D03*
X278700Y44800D03*
X271000Y37800D03*
X278800Y37700D03*
X268910Y40490D03*
X278868Y56000D03*
X274000Y55800D03*
X271000Y57500D03*
X268000D03*
X275200Y78700D03*
X275900Y88200D03*
X280100Y89100D03*
X268928Y112625D03*
X272200Y108352D03*
X268895Y107350D03*
X272185Y111831D03*
X278075Y116475D03*
X272300Y129442D03*
X268900Y129386D03*
X280400Y129225D03*
X272300Y149900D03*
X267187Y149800D03*
X268300Y141869D03*
X278000Y141900D03*
X273900Y156198D03*
X270500Y163200D03*
X274100Y163300D03*
X267456Y160156D03*
X267100Y156200D03*
X272380Y159240D03*
X270500Y156250D03*
X268283Y173035D03*
X278300Y173300D03*
X269772Y188274D03*
X276910Y189400D03*
X273060Y189374D03*
X266140Y191850D03*
X270341Y211835D03*
X278450Y216800D03*
X265259Y216659D03*
X270774Y222226D03*
X274700Y222100D03*
X275400Y237900D03*
X267275Y253400D03*
X265500Y249300D03*
X269800Y250700D03*
X278700Y254240D03*
X275300Y254100D03*
X267000Y271300D03*
X284758Y40490D03*
X280988D03*
X286900Y37800D03*
X294500Y37900D03*
X292500Y60500D03*
X284000Y55800D03*
X286800Y57900D03*
X290200D03*
X288700Y71100D03*
X292100D03*
X295300Y66200D03*
X288400Y94200D03*
X288100Y99500D03*
X281005Y99105D03*
X281475Y116475D03*
X286500Y119900D03*
X286600Y136000D03*
X285100Y129510D03*
X281500Y142100D03*
X295900Y154200D03*
X287071Y173154D03*
X282950Y181350D03*
X282460Y189400D03*
X286300Y191885D03*
X287700Y211900D03*
X293300Y212400D03*
X291201Y225025D03*
X287802Y225200D03*
X295300Y238100D03*
X287600D03*
X287400Y254100D03*
X295500Y253500D03*
X285000Y261700D03*
X281599Y261799D03*
X287250Y269250D03*
X310348Y37900D03*
X296736Y40490D03*
X300506D03*
X302600Y37800D03*
X302400Y59500D03*
X300900Y46900D03*
X308200Y57400D03*
X304800D03*
X297150Y91100D03*
X309400Y82100D03*
X299800Y85950D03*
Y82300D03*
X304400Y88400D03*
X306100Y90600D03*
X301300Y97000D03*
X301600Y93300D03*
X303400Y98500D03*
X303376Y95200D03*
X299300Y98500D03*
X296564Y136311D03*
Y127500D03*
X296531Y133061D03*
X301109Y146156D03*
X300700Y142850D03*
X297000Y160200D03*
X307231Y164059D03*
X297250Y163700D03*
X310579Y182800D03*
X306612Y171882D03*
X304400Y182000D03*
X302591Y173906D03*
X309112Y171960D03*
X309200Y180500D03*
X305091Y173888D03*
X301745Y181788D03*
X307200Y182000D03*
X296600Y189100D03*
X305300Y203125D03*
X307300Y224900D03*
X304400D03*
X309900D03*
X298900Y253300D03*
X309400Y253600D03*
X306000D03*
X302600D03*
X304300Y262900D03*
X309000Y266700D03*
X311300Y277800D03*
X321900Y44000D03*
X326096Y37900D03*
X318048Y37700D03*
X312484Y40690D03*
X316254D03*
X314800Y48625D03*
X311950Y50800D03*
X320400Y48600D03*
X311598Y57522D03*
X322548Y58300D03*
X324000Y54900D03*
X324176Y48600D03*
X315800Y57400D03*
X319200D03*
X323882Y71643D03*
X318882D03*
X312400Y79700D03*
X312150Y100682D03*
X326000Y254100D03*
X315500D03*
X322500Y254200D03*
X319000D03*
X311400Y269200D03*
X326100Y267000D03*
X322000Y264300D03*
X318600D03*
X313824Y280255D03*
X316945Y281606D03*
X316400Y276800D03*
X319400Y278800D03*
X322700Y277700D03*
X321600Y282500D03*
X325100Y281500D03*
X331931Y40995D03*
X328303D03*
X333700Y38000D03*
X331300Y48475D03*
X327577D03*
X328300Y58200D03*
X327400Y54900D03*
X333600Y63800D03*
X337000Y74202D03*
X328882Y71643D03*
X356432Y43657D03*
X356971Y37700D03*
X349900Y263800D03*
X342600Y277900D03*
X364600Y44298D03*
X363583Y37642D03*
X367497Y41042D03*
X363604D03*
X371457Y37642D03*
X367520D03*
X366484Y47129D03*
X362626Y47068D03*
X366700Y68700D03*
X369500Y237200D03*
Y240600D03*
X373000Y242300D03*
X369500Y234600D03*
X373000Y236000D03*
Y238900D03*
X369500Y244000D03*
X365800Y264900D03*
X362400D03*
X369300D03*
X375400Y37700D03*
X385300Y47000D03*
X388000Y72963D03*
X382700Y275300D03*
X380000Y263461D03*
X383500D03*
X376500D03*
X386100Y275300D03*
X379300D03*
X394229Y241128D03*
X391788Y238760D03*
X393000Y236200D03*
X397400Y239700D03*
X399438Y243839D03*
X401838Y246248D03*
X390500Y268800D03*
X393000Y275000D03*
X400900Y273000D03*
X391000Y265000D03*
X389500Y275300D03*
X405700Y246500D03*
X417000Y258000D03*
X416128Y272896D03*
X425400Y9103D03*
X422000D03*
X428800D03*
X432200D03*
X430500Y17000D03*
X430000Y21500D03*
Y27358D03*
X424543Y22208D03*
Y27900D03*
X426405Y25054D03*
X427000Y17000D03*
X423500Y16885D03*
X423000Y43900D03*
X430000Y30758D03*
X424536Y34800D03*
X430000Y34158D03*
X424599Y31300D03*
X422986Y40350D03*
X430000Y244450D03*
X426600D03*
X420000Y244000D03*
X420500Y257800D03*
X433129Y245783D03*
X423600Y246700D03*
X423900Y257500D03*
X423000Y274000D03*
X433300Y274100D03*
X426600D03*
X429900Y274940D03*
X442100Y7006D03*
X437061Y10393D03*
X434900Y6925D03*
X446800Y9900D03*
X438300Y6925D03*
X449600Y5900D03*
X446200D03*
X446100Y18700D03*
X441390Y28680D03*
X444783Y28451D03*
X436240Y26300D03*
X449734Y18681D03*
X441281Y17025D03*
X436100Y30900D03*
X436106Y34506D03*
X435700Y243250D03*
X445300Y274400D03*
X440600Y274300D03*
X449400Y273700D03*
X436600Y275000D03*
X450200Y9800D03*
X451300Y21700D03*
X451000Y257413D03*
X464000Y275200D03*
X456300Y275300D03*
X460400Y275200D03*
X452500D03*
X480400Y154050D03*
X467100Y154200D03*
X477000Y154050D03*
X470100Y154200D03*
X473500Y154050D03*
X467700Y245500D03*
X469000Y275200D03*
X472400Y275100D03*
X466500Y272800D03*
X472101Y266090D03*
X475500Y265900D03*
X479000D03*
X493000Y119299D03*
X483800Y154050D03*
X487200Y154100D03*
X495400Y183500D03*
X482400Y266200D03*
X502000Y89000D03*
X498500Y88995D03*
X508000Y119500D03*
X511500D03*
X511200Y183400D03*
X500900D03*
X504400D03*
X510675Y209700D03*
X505315Y268500D03*
X497002Y275400D03*
X525740Y88960D03*
X522280Y89810D03*
X515502Y88998D03*
X518902Y88987D03*
X524700Y119500D03*
X515000Y119270D03*
X524700Y145041D03*
X518200Y183400D03*
X526600Y183500D03*
X514800Y183400D03*
X513100Y234500D03*
X516500D03*
X528985Y89975D03*
X533267Y89634D03*
X539574Y88990D03*
X533000Y119500D03*
X536400D03*
X528100D03*
X528400Y145041D03*
X541550Y183550D03*
X534750Y183600D03*
X538150D03*
X530214Y183481D03*
X531500Y219500D03*
X531000Y228350D03*
X541500Y234900D03*
X551800Y69600D03*
X548400Y69700D03*
X555199D03*
X556500Y89000D03*
X546349Y89512D03*
X552900Y89100D03*
X542950Y89400D03*
X552100Y136000D03*
X557100D03*
X555500Y183500D03*
X548354Y183600D03*
X544954D03*
X551754D03*
X548300Y209700D03*
X551700Y209800D03*
X550400Y222285D03*
X561999Y69700D03*
X558599D03*
X570715Y89100D03*
X566000D03*
X572100Y136000D03*
X567100D03*
X562000Y127800D03*
X562100Y136000D03*
X562000Y144900D03*
X572845Y183300D03*
X566897Y183405D03*
X561900Y183600D03*
X564398Y183481D03*
X569395Y183300D03*
X558915Y183603D03*
X558300Y210000D03*
X561000Y222700D03*
X561196Y227366D03*
X569200Y223600D03*
X564200Y224000D03*
X575000Y89100D03*
X587500Y88913D03*
X578400Y89100D03*
X588600Y124700D03*
X584800Y183300D03*
X582254Y183313D03*
X576295Y183400D03*
X588475Y183300D03*
X578795D03*
X573600Y190100D03*
X586800Y213200D03*
X583800Y207200D03*
X580350Y207250D03*
X599500Y87500D03*
X590898Y89045D03*
X596845Y89624D03*
X599300Y119270D03*
X593400Y126000D03*
X588800Y145000D03*
X592200D03*
X599200D03*
X595744Y145041D03*
X599150Y180300D03*
X593475Y183275D03*
X601750Y182500D03*
X590975Y183275D03*
X594350Y187725D03*
X591850D03*
X588800Y205900D03*
X591363Y208387D03*
X602800Y203225D03*
X601200Y207700D03*
X603964Y210400D03*
X612120Y121750D03*
X608360Y121800D03*
X617700Y125500D03*
X608300Y144890D03*
X618500Y159000D03*
X605600Y186650D03*
X609345Y190100D03*
X607500Y188300D03*
X616100Y197400D03*
X634000Y97500D03*
X630700Y100500D03*
X627500Y104900D03*
X620000Y112575D03*
X624726Y107395D03*
X621100Y124900D03*
X625500Y159000D03*
X629000D03*
X622000D03*
X633319Y155008D03*
X631900Y175850D03*
X634748Y177708D03*
X633100Y198300D03*
X626300Y198250D03*
X629700Y198300D03*
X622873Y204200D03*
X642823Y88477D03*
X640677Y91115D03*
X638500Y94000D03*
X635000Y110500D03*
X638000Y107400D03*
X639500Y136490D03*
X648500Y144000D03*
X636719Y154972D03*
X643500Y155000D03*
X648500Y162600D03*
X640110Y155272D03*
X640461Y181410D03*
X642600Y186400D03*
X646000D03*
X636500Y198300D03*
X653600Y122400D03*
X656477Y148033D03*
X656642Y151430D03*
X656200Y144000D03*
X661600Y156700D03*
X650500Y155000D03*
X661000Y173800D03*
X657722Y193800D03*
X661600Y197300D03*
X654851Y191978D03*
X663800Y199900D03*
X654100Y221800D03*
X673100Y179455D03*
X676200Y181600D03*
X673044Y190456D03*
X668732Y204555D03*
X666446Y202037D03*
X682600Y114300D03*
X684700Y179800D03*
X689400Y178900D03*
X689547Y175500D03*
X686700Y187400D03*
X687456Y183944D03*
X694600Y229800D03*
X705145Y93500D03*
X707209Y97500D03*
X698970Y118149D03*
X699241Y114759D03*
X709500Y143500D03*
X709900Y139900D03*
X698000Y181500D03*
X701245Y183800D03*
X704700D03*
X718900Y94000D03*
X726800Y95500D03*
X724200Y108400D03*
X714000Y118500D03*
X727448Y128893D03*
X715700Y124200D03*
X714900Y131900D03*
X727187Y140000D03*
X718200Y147000D03*
Y150400D03*
X718825Y155453D03*
X712700Y155978D03*
X724400Y176025D03*
X717000Y187500D03*
X725500Y195500D03*
X715500Y205837D03*
X727400Y227400D03*
X738000Y65700D03*
X738500Y90000D03*
X731340Y82515D03*
X736900Y98500D03*
X730200Y94900D03*
X739500Y114900D03*
X742100Y118200D03*
X736300Y118000D03*
X729400Y120200D03*
X732000Y122700D03*
X728900Y132976D03*
X727800Y136600D03*
X741104Y133763D03*
X740300Y164700D03*
X736900Y162300D03*
X729500D03*
X733400D03*
X727800Y176600D03*
X733000Y176200D03*
X737000Y188315D03*
X739900Y212800D03*
X734000Y205000D03*
X731000Y210200D03*
X739800Y216300D03*
X750100Y16100D03*
X752500Y49007D03*
X756000Y106000D03*
X749500Y101500D03*
X751300Y118200D03*
X754000Y115100D03*
X748800Y115800D03*
X758176Y135024D03*
X757900Y124700D03*
X745104Y129763D03*
X749104Y133763D03*
X745104D03*
X752191Y146613D03*
X745104Y137763D03*
X747000Y162000D03*
X750500D03*
X746000Y182300D03*
X743100Y195500D03*
X743000Y211000D03*
X744100Y221900D03*
X743800Y215900D03*
X758916Y104250D03*
X762304Y103957D03*
X768500Y114000D03*
X765500Y112000D03*
X769800Y133000D03*
X759400Y131000D03*
X771300Y140200D03*
X766600Y139800D03*
X762000Y281000D03*
X765400D03*
X774500Y31307D03*
X778000D03*
X779000Y142000D03*
X788515Y144060D03*
X784515D03*
X787600Y183300D03*
X787800Y179900D03*
X796515Y144060D03*
X792515D03*
X800515D03*
Y148060D03*
X796515D03*
X792515D03*
X793000Y174500D03*
X805500Y128000D03*
G54D16*
X32500Y90700D03*
Y87300D03*
X35500Y90700D03*
Y87300D03*
X61000Y135300D03*
Y138700D03*
X64500Y87700D03*
Y84300D03*
X78000Y242200D03*
Y238800D03*
X87800Y211800D03*
Y215200D03*
X92800Y224700D03*
Y221300D03*
X88200Y242200D03*
Y238800D03*
X88000Y256700D03*
Y253300D03*
X121000Y212700D03*
Y209300D03*
X127500Y101200D03*
Y97800D03*
X143500Y82200D03*
Y78800D03*
Y96200D03*
Y92800D03*
X164900Y110100D03*
Y106700D03*
X167900Y110100D03*
Y106700D03*
X175600Y113200D03*
Y109800D03*
X184600Y113200D03*
Y109800D03*
X189000Y112700D03*
Y109300D03*
X195000Y172700D03*
Y169300D03*
X209000Y51700D03*
Y48300D03*
X212000Y51700D03*
Y48300D03*
X207400Y94500D03*
Y91100D03*
X218100Y198400D03*
Y195000D03*
X236500Y54200D03*
Y50800D03*
X239500Y54200D03*
Y50800D03*
X261300Y90200D03*
Y93600D03*
X264100Y151400D03*
Y154800D03*
X278500Y104100D03*
Y107500D03*
X278600Y149300D03*
Y145900D03*
X274000Y182800D03*
X277400Y181200D03*
Y177800D03*
X274000Y186200D03*
X293200Y151000D03*
Y154400D03*
X280500Y212200D03*
Y208800D03*
X304500Y85200D03*
Y81800D03*
X308700Y104500D03*
Y101100D03*
X297500Y146200D03*
Y142800D03*
X325100Y109900D03*
Y106500D03*
X322500Y250700D03*
Y247300D03*
X319000Y250700D03*
Y247300D03*
X315500Y250700D03*
Y247300D03*
X328100Y115500D03*
Y112100D03*
X336000Y110700D03*
Y107300D03*
X344500Y135900D03*
Y139300D03*
X353000Y156200D03*
Y152800D03*
X351000Y180300D03*
X349500Y175200D03*
Y171800D03*
X356000Y172000D03*
Y168600D03*
X351000Y183700D03*
X398300Y177500D03*
Y174100D03*
X396000Y203700D03*
Y200300D03*
Y210700D03*
Y207300D03*
X388500Y204200D03*
Y200800D03*
X395000Y253200D03*
Y249800D03*
X410000Y126763D03*
Y123363D03*
X433500Y24200D03*
Y20800D03*
X433000Y120363D03*
Y123763D03*
X472000Y258200D03*
Y254800D03*
X468500Y258200D03*
Y254800D03*
X509000Y101200D03*
Y97800D03*
X525000Y237700D03*
Y234300D03*
X538500Y238700D03*
Y235300D03*
X573500Y178700D03*
Y175300D03*
X576500Y178700D03*
Y175300D03*
X698000Y165800D03*
Y169200D03*
X725200Y119900D03*
Y116500D03*
X738300Y126600D03*
Y123200D03*
X742500Y111700D03*
Y108300D03*
X745500Y111700D03*
Y108300D03*
X749500Y126200D03*
Y122800D03*
X778000Y20100D03*
Y16700D03*
X775000Y20100D03*
Y16700D03*
G54D25*
X35000Y99000D03*
X75500Y91500D03*
X67500Y132500D03*
X71000Y222000D03*
X88500Y110000D03*
X136000Y201000D03*
X147000Y106000D03*
X212000Y74000D03*
Y68000D03*
Y71000D03*
Y77000D03*
X266000Y108500D03*
Y111500D03*
Y120200D03*
Y117200D03*
X310500Y88300D03*
X311000Y144200D03*
X340500Y78500D03*
X347500Y88500D03*
X352500Y103500D03*
Y100500D03*
X350000Y97500D03*
Y94500D03*
X347500Y91500D03*
X352500Y106500D03*
X362450Y134700D03*
X366500Y182700D03*
Y179700D03*
X395496Y131063D03*
X396342Y143124D03*
X391000Y210500D03*
X437000Y17500D03*
X434500Y170000D03*
X471500Y242500D03*
X528000Y122500D03*
Y148500D03*
Y151500D03*
X530500Y179000D03*
Y176000D03*
X550500Y179000D03*
X563500D03*
X605000Y142000D03*
X610000Y211000D03*
G54D34*
X94900Y193000D03*
X100100D03*
X120900Y121000D03*
X126100D03*
X154900Y157500D03*
X142900Y190500D03*
X148100D03*
X160100Y157500D03*
X192900Y115200D03*
X198100D03*
X262400Y65500D03*
X261400Y83000D03*
X267600Y65500D03*
X266600Y83000D03*
X300400Y77700D03*
X305600D03*
X334400Y131000D03*
X339600D03*
X338360Y150400D03*
X343560D03*
X370396Y68063D03*
X370400Y73200D03*
X368400Y175650D03*
X375596Y68063D03*
X375600Y73200D03*
X373600Y175650D03*
X508900Y46507D03*
X514100D03*
X725900Y59000D03*
Y54000D03*
X731100Y59000D03*
Y54000D03*
X775900Y6500D03*
X781100D03*
X775900Y11700D03*
X781100D03*
X799400Y252300D03*
Y257300D03*
Y262500D03*
X804600Y252300D03*
Y257300D03*
Y262500D03*
G54D43*
X169085Y183848D03*
Y201170D03*
X192007Y183848D03*
Y201170D03*
G54D61*
X305900Y121151D03*
X303610Y110800D03*
X309000Y114700D03*
X306700D03*
X311200Y114800D03*
X311410Y118110D03*
X309194Y117700D03*
X306994Y117725D03*
X304149Y128349D03*
X307854Y130539D03*
X309700Y122796D03*
X309500Y132925D03*
X307298Y132697D03*
X307500Y122700D03*
X305050Y151150D03*
X309000Y137600D03*
X311000Y141731D03*
X306961Y153717D03*
X306696Y158610D03*
X309000Y158806D03*
X311242Y158732D03*
X309220Y153698D03*
X305800Y195400D03*
X305290Y187836D03*
X301320Y191060D03*
X303500Y195400D03*
X310500Y195600D03*
X308200D03*
X303480Y189100D03*
X301300Y188700D03*
X309700Y187997D03*
X307500Y188000D03*
X309100Y206800D03*
X317641Y90956D03*
X325081Y100631D03*
X322075Y100650D03*
X323120Y92400D03*
X319520Y92419D03*
X318900Y98000D03*
X317600Y93625D03*
X326162Y91438D03*
X315950Y98650D03*
X315613Y100850D03*
X315400Y110800D03*
X312000Y122600D03*
X320992Y112180D03*
X325300Y112300D03*
X311600Y110800D03*
X322010Y118573D03*
X325350Y114500D03*
X319096Y113300D03*
X319418Y123225D03*
X315451Y123219D03*
X323900Y129900D03*
X322691Y136023D03*
X326313Y122380D03*
X323007Y127672D03*
X320321Y130528D03*
X325418Y127349D03*
X325746Y133702D03*
X312917Y133440D03*
X323300Y147046D03*
X323550Y142104D03*
X319252Y140949D03*
X326322Y138434D03*
X325763Y141958D03*
X319401Y149354D03*
X317698Y152311D03*
X325200Y149319D03*
X319704Y162804D03*
X323000Y153900D03*
X315384Y166733D03*
X324953Y161722D03*
X324200Y157800D03*
X324029Y166384D03*
X326234Y153969D03*
X311417Y153821D03*
X323165Y171937D03*
X324436Y175705D03*
X326399Y169401D03*
X323500Y180063D03*
X311460Y172078D03*
X319942Y180524D03*
X323121Y182913D03*
X326408Y182292D03*
X312829Y181940D03*
X316844Y196010D03*
X319801Y194890D03*
X326550Y191600D03*
X323800Y192150D03*
X323789Y188117D03*
X320029Y184300D03*
X326500Y187900D03*
X311900Y188070D03*
X322256Y198618D03*
X323331Y196696D03*
X319500Y212100D03*
X325642Y202325D03*
X321600Y208700D03*
Y211000D03*
X317200Y213100D03*
X315585Y207787D03*
X324100Y208000D03*
X318700Y207800D03*
X311600Y207600D03*
X325200Y221700D03*
X319400Y216200D03*
X317200Y215300D03*
X313600Y237700D03*
X321400D03*
X316000D03*
X319100D03*
X329300Y87300D03*
X331200Y88600D03*
X330100Y100200D03*
Y98000D03*
X328000Y97100D03*
X334850Y96900D03*
X336750Y93500D03*
X335500Y91600D03*
X336750Y95704D03*
X328000Y92700D03*
X330900Y93400D03*
X333313Y103693D03*
X339500Y102000D03*
X332600Y101400D03*
X329415Y119923D03*
X333601Y120500D03*
X333534Y118040D03*
X333551Y115090D03*
X333434Y106668D03*
X333416Y108899D03*
X330470Y112515D03*
X330910Y115010D03*
X341200Y112569D03*
X338768Y116755D03*
Y119755D03*
X329308Y122386D03*
X338329Y135665D03*
X329031Y125428D03*
X335303Y135178D03*
X339280Y127380D03*
X341309Y135651D03*
X329693Y134428D03*
X331290Y125810D03*
X330870Y130540D03*
X336900Y127600D03*
X333977Y127678D03*
X327854Y130434D03*
X338470Y138177D03*
X335450Y150900D03*
X327963Y142008D03*
X335514Y138220D03*
X338320Y141300D03*
X327390Y149106D03*
X336920Y146130D03*
X329421Y138228D03*
X327696Y146108D03*
X336190Y141970D03*
X330796Y146221D03*
X330163Y142008D03*
X332478Y138255D03*
X341342Y138224D03*
X333750Y145950D03*
X339491Y143163D03*
X329800Y150800D03*
X332000D03*
X330300Y158546D03*
X339784Y161847D03*
X335499Y153846D03*
X327800Y161500D03*
X336900Y161600D03*
X336800Y164434D03*
X341390Y153991D03*
X329161Y153830D03*
X335964Y158512D03*
X333742Y161624D03*
X332185Y153806D03*
X338421Y153802D03*
X334470Y164760D03*
X341400Y156700D03*
X331000Y164500D03*
X330900Y161700D03*
X333000Y158300D03*
X339747Y164478D03*
X341300Y169600D03*
X335400D03*
X339300Y174100D03*
X330821Y177402D03*
X333842Y177224D03*
X332300Y173900D03*
X339875Y177303D03*
X329442Y169463D03*
X327708Y177241D03*
X332353Y169522D03*
X337000Y174102D03*
X327600Y174174D03*
X330027Y174119D03*
X334700Y174100D03*
X336915Y177423D03*
X337863Y180545D03*
X334715Y180900D03*
X330280D03*
X332500D03*
X332100Y185600D03*
X338000Y185700D03*
X335000Y185500D03*
X335400Y196300D03*
X337800Y189200D03*
X326850Y193900D03*
X329972Y196400D03*
Y193559D03*
X333996Y192063D03*
X334707Y189383D03*
X337800Y192200D03*
X338048Y196250D03*
X342029Y196427D03*
X332800Y187700D03*
X326831Y196119D03*
X329313Y188000D03*
X337670Y213520D03*
X335739Y199317D03*
X336500Y204600D03*
X332974Y210874D03*
X338926Y211674D03*
X338967Y209455D03*
X331658Y212660D03*
X329028Y199931D03*
X339800Y207400D03*
X327216Y203902D03*
X330200Y216800D03*
X336000Y219750D03*
X328510Y218320D03*
X327024Y220024D03*
X337307Y217961D03*
X331616Y214860D03*
X337341Y215731D03*
X333036Y231910D03*
X327100Y237100D03*
X328945Y235846D03*
X331142Y233658D03*
X344523Y98477D03*
X344500Y94000D03*
X347230Y100190D03*
X351342Y114158D03*
X346596Y118163D03*
Y115163D03*
X351000Y111700D03*
X355175Y108212D03*
X348076Y108910D03*
X343570Y112561D03*
X346600Y121100D03*
X346495Y130000D03*
X349149Y124141D03*
X351500Y136000D03*
X354333Y125665D03*
X343000Y126200D03*
X343146Y128473D03*
X343000Y124000D03*
X347641Y133479D03*
X342533Y133822D03*
X349600Y126700D03*
X357300Y128600D03*
X355400Y137100D03*
X354300Y128600D03*
X346300Y143000D03*
X342880Y146180D03*
X355447Y146528D03*
X344500Y141700D03*
X348675Y143326D03*
X350800Y138300D03*
X355342Y143424D03*
X348743Y146072D03*
X346000Y146043D03*
X346450Y149120D03*
X348743Y149100D03*
X355460Y149510D03*
X348432Y164844D03*
X346944Y156775D03*
X350550Y153280D03*
X342716Y161593D03*
X344300Y153800D03*
X344090Y156690D03*
X352000Y162000D03*
X348700Y161700D03*
X351600Y164300D03*
X355400Y152900D03*
X355413Y156050D03*
X351700Y167300D03*
X350700Y155600D03*
X345900Y161700D03*
X342188Y183361D03*
X355300Y174600D03*
X347200Y174300D03*
X344165Y169466D03*
X352200Y171800D03*
X350000Y177700D03*
X345562Y178700D03*
X347500Y169500D03*
X351600Y169600D03*
X353302Y182993D03*
X353321Y180128D03*
X342233Y185639D03*
X356900Y186100D03*
X349600Y194800D03*
X342760Y187810D03*
X342339Y192225D03*
X342342Y190024D03*
X349100Y191900D03*
X353625Y195045D03*
Y192045D03*
X356600Y195700D03*
X356700Y193300D03*
X345503Y193474D03*
X345500Y190500D03*
X349100Y189700D03*
X353342Y186124D03*
X349751Y187241D03*
X356800Y191000D03*
X345500Y184500D03*
X345631Y187420D03*
X351950Y214800D03*
X346500Y208350D03*
X345500Y213000D03*
X353594Y210707D03*
X347593Y210277D03*
X353385Y212898D03*
X345837Y199887D03*
X350409Y199755D03*
X353792Y208466D03*
X354700Y199900D03*
X343242Y213690D03*
X347664Y212476D03*
X355860Y216690D03*
X345300Y216700D03*
X343198Y215910D03*
X371900Y85400D03*
X364800Y91200D03*
X368600Y90700D03*
X361200Y90200D03*
X371900Y89000D03*
X371950Y92500D03*
X364874Y98250D03*
X362803Y106035D03*
X357900Y99200D03*
X368600Y97500D03*
X357721Y91779D03*
X361200Y97500D03*
X368600Y94100D03*
X365000Y94700D03*
X357721Y95100D03*
X360900Y94200D03*
X361141Y104099D03*
X365316Y108130D03*
X372700Y119663D03*
X370100Y119563D03*
X370000Y116563D03*
X369997Y113706D03*
X368721Y108528D03*
X359942Y110924D03*
X365721Y115528D03*
X358000Y115500D03*
X366400Y112200D03*
X364600Y137063D03*
X367221Y125428D03*
X370000Y122563D03*
X362111Y127142D03*
X362120Y124153D03*
X359421Y127128D03*
Y124008D03*
X372821Y125628D03*
X370121Y125528D03*
X367321Y122528D03*
X368026Y137118D03*
X364700Y134000D03*
X367992Y133982D03*
X367121Y128628D03*
X362111Y130128D03*
X358500Y137000D03*
X371176Y136890D03*
X359300Y130000D03*
X367900Y152550D03*
X368000Y146500D03*
X361700Y143300D03*
X364886Y140268D03*
X368026D03*
Y143418D03*
X364621Y143328D03*
X361726Y140268D03*
X361700Y146549D03*
X361500Y149500D03*
X364700Y152713D03*
X368026Y149718D03*
X368100Y165300D03*
X364600D03*
X367950Y159200D03*
X371157Y162320D03*
X371176Y158940D03*
X358477Y159300D03*
X361600Y159250D03*
X368100Y162200D03*
X358342Y165324D03*
X358576Y162090D03*
X358500Y155700D03*
X371100Y168700D03*
X364600Y174800D03*
X361500Y175000D03*
Y168500D03*
X368000D03*
X367906Y171458D03*
X364600Y171600D03*
X364607Y177103D03*
X370900Y171700D03*
X361200Y178500D03*
X361292Y181409D03*
X372400Y179100D03*
X369021Y180128D03*
X372600Y181400D03*
X361400Y187600D03*
X368455Y196455D03*
X371299Y196008D03*
X364792Y188743D03*
X364600Y186138D03*
X364895Y190941D03*
X369106Y191903D03*
X369200Y189100D03*
X361257Y193524D03*
Y190700D03*
X364947Y193141D03*
X361300Y184500D03*
X359222Y197700D03*
X369009Y186191D03*
X372700Y213700D03*
X369450Y212040D03*
X359750Y208390D03*
X359910Y214100D03*
X358498Y210220D03*
X358382Y212427D03*
X371100Y199500D03*
X365250Y208600D03*
X372800Y221600D03*
X369580Y218800D03*
Y215400D03*
X357966Y217516D03*
X359827Y216341D03*
X383350Y83350D03*
X383450Y90500D03*
X387200D03*
X387100Y83500D03*
X375800D03*
Y90500D03*
X379500Y83302D03*
Y90600D03*
X375800Y87000D03*
X383450Y86900D03*
X387200D03*
X379500D03*
X379526Y106396D03*
X381950Y100950D03*
X381600Y119900D03*
X381900Y113000D03*
X382596Y108600D03*
X385600Y116500D03*
X385200Y113137D03*
X385721Y119528D03*
X381550Y117400D03*
X377800Y112063D03*
X377818Y115008D03*
X386561Y108812D03*
X377713Y121061D03*
X385479Y125569D03*
X381500Y123200D03*
X381600Y126427D03*
X385523Y122532D03*
X385750Y128517D03*
X386708Y137118D03*
X383567Y137096D03*
X377800Y124163D03*
X380475Y137016D03*
X380400Y133928D03*
X380443Y130102D03*
X374200Y136994D03*
X387000Y143280D03*
X380398Y146568D03*
X383548D03*
X380398Y143418D03*
X383395Y143306D03*
X374200Y140144D03*
Y143294D03*
X380400Y152700D03*
X383575Y149603D03*
X380522Y149564D03*
X386853Y149640D03*
X377476Y149688D03*
X374200Y149494D03*
X374100Y159150D03*
X386800Y165300D03*
X380398Y165240D03*
X383781Y165235D03*
X386777Y162155D03*
X387000Y155850D03*
X386777Y159005D03*
X380500Y162025D03*
X383700Y162199D03*
X383500Y159000D03*
X374300Y155800D03*
X377500Y165240D03*
Y156000D03*
X384740Y180080D03*
X381720Y180220D03*
X381800Y183300D03*
X380540Y177370D03*
X380500Y168500D03*
X383693Y171424D03*
X383548Y168390D03*
X386600Y174900D03*
X380477Y171605D03*
X376830Y175640D03*
X376800Y178600D03*
X384650Y183170D03*
X376742Y181524D03*
X381460Y195610D03*
X384390Y196470D03*
X381140Y187960D03*
X381280Y191550D03*
X384708Y188910D03*
X384600Y186100D03*
X376800Y193500D03*
X376900Y196600D03*
X380510Y185500D03*
X384684Y191950D03*
X373922Y193103D03*
X374000Y190350D03*
X379750Y213500D03*
X376300Y211000D03*
Y213700D03*
X384810Y208530D03*
X384644Y205994D03*
X382471Y199843D03*
X382600Y222600D03*
X382750Y229000D03*
X379700Y219200D03*
X385947Y226500D03*
X385900Y218400D03*
X376300Y216200D03*
X385900Y222600D03*
X382700Y226000D03*
X379700Y216500D03*
X372950Y217400D03*
X390700Y89300D03*
X403726Y83826D03*
X403700Y90200D03*
X397300Y89168D03*
X400400Y92200D03*
Y98500D03*
X390750Y96500D03*
X394100Y91400D03*
Y99000D03*
X397100Y96600D03*
X397300Y93100D03*
X392382Y102149D03*
X390650Y93000D03*
X394100Y94900D03*
X400400Y95000D03*
X393331Y118043D03*
X393351Y115107D03*
X397650Y115500D03*
X401749Y112418D03*
X401159Y119636D03*
X401353Y116562D03*
X396276Y120948D03*
X396251Y117999D03*
X396600Y112463D03*
X390683Y108042D03*
X400700Y108800D03*
X393653Y121122D03*
X389700Y112363D03*
X398500Y125604D03*
X398512Y122815D03*
X401500Y125600D03*
X393482Y123982D03*
X396700Y128000D03*
X389914Y124536D03*
X393561Y127130D03*
X401500Y122600D03*
X401256Y128755D03*
X397800Y130000D03*
X399452Y133964D03*
X389380Y130100D03*
X390100Y127600D03*
X390205Y133858D03*
X392998Y133968D03*
X396148D03*
X396321Y136987D03*
X402561Y137000D03*
X399298Y137118D03*
X392998D03*
X389848D03*
X402400Y140163D03*
X393000Y152663D03*
X402900Y149663D03*
X389721Y143320D03*
X393000Y140268D03*
X403132Y144374D03*
X396148Y140268D03*
X399298D03*
X389848Y146568D03*
X393204Y146436D03*
X403080Y146931D03*
X399198Y146468D03*
X396192Y146444D03*
X392998Y149718D03*
X399198Y149618D03*
X396182Y149674D03*
X396200Y152763D03*
X396300Y162100D03*
X399300Y152863D03*
Y155963D03*
X392998Y165240D03*
X396148Y155790D03*
X393208D03*
X399298Y165240D03*
X393028Y162059D03*
X393198Y158940D03*
X403078Y152922D03*
X402373Y155952D03*
X399298Y162090D03*
X402505Y159133D03*
X396148Y158940D03*
X399298D03*
X392599Y181686D03*
X400252Y182966D03*
X403600Y182400D03*
Y180200D03*
X402540Y171760D03*
X399300Y168400D03*
X402600Y174611D03*
X395573Y175400D03*
X396000Y179000D03*
X393077Y168455D03*
X399385Y171686D03*
X396225D03*
X390025Y174672D03*
X393085Y171686D03*
Y174836D03*
X400352Y180171D03*
X397100Y181000D03*
X400301Y186099D03*
X397805Y192061D03*
X392600Y190600D03*
X396200Y194700D03*
X392624Y184537D03*
X389500Y193600D03*
X397307Y186607D03*
X395600Y184100D03*
Y190300D03*
X392700Y193563D03*
X403022Y192094D03*
X402967Y195005D03*
X389484Y190442D03*
X389300Y187700D03*
X402962Y189014D03*
X392596Y187541D03*
X397728Y189053D03*
X395641Y188045D03*
X392100Y213700D03*
X395700Y213600D03*
X400400Y209400D03*
X398500Y208000D03*
X389100Y224000D03*
X399700Y225000D03*
Y216400D03*
X395600Y224400D03*
X395700Y217000D03*
X391950Y220800D03*
X389200Y227400D03*
X392000Y217200D03*
X395700Y220600D03*
X399800D03*
X389150Y230300D03*
X407500Y84000D03*
X407400Y91000D03*
X411300Y85600D03*
X414722Y90250D03*
X414300Y85600D03*
X403800Y87000D03*
X407400Y87400D03*
X411000Y88900D03*
X418300Y91300D03*
X418400Y98150D03*
X411000Y92100D03*
X414622Y98000D03*
X414672Y94500D03*
X417800Y100400D03*
X412650Y100197D03*
X418300Y94800D03*
X407550Y100196D03*
X404529Y118507D03*
X405900Y121700D03*
X409110Y114910D03*
X405200Y115343D03*
X412462Y115713D03*
X409196Y118195D03*
X416904Y119591D03*
X416922Y116613D03*
X413100Y121800D03*
X409110Y120910D03*
X404900Y124600D03*
X416000Y135983D03*
X415000Y131400D03*
X408956Y130064D03*
X418500Y128200D03*
X415100Y127900D03*
X406200Y127400D03*
X412100Y135600D03*
X416851Y122600D03*
X412600Y124100D03*
X412462Y126300D03*
X417753Y131322D03*
X404400Y128900D03*
X405500Y131063D03*
X414900Y147000D03*
X417900Y146900D03*
X408800Y147000D03*
X411900Y146800D03*
X413300Y139100D03*
X413400Y142700D03*
X418000Y142500D03*
X406000Y150200D03*
X407500Y152100D03*
X410400Y152000D03*
X415700Y143100D03*
X410302Y141864D03*
X405990Y144251D03*
X409096Y143963D03*
X406042Y147025D03*
X415100Y149800D03*
X407399Y142561D03*
X408837Y149809D03*
X418439Y167118D03*
X414800Y162600D03*
X411800Y162700D03*
X414572Y165913D03*
X411356Y165732D03*
X407500Y157600D03*
X412900Y157800D03*
X407400Y154863D03*
X406100Y159500D03*
X417785Y162622D03*
X413314Y154908D03*
X410100Y157700D03*
X415100Y158100D03*
X410272Y154794D03*
X416400Y155000D03*
X408600Y159600D03*
X411600D03*
X409300Y167163D03*
X408900Y162463D03*
X406000Y162663D03*
X404558Y154835D03*
X407100Y167429D03*
X418600Y182800D03*
X414960Y178130D03*
X414950Y181460D03*
X411260Y178090D03*
X411553Y181222D03*
X416400Y170300D03*
X413265Y170423D03*
X410408Y170261D03*
X410620Y173300D03*
X405100Y178500D03*
X408158Y178666D03*
X407552Y170424D03*
X416315Y183219D03*
X417900Y178363D03*
X415992Y189254D03*
Y186205D03*
X419097Y189563D03*
X416500Y195563D03*
X408242Y184624D03*
X405231Y184976D03*
X408200Y190500D03*
X408100Y193600D03*
X412500Y197300D03*
X405000Y190700D03*
X412000Y187500D03*
X412500Y194900D03*
X412100Y190400D03*
X418800Y196700D03*
X416139Y192007D03*
X411342Y185024D03*
X405800Y196700D03*
X405102Y187874D03*
X412200Y192600D03*
X416900Y200100D03*
X416353Y207249D03*
X408200Y226900D03*
X408100Y220500D03*
X404400Y228600D03*
Y222300D03*
X415600Y222700D03*
X415800Y215900D03*
X412050Y225100D03*
X412100Y218400D03*
X408200Y223800D03*
X412000Y222000D03*
X415700Y219200D03*
X404400Y225300D03*
X422078Y97678D03*
X422000Y91300D03*
X427560Y104770D03*
X429105Y106337D03*
X426800Y97850D03*
X429500Y93800D03*
X434021Y100128D03*
X422050Y94800D03*
X428100Y120000D03*
X424900Y121213D03*
X420600Y118300D03*
X420672Y120600D03*
X422042Y115224D03*
X424700Y115000D03*
X427900Y114300D03*
X428100Y116500D03*
X427500Y112091D03*
X430302Y112098D03*
X419596Y113463D03*
X425200Y118823D03*
X431188Y116105D03*
X430342Y119724D03*
X428255Y126236D03*
X425000Y135350D03*
X419500Y136400D03*
X430100Y131500D03*
X431700Y128300D03*
X423500Y128200D03*
X427000Y128050D03*
X423900Y131500D03*
X420942Y131324D03*
X422300Y126300D03*
X431504Y126061D03*
X424982Y126500D03*
X434700Y131800D03*
X432542Y136898D03*
X426982Y131334D03*
X427600Y143841D03*
X421500Y142400D03*
X426900Y147100D03*
X431100Y145500D03*
X424856Y142270D03*
X422400Y139000D03*
X420861Y149687D03*
Y146923D03*
X430694Y142275D03*
X428390Y139059D03*
X419499Y139064D03*
X423496Y144000D03*
X428363Y141756D03*
X423945Y165221D03*
X421710Y167230D03*
X431130Y166660D03*
X428238Y167709D03*
X420804Y162659D03*
X420900Y160037D03*
X425500Y154737D03*
X428400D03*
X426000Y167370D03*
X426900Y160040D03*
X430542Y160753D03*
X430600Y164513D03*
X431620Y154620D03*
X422363Y154700D03*
X434500Y160037D03*
X430360Y181350D03*
X430340Y177620D03*
X423642Y181374D03*
X426970Y178310D03*
X425400Y170240D03*
X428500Y173120D03*
X422337Y170575D03*
X425427Y173113D03*
X419453Y173187D03*
X420922Y178117D03*
X423842Y178274D03*
X428431Y170264D03*
X419340Y170500D03*
X421697Y174049D03*
X423910Y175700D03*
X432712Y172469D03*
X434482Y177021D03*
X432100Y190400D03*
X429100Y189696D03*
X426173Y190784D03*
X428830Y195379D03*
X422152Y189600D03*
X420800Y193100D03*
X421171Y196496D03*
X431270Y193425D03*
X425500Y186045D03*
X423966Y190846D03*
X423800Y196500D03*
X433842Y197021D03*
X421848Y186550D03*
X428400Y185900D03*
X429933Y197283D03*
X420975Y211300D03*
X427900Y202800D03*
X424832Y200174D03*
X421811Y202603D03*
X426311Y204399D03*
X421253Y199822D03*
X425642Y209524D03*
X419550Y222700D03*
X419600Y216200D03*
Y219200D03*
X444578Y106201D03*
X442378Y106198D03*
X440178Y106200D03*
X437400Y121600D03*
X442842Y120824D03*
X438700Y112900D03*
X438500Y116400D03*
X439400Y120100D03*
X434960Y114529D03*
X444242Y124324D03*
X435442Y124024D03*
X437800Y128100D03*
X439275Y124197D03*
X434700Y128200D03*
X443443Y144757D03*
X437398Y146257D03*
X435004Y142110D03*
X443400Y148900D03*
X437472Y152501D03*
X434834Y163817D03*
X439600Y153800D03*
X439276Y159645D03*
X435453Y167560D03*
X435105Y181207D03*
X438742Y197224D03*
X435642Y194824D03*
X437921Y192956D03*
X445000Y194500D03*
X443100Y195900D03*
X443000Y192700D03*
X435453Y185397D03*
X436957Y209867D03*
X459800Y118800D03*
X453000Y118700D03*
X456200Y118900D03*
X459700Y129900D03*
X452200Y129800D03*
X463100Y133700D03*
X456000Y133500D03*
X460100Y123100D03*
X453000Y123300D03*
X463200Y126200D03*
X456500Y126100D03*
X456200Y129600D03*
X459700Y133600D03*
X459800Y126200D03*
X456500Y123000D03*
X461200Y167400D03*
X454200D03*
X457700D03*
X464300Y181800D03*
X458000Y171100D03*
X451000D03*
X460000Y174900D03*
X453000D03*
X456500D03*
X454500Y171100D03*
X457400Y197000D03*
X450400D03*
X462500Y189000D03*
X460400Y193300D03*
X453400D03*
X456900D03*
X453900Y197000D03*
X459500Y200700D03*
X452500D03*
X456000D03*
X473900Y178200D03*
X466900D03*
X471300Y181800D03*
X470400Y178200D03*
X467800Y181800D03*
X473100Y185500D03*
X466000D03*
X469500Y189000D03*
X469600Y185500D03*
X466000Y189000D03*
X504000Y12507D03*
X506800Y12907D03*
X508700Y14607D03*
Y17207D03*
X511589Y30295D03*
X507839Y30362D03*
X506500Y32807D03*
X507817Y252248D03*
X511200Y258900D03*
X509244Y272796D03*
X506496Y272500D03*
X523453Y12360D03*
X511800Y12507D03*
X514360Y12417D03*
X526000Y12507D03*
X519426Y12318D03*
X520700Y14807D03*
X518769Y22907D03*
X515484D03*
X522311Y16720D03*
X514300Y20507D03*
X519623Y20457D03*
X525753Y30893D03*
X522733Y32832D03*
X522700Y30007D03*
X513005Y32412D03*
X519400Y33340D03*
X526700Y33207D03*
X511640Y255956D03*
X514137Y256089D03*
X522908Y255117D03*
X526715Y254700D03*
X516600Y252200D03*
X521800Y252875D03*
X513776Y258563D03*
X511736Y273001D03*
X514900Y271350D03*
X522992Y270700D03*
X525845Y272863D03*
X517846Y262489D03*
X521131D03*
X516727Y273122D03*
X521790Y273140D03*
X517100Y265100D03*
X521987D03*
X528525Y12549D03*
X537964Y12317D03*
X532500Y13407D03*
X541114Y12307D03*
X542100Y15107D03*
X530700Y15407D03*
X536485Y22907D03*
X533200D03*
X528219Y15096D03*
X532472Y20515D03*
X537410Y20584D03*
X542407Y30882D03*
X532350Y30807D03*
X529120Y32575D03*
X529000Y30007D03*
X541950Y33340D03*
X532542Y33307D03*
X537200Y33207D03*
X530015Y255000D03*
X531775Y252231D03*
X541005Y254800D03*
X532900Y255300D03*
X535098Y252600D03*
X540900Y252300D03*
X527400Y252100D03*
X530900Y273000D03*
X534100Y270700D03*
X541500Y270900D03*
X535562Y262489D03*
X538847D03*
X529300Y271000D03*
X528330Y273140D03*
X539937Y272989D03*
X539505Y265100D03*
X534905Y273097D03*
X534700Y265100D03*
X550000Y12507D03*
X544860Y12407D03*
X547500Y12507D03*
X553720Y12297D03*
X552800Y14807D03*
X557745Y22907D03*
X554460D03*
X550234Y14997D03*
X553797Y20496D03*
X549500Y29107D03*
X553079Y30712D03*
X549500Y31607D03*
X545928Y31047D03*
X553250Y33207D03*
X547306Y33134D03*
X544800Y255100D03*
X550200Y255500D03*
X551000Y252056D03*
X552800Y255300D03*
X545500Y252600D03*
X553485Y252332D03*
X544292Y273128D03*
X548800Y271000D03*
X551937Y272789D03*
X555641Y262489D03*
X546200Y271000D03*
X554500Y264900D03*
X546900Y273100D03*
X554434Y272914D03*
X568555Y12407D03*
X561200Y12507D03*
X558448Y12407D03*
X566040Y12317D03*
X571600Y14207D03*
X564400Y14307D03*
X566000Y16507D03*
X572200Y28707D03*
X558500Y20507D03*
X573200Y19907D03*
X570852Y33204D03*
X569800Y29807D03*
X565091Y30815D03*
X561456Y30902D03*
X565470Y33287D03*
X573242Y32462D03*
X560635Y33264D03*
X561419Y254850D03*
X565054Y254773D03*
X568327Y253348D03*
X571867Y254685D03*
X560555Y252503D03*
X563376Y256627D03*
X566151Y252115D03*
X572150Y252200D03*
X560600Y270300D03*
X564100Y271100D03*
X567800Y270500D03*
X570200Y273100D03*
X558926Y262489D03*
X570200Y269700D03*
X559600Y272900D03*
X572155Y264900D03*
X565700Y273050D03*
X559700Y264900D03*
X572700Y273100D03*
X587940Y12417D03*
X582655Y12407D03*
X573470Y12347D03*
X578620Y12357D03*
X585280Y12267D03*
X579800Y14807D03*
X577824Y22907D03*
X574539D03*
X583700Y28207D03*
X578600Y20307D03*
X585179Y30867D03*
X581450Y30707D03*
X579100Y33207D03*
X585550Y33340D03*
X587700Y255300D03*
X579205Y254850D03*
X582200Y252206D03*
X587642D03*
X582300Y254900D03*
X578800Y252200D03*
X580200Y273000D03*
X582600Y270300D03*
X588036Y273089D03*
X588400Y270300D03*
X573357Y262489D03*
X576642D03*
X577450Y264900D03*
X580107Y270501D03*
X577636Y272947D03*
X594600Y6707D03*
X590000Y14007D03*
X594500Y4007D03*
X600896Y12407D03*
X601704Y22907D03*
X601000Y20507D03*
X594400Y36207D03*
X589300Y33007D03*
X590500Y30507D03*
X594200Y33607D03*
X600360Y33287D03*
X594600Y260000D03*
X591300Y255010D03*
X590837Y259889D03*
X598398Y260199D03*
X591342Y252206D03*
X603187Y252056D03*
X589500Y257100D03*
X594500Y265200D03*
X591500Y270100D03*
X591536Y273000D03*
X590700Y264833D03*
X598300Y265400D03*
X589900Y268133D03*
X602450Y272900D03*
X598418Y262699D03*
X590322Y262361D03*
X594559Y262559D03*
X595386Y272932D03*
X610952Y12307D03*
X616600D03*
X605700Y12407D03*
X614700Y14107D03*
X615852Y19807D03*
X615907Y24856D03*
X607300Y14507D03*
X616707Y15616D03*
X604989Y22907D03*
X610800Y14807D03*
X605728Y20518D03*
X615951Y22356D03*
X612000Y17407D03*
X610944Y33333D03*
X607800Y30407D03*
X618900Y33290D03*
X615103Y30690D03*
X610500Y30507D03*
X615044Y33190D03*
X607544Y33340D03*
X618877Y30790D03*
X619382Y260089D03*
X615532Y259700D03*
X611706Y259387D03*
X606700Y255600D03*
X604074Y254394D03*
X609500Y254900D03*
X609937Y252106D03*
X608700Y257300D03*
X611845Y253723D03*
X615537Y264789D03*
X619100Y265300D03*
X611536Y264385D03*
X609896Y272889D03*
X608996Y270206D03*
X605100Y270100D03*
X605065Y272967D03*
X611593Y261885D03*
X606200Y267800D03*
X615430Y262213D03*
X612393Y273026D03*
X619180Y262689D03*
X633500Y12406D03*
X624000D03*
X623532Y20007D03*
X623555Y25107D03*
X619607Y19807D03*
X627255Y25107D03*
X627231Y19907D03*
X630955Y25207D03*
X631000Y20107D03*
X634555Y25307D03*
X634757Y20207D03*
X619730Y24864D03*
X634757Y22707D03*
X623480Y22564D03*
X631007Y22707D03*
X619700Y22307D03*
X627257Y22407D03*
X624100Y33190D03*
X633449D03*
X630432Y260100D03*
X626682Y260300D03*
X622933Y260189D03*
X634207Y260300D03*
X630455Y265400D03*
X634280Y265332D03*
X626651Y265489D03*
X622899Y265189D03*
X629937Y272990D03*
X630457Y262832D03*
X626680Y262989D03*
X634280Y262832D03*
X620437Y272990D03*
X622930Y262689D03*
X644193Y12907D03*
X648800Y12707D03*
X641745Y12367D03*
X638400Y20607D03*
X638290Y25674D03*
X642246Y25807D03*
X642451Y20707D03*
X645300Y15507D03*
X648400Y15490D03*
X645200Y27707D03*
X646800Y17607D03*
X642257Y23307D03*
X638507Y23183D03*
X647000Y29607D03*
X649550Y30807D03*
X643700Y33290D03*
X644100Y30307D03*
X650200Y33307D03*
X641900Y31507D03*
X638032Y260342D03*
X642802Y252186D03*
X645920Y254130D03*
X635043Y252106D03*
X638900Y254809D03*
X643020Y254710D03*
X647800Y252300D03*
X635197Y254602D03*
X638893Y252206D03*
X638090Y265340D03*
X642937Y273089D03*
X646360Y271530D03*
X637288Y270100D03*
X637337Y272944D03*
X648948Y262489D03*
X644090Y270420D03*
X648200Y265300D03*
X637987Y262842D03*
X644550Y267170D03*
X639500Y268800D03*
X648291Y273140D03*
X662359Y12379D03*
X657897Y12504D03*
X651316Y12360D03*
X659400Y25907D03*
Y20474D03*
X662192Y14874D03*
X663202Y25973D03*
X655602Y25223D03*
X663200Y20956D03*
X655700Y20225D03*
X664212Y16356D03*
X663300Y23454D03*
X662916Y28457D03*
X655592Y22723D03*
X659400Y23207D03*
X662503Y33207D03*
X657900Y30690D03*
X664678Y30307D03*
X661708Y30699D03*
X657900Y33190D03*
X659437Y246389D03*
X665500Y252189D03*
X665300Y254700D03*
X661200Y248500D03*
X653600Y252130D03*
X659500Y274000D03*
X665100Y272700D03*
X652233Y262489D03*
X664500Y270000D03*
X653000Y264900D03*
X661600Y272300D03*
X653041Y272989D03*
X671290Y12457D03*
X665901Y12307D03*
X675990Y12357D03*
X674320Y14219D03*
X666175Y14807D03*
X680580Y22807D03*
X677295D03*
X669600Y17907D03*
X676600Y20307D03*
X671500Y15007D03*
X674400Y31307D03*
X671295Y33190D03*
X671900Y30707D03*
X675970Y33267D03*
X670200Y254700D03*
X673770Y254752D03*
X669930Y252150D03*
X674636Y252406D03*
X669700Y270900D03*
X672800Y272700D03*
X676113Y262489D03*
X679398D03*
X680600Y265000D03*
X675400D03*
X668000Y272890D03*
X680400Y273100D03*
X675400D03*
X690102Y12502D03*
X684760Y12256D03*
X687602Y12439D03*
X694200Y13507D03*
X681280Y12457D03*
X692200Y15357D03*
X682013Y14848D03*
X695029Y22853D03*
X684500Y15507D03*
X689595Y27883D03*
X685400Y28307D03*
X681700Y20507D03*
X694205Y20302D03*
X693300Y30607D03*
X689624Y30383D03*
X685700Y30807D03*
X681900Y30907D03*
X693700Y33107D03*
X681280Y33340D03*
X687900Y33327D03*
X682800Y254900D03*
X685382Y252200D03*
X688800Y254600D03*
X692250Y255700D03*
X690000Y256800D03*
X685390Y254900D03*
X688720Y252090D03*
X693860Y252210D03*
X681900Y252500D03*
X682481Y270700D03*
X685100Y273100D03*
X689700Y270800D03*
X692537Y272989D03*
X696192Y262489D03*
X691900Y269300D03*
X683100Y268000D03*
X695500Y265000D03*
Y273100D03*
X687682Y272889D03*
X709000Y12407D03*
X702000Y12607D03*
X699503Y12482D03*
X706360Y12397D03*
X705031Y14515D03*
X698277Y22855D03*
X705604Y16949D03*
X710813Y28796D03*
X699104Y20495D03*
X708900Y30407D03*
X704430Y33313D03*
X701800Y30807D03*
X707157Y33333D03*
X700940Y33340D03*
X701649Y255049D03*
X704178Y252189D03*
X707800Y255000D03*
X711400Y255072D03*
X704137Y254796D03*
X699800Y252230D03*
X701704Y257549D03*
X707490Y252310D03*
X701300Y270777D03*
X704277Y272989D03*
X709400Y272600D03*
X699477Y262489D03*
X706000Y270500D03*
X700200Y264900D03*
X700300Y273100D03*
X706900Y273000D03*
X723586Y14080D03*
X712182Y14124D03*
X714000Y12407D03*
X719110Y12347D03*
X725530Y12507D03*
X720100Y14707D03*
X718375Y22907D03*
X715090D03*
X714100Y20607D03*
X719220Y20553D03*
X727000Y30407D03*
X723500Y29907D03*
X721747Y32954D03*
X712400Y30807D03*
X721074Y30514D03*
X718350Y33107D03*
X712450Y33340D03*
X725653Y32654D03*
X721500Y255000D03*
X724374Y254515D03*
X712350Y252640D03*
X725950Y252573D03*
X721395Y252175D03*
X721600Y257500D03*
X716737Y252189D03*
X712200Y270500D03*
X722400Y270800D03*
X725300Y272800D03*
X717452Y262489D03*
X720737D03*
X716795Y265000D03*
X721400D03*
X721395Y273100D03*
X713100Y273000D03*
X716737Y272989D03*
X715900Y270000D03*
X742200Y12407D03*
X728010Y12857D03*
X737300Y12307D03*
X732110Y12267D03*
X739000Y14407D03*
X731169Y14584D03*
X736091Y23607D03*
X732806D03*
X728500Y15507D03*
X742100Y28107D03*
X732000Y20307D03*
X736748D03*
X728500Y27907D03*
X742100Y33007D03*
X740200Y29907D03*
X730500D03*
X733474Y33340D03*
X738487Y33094D03*
X730400Y255400D03*
X732200Y252200D03*
X741560Y255000D03*
X730300Y257900D03*
X734937Y253100D03*
X739750Y252800D03*
X730400Y272850D03*
X732740Y270200D03*
X741200Y270500D03*
X735168Y262489D03*
X738453D03*
X729860Y269810D03*
X734200Y265100D03*
X739111Y264962D03*
X739838Y272813D03*
X727800Y272800D03*
X734510Y273110D03*
X745100Y12256D03*
X744900Y20500D03*
X745000Y23000D03*
X744800Y33007D03*
X747441D03*
X744437Y252189D03*
X744100Y254800D03*
X749000Y252200D03*
X744200Y272600D03*
X753000Y272100D03*
X746737Y272889D03*
G54D52*
X249410Y67126D03*
Y182480D03*
G54D70*
X380000Y263461D03*
G54D71*
X402250Y254500D03*
G54D53*
X272079Y73795D03*
X274047D03*
X276016D03*
X277984D03*
Y84205D03*
X276016D03*
X274047D03*
X272079D03*
X279953Y73795D03*
X281921D03*
Y84205D03*
X279953D03*
G54D62*
X314639Y74202D03*
Y71643D03*
Y69084D03*
Y66525D03*
Y76761D03*
X333125Y66525D03*
Y69084D03*
Y71643D03*
Y74202D03*
Y76761D03*
G54D17*
X32000Y99000D03*
X72500Y91500D03*
X64500Y132500D03*
X68000Y222000D03*
X85500Y110000D03*
X133000Y201000D03*
X144000Y106000D03*
X209000Y74000D03*
Y68000D03*
Y71000D03*
Y77000D03*
X263000Y108500D03*
Y111500D03*
Y120200D03*
Y117200D03*
X307500Y88300D03*
X308000Y144200D03*
X337500Y78500D03*
X344500Y88500D03*
X349500Y103500D03*
Y100500D03*
X347000Y97500D03*
Y94500D03*
X344500Y91500D03*
X349500Y106500D03*
X359450Y134700D03*
X363500Y182700D03*
Y179700D03*
X392496Y131063D03*
X393342Y143124D03*
X388000Y210500D03*
X434000Y17500D03*
X431500Y170000D03*
X468500Y242500D03*
X525000Y122500D03*
Y148500D03*
Y151500D03*
X527500Y179000D03*
Y176000D03*
X547500Y179000D03*
X560500D03*
X602000Y142000D03*
X607000Y211000D03*
G54D35*
X81500Y234500D03*
X127000Y209500D03*
X154000Y118500D03*
X150500Y177000D03*
X160000Y165000D03*
X161000Y203000D03*
X212500Y169500D03*
X259000Y52000D03*
X262000D03*
X353000Y146500D03*
X356000Y158600D03*
Y180000D03*
X352500Y174000D03*
X359000Y145800D03*
X370742Y139924D03*
X361300Y162200D03*
X364300Y159850D03*
X359000Y168000D03*
Y180000D03*
X371500Y187600D03*
X376390Y187650D03*
X385500Y200700D03*
X389500Y150463D03*
X401866Y162000D03*
X396142Y165024D03*
X400500Y201063D03*
X395000Y267500D03*
X406500Y68500D03*
X411500Y130000D03*
X403500Y201063D03*
X406500D03*
X409500D03*
X424500Y160000D03*
X420000Y206000D03*
X423000Y206063D03*
X517000Y56507D03*
X626500Y47507D03*
X633300D03*
X636600D03*
X661500Y48107D03*
X658500D03*
X664500D03*
X735000Y66500D03*
X739300Y109000D03*
G54D26*
X60433Y24392D03*
X68307D03*
X72244D03*
X76181D03*
X80118D03*
X84055D03*
X87992D03*
X91929D03*
X95866D03*
X99803D03*
X103740D03*
X107677D03*
X111614D03*
X115551D03*
X119488D03*
X123425D03*
X127362D03*
X131299D03*
X135236D03*
X139173D03*
X143110D03*
X147047D03*
X150984D03*
X154921D03*
X158858D03*
X162795D03*
X166732D03*
X170669D03*
X174606D03*
X178543D03*
X182480D03*
X186417D03*
X190354D03*
X194291D03*
X198228D03*
X202165D03*
X206102D03*
X210039D03*
X213976D03*
X217913D03*
X221850D03*
X225787D03*
X229724D03*
X233661D03*
X237598D03*
X241535D03*
X245472D03*
X249409D03*
X253346D03*
X257283D03*
X261220D03*
X265157D03*
X269094D03*
X273031D03*
X276968D03*
X280905D03*
X284842D03*
X288779D03*
X292716D03*
X296653D03*
X300590D03*
X304527D03*
X308464D03*
X312401D03*
X316338D03*
X320275D03*
X324212D03*
X328149D03*
X332086D03*
X336023D03*
X347835D03*
X351772D03*
X355709D03*
X359646D03*
X363583D03*
X367520D03*
X371457D03*
X375394D03*
X379331D03*
X383268D03*
X387205D03*
G36*
G01X507677Y35390D02*
X507802Y35400D01*
X507927Y35440D01*
X508037Y35500D01*
X508137Y35580D01*
X508217Y35680D01*
X508277Y35790D01*
X508317Y35915D01*
X508327Y36040D01*
Y38165D01*
X508357Y38195D01*
X508382Y38230D01*
X508412Y38265D01*
X508432Y38300D01*
X508457Y38335D01*
X508497Y38415D01*
X508542Y38535D01*
X508552Y38575D01*
X508562Y38620D01*
X508567Y38660D01*
X508577Y38705D01*
Y38875D01*
X508567Y38920D01*
X508562Y38960D01*
X508552Y39005D01*
X508542Y39045D01*
X508497Y39165D01*
X508457Y39245D01*
X508432Y39280D01*
X508412Y39315D01*
X508382Y39350D01*
X508357Y39385D01*
X508327Y39415D01*
Y41840D01*
X508317Y41965D01*
X508277Y42090D01*
X508217Y42200D01*
X508137Y42300D01*
X508037Y42380D01*
X507927Y42440D01*
X507802Y42480D01*
X507677Y42490D01*
X507552Y42480D01*
X507427Y42440D01*
X507317Y42380D01*
X507217Y42300D01*
X507137Y42200D01*
X507077Y42090D01*
X507037Y41965D01*
X507027Y41840D01*
Y39410D01*
X506997Y39380D01*
X506897Y39240D01*
X506877Y39200D01*
X506862Y39165D01*
X506842Y39125D01*
X506827Y39085D01*
X506817Y39045D01*
X506802Y39000D01*
X506797Y38960D01*
X506787Y38920D01*
X506782Y38875D01*
Y38835D01*
X506777Y38790D01*
X506782Y38745D01*
Y38705D01*
X506787Y38660D01*
X506797Y38620D01*
X506802Y38580D01*
X506817Y38535D01*
X506827Y38495D01*
X506842Y38455D01*
X506862Y38415D01*
X506877Y38380D01*
X506897Y38340D01*
X506997Y38200D01*
X507027Y38170D01*
Y36040D01*
X507037Y35915D01*
X507077Y35790D01*
X507137Y35680D01*
X507217Y35580D01*
X507317Y35500D01*
X507427Y35440D01*
X507552Y35400D01*
X507677Y35390D01*
G37*
G36*
G01X521850D02*
X521975Y35400D01*
X522100Y35440D01*
X522210Y35500D01*
X522310Y35580D01*
X522390Y35680D01*
X522450Y35790D01*
X522490Y35915D01*
X522500Y36040D01*
Y38165D01*
X522530Y38195D01*
X522555Y38230D01*
X522585Y38265D01*
X522605Y38300D01*
X522630Y38335D01*
X522670Y38415D01*
X522715Y38535D01*
X522725Y38575D01*
X522735Y38620D01*
X522740Y38660D01*
X522750Y38705D01*
Y38875D01*
X522740Y38920D01*
X522735Y38960D01*
X522725Y39005D01*
X522715Y39045D01*
X522670Y39165D01*
X522630Y39245D01*
X522605Y39280D01*
X522585Y39315D01*
X522555Y39350D01*
X522530Y39385D01*
X522500Y39415D01*
Y41840D01*
X522490Y41965D01*
X522450Y42090D01*
X522390Y42200D01*
X522310Y42300D01*
X522210Y42380D01*
X522100Y42440D01*
X521975Y42480D01*
X521850Y42490D01*
X521725Y42480D01*
X521600Y42440D01*
X521490Y42380D01*
X521390Y42300D01*
X521310Y42200D01*
X521250Y42090D01*
X521210Y41965D01*
X521200Y41840D01*
Y39410D01*
X521170Y39380D01*
X521070Y39240D01*
X521050Y39200D01*
X521035Y39165D01*
X521015Y39125D01*
X521000Y39085D01*
X520990Y39045D01*
X520975Y39000D01*
X520970Y38960D01*
X520960Y38920D01*
X520955Y38875D01*
Y38835D01*
X520950Y38790D01*
X520955Y38745D01*
Y38705D01*
X520960Y38660D01*
X520970Y38620D01*
X520975Y38580D01*
X520990Y38535D01*
X521000Y38495D01*
X521015Y38455D01*
X521035Y38415D01*
X521050Y38380D01*
X521070Y38340D01*
X521170Y38200D01*
X521200Y38170D01*
Y36040D01*
X521210Y35915D01*
X521250Y35790D01*
X521310Y35680D01*
X521390Y35580D01*
X521490Y35500D01*
X521600Y35440D01*
X521725Y35400D01*
X521850Y35390D01*
G37*
G36*
G01X517126D02*
X517251Y35400D01*
X517376Y35440D01*
X517486Y35500D01*
X517586Y35580D01*
X517666Y35680D01*
X517726Y35790D01*
X517766Y35915D01*
X517776Y36040D01*
Y38165D01*
X517806Y38195D01*
X517831Y38230D01*
X517861Y38265D01*
X517881Y38300D01*
X517906Y38335D01*
X517946Y38415D01*
X517991Y38535D01*
X518001Y38575D01*
X518011Y38620D01*
X518016Y38660D01*
X518026Y38705D01*
Y38875D01*
X518016Y38920D01*
X518011Y38960D01*
X518001Y39005D01*
X517991Y39045D01*
X517946Y39165D01*
X517906Y39245D01*
X517881Y39280D01*
X517861Y39315D01*
X517831Y39350D01*
X517806Y39385D01*
X517776Y39415D01*
Y41840D01*
X517766Y41965D01*
X517726Y42090D01*
X517666Y42200D01*
X517586Y42300D01*
X517486Y42380D01*
X517376Y42440D01*
X517251Y42480D01*
X517126Y42490D01*
X517001Y42480D01*
X516876Y42440D01*
X516766Y42380D01*
X516666Y42300D01*
X516586Y42200D01*
X516526Y42090D01*
X516486Y41965D01*
X516476Y41840D01*
Y39410D01*
X516446Y39380D01*
X516346Y39240D01*
X516326Y39200D01*
X516311Y39165D01*
X516291Y39125D01*
X516276Y39085D01*
X516266Y39045D01*
X516251Y39000D01*
X516246Y38960D01*
X516236Y38920D01*
X516231Y38875D01*
Y38835D01*
X516226Y38790D01*
X516231Y38745D01*
Y38705D01*
X516236Y38660D01*
X516246Y38620D01*
X516251Y38580D01*
X516266Y38535D01*
X516276Y38495D01*
X516291Y38455D01*
X516311Y38415D01*
X516326Y38380D01*
X516346Y38340D01*
X516446Y38200D01*
X516476Y38170D01*
Y36040D01*
X516486Y35915D01*
X516526Y35790D01*
X516586Y35680D01*
X516666Y35580D01*
X516766Y35500D01*
X516876Y35440D01*
X517001Y35400D01*
X517126Y35390D01*
G37*
G36*
G01X512401D02*
X512526Y35400D01*
X512651Y35440D01*
X512761Y35500D01*
X512861Y35580D01*
X512941Y35680D01*
X513001Y35790D01*
X513041Y35915D01*
X513051Y36040D01*
Y38165D01*
X513081Y38195D01*
X513106Y38230D01*
X513136Y38265D01*
X513156Y38300D01*
X513181Y38335D01*
X513221Y38415D01*
X513266Y38535D01*
X513276Y38575D01*
X513286Y38620D01*
X513291Y38660D01*
X513301Y38705D01*
Y38875D01*
X513291Y38920D01*
X513286Y38960D01*
X513276Y39005D01*
X513266Y39045D01*
X513221Y39165D01*
X513181Y39245D01*
X513156Y39280D01*
X513136Y39315D01*
X513106Y39350D01*
X513081Y39385D01*
X513051Y39415D01*
Y41840D01*
X513041Y41965D01*
X513001Y42090D01*
X512941Y42200D01*
X512861Y42300D01*
X512761Y42380D01*
X512651Y42440D01*
X512526Y42480D01*
X512401Y42490D01*
X512276Y42480D01*
X512151Y42440D01*
X512041Y42380D01*
X511941Y42300D01*
X511861Y42200D01*
X511801Y42090D01*
X511761Y41965D01*
X511751Y41840D01*
Y39410D01*
X511721Y39380D01*
X511621Y39240D01*
X511601Y39200D01*
X511586Y39165D01*
X511566Y39125D01*
X511551Y39085D01*
X511541Y39045D01*
X511526Y39000D01*
X511521Y38960D01*
X511511Y38920D01*
X511506Y38875D01*
Y38835D01*
X511501Y38790D01*
X511506Y38745D01*
Y38705D01*
X511511Y38660D01*
X511521Y38620D01*
X511526Y38580D01*
X511541Y38535D01*
X511551Y38495D01*
X511566Y38455D01*
X511586Y38415D01*
X511601Y38380D01*
X511621Y38340D01*
X511721Y38200D01*
X511751Y38170D01*
Y36040D01*
X511761Y35915D01*
X511801Y35790D01*
X511861Y35680D01*
X511941Y35580D01*
X512041Y35500D01*
X512151Y35440D01*
X512276Y35400D01*
X512401Y35390D01*
G37*
G36*
G01X540748D02*
X540873Y35400D01*
X540998Y35440D01*
X541108Y35500D01*
X541208Y35580D01*
X541288Y35680D01*
X541348Y35790D01*
X541388Y35915D01*
X541398Y36040D01*
Y38165D01*
X541428Y38195D01*
X541453Y38230D01*
X541483Y38265D01*
X541503Y38300D01*
X541528Y38335D01*
X541568Y38415D01*
X541613Y38535D01*
X541623Y38575D01*
X541633Y38620D01*
X541638Y38660D01*
X541648Y38705D01*
Y38875D01*
X541638Y38920D01*
X541633Y38960D01*
X541623Y39005D01*
X541613Y39045D01*
X541568Y39165D01*
X541528Y39245D01*
X541503Y39280D01*
X541483Y39315D01*
X541453Y39350D01*
X541428Y39385D01*
X541398Y39415D01*
Y41840D01*
X541388Y41965D01*
X541348Y42090D01*
X541288Y42200D01*
X541208Y42300D01*
X541108Y42380D01*
X540998Y42440D01*
X540873Y42480D01*
X540748Y42490D01*
X540623Y42480D01*
X540498Y42440D01*
X540388Y42380D01*
X540288Y42300D01*
X540208Y42200D01*
X540148Y42090D01*
X540108Y41965D01*
X540098Y41840D01*
Y39410D01*
X540068Y39380D01*
X539968Y39240D01*
X539948Y39200D01*
X539933Y39165D01*
X539913Y39125D01*
X539898Y39085D01*
X539888Y39045D01*
X539873Y39000D01*
X539868Y38960D01*
X539858Y38920D01*
X539853Y38875D01*
Y38835D01*
X539848Y38790D01*
X539853Y38745D01*
Y38705D01*
X539858Y38660D01*
X539868Y38620D01*
X539873Y38580D01*
X539888Y38535D01*
X539898Y38495D01*
X539913Y38455D01*
X539933Y38415D01*
X539948Y38380D01*
X539968Y38340D01*
X540068Y38200D01*
X540098Y38170D01*
Y36040D01*
X540108Y35915D01*
X540148Y35790D01*
X540208Y35680D01*
X540288Y35580D01*
X540388Y35500D01*
X540498Y35440D01*
X540623Y35400D01*
X540748Y35390D01*
G37*
G36*
G01X536023D02*
X536148Y35400D01*
X536273Y35440D01*
X536383Y35500D01*
X536483Y35580D01*
X536563Y35680D01*
X536623Y35790D01*
X536663Y35915D01*
X536673Y36040D01*
Y38165D01*
X536703Y38195D01*
X536728Y38230D01*
X536758Y38265D01*
X536778Y38300D01*
X536803Y38335D01*
X536843Y38415D01*
X536888Y38535D01*
X536898Y38575D01*
X536908Y38620D01*
X536913Y38660D01*
X536923Y38705D01*
Y38875D01*
X536913Y38920D01*
X536908Y38960D01*
X536898Y39005D01*
X536888Y39045D01*
X536843Y39165D01*
X536803Y39245D01*
X536778Y39280D01*
X536758Y39315D01*
X536728Y39350D01*
X536703Y39385D01*
X536673Y39415D01*
Y41840D01*
X536663Y41965D01*
X536623Y42090D01*
X536563Y42200D01*
X536483Y42300D01*
X536383Y42380D01*
X536273Y42440D01*
X536148Y42480D01*
X536023Y42490D01*
X535898Y42480D01*
X535773Y42440D01*
X535663Y42380D01*
X535563Y42300D01*
X535483Y42200D01*
X535423Y42090D01*
X535383Y41965D01*
X535373Y41840D01*
Y39410D01*
X535343Y39380D01*
X535243Y39240D01*
X535223Y39200D01*
X535208Y39165D01*
X535188Y39125D01*
X535173Y39085D01*
X535163Y39045D01*
X535148Y39000D01*
X535143Y38960D01*
X535133Y38920D01*
X535128Y38875D01*
Y38835D01*
X535123Y38790D01*
X535128Y38745D01*
Y38705D01*
X535133Y38660D01*
X535143Y38620D01*
X535148Y38580D01*
X535163Y38535D01*
X535173Y38495D01*
X535188Y38455D01*
X535208Y38415D01*
X535223Y38380D01*
X535243Y38340D01*
X535343Y38200D01*
X535373Y38170D01*
Y36040D01*
X535383Y35915D01*
X535423Y35790D01*
X535483Y35680D01*
X535563Y35580D01*
X535663Y35500D01*
X535773Y35440D01*
X535898Y35400D01*
X536023Y35390D01*
G37*
G36*
G01X531299D02*
X531424Y35400D01*
X531549Y35440D01*
X531659Y35500D01*
X531759Y35580D01*
X531839Y35680D01*
X531899Y35790D01*
X531939Y35915D01*
X531949Y36040D01*
Y38165D01*
X531979Y38195D01*
X532004Y38230D01*
X532034Y38265D01*
X532054Y38300D01*
X532079Y38335D01*
X532119Y38415D01*
X532164Y38535D01*
X532174Y38575D01*
X532184Y38620D01*
X532189Y38660D01*
X532199Y38705D01*
Y38875D01*
X532189Y38920D01*
X532184Y38960D01*
X532174Y39005D01*
X532164Y39045D01*
X532119Y39165D01*
X532079Y39245D01*
X532054Y39280D01*
X532034Y39315D01*
X532004Y39350D01*
X531979Y39385D01*
X531949Y39415D01*
Y41840D01*
X531939Y41965D01*
X531899Y42090D01*
X531839Y42200D01*
X531759Y42300D01*
X531659Y42380D01*
X531549Y42440D01*
X531424Y42480D01*
X531299Y42490D01*
X531174Y42480D01*
X531049Y42440D01*
X530939Y42380D01*
X530839Y42300D01*
X530759Y42200D01*
X530699Y42090D01*
X530659Y41965D01*
X530649Y41840D01*
Y39410D01*
X530619Y39380D01*
X530519Y39240D01*
X530499Y39200D01*
X530484Y39165D01*
X530464Y39125D01*
X530449Y39085D01*
X530439Y39045D01*
X530424Y39000D01*
X530419Y38960D01*
X530409Y38920D01*
X530404Y38875D01*
Y38835D01*
X530399Y38790D01*
X530404Y38745D01*
Y38705D01*
X530409Y38660D01*
X530419Y38620D01*
X530424Y38580D01*
X530439Y38535D01*
X530449Y38495D01*
X530464Y38455D01*
X530484Y38415D01*
X530499Y38380D01*
X530519Y38340D01*
X530619Y38200D01*
X530649Y38170D01*
Y36040D01*
X530659Y35915D01*
X530699Y35790D01*
X530759Y35680D01*
X530839Y35580D01*
X530939Y35500D01*
X531049Y35440D01*
X531174Y35400D01*
X531299Y35390D01*
G37*
G36*
G01X526575D02*
X526700Y35400D01*
X526825Y35440D01*
X526935Y35500D01*
X527035Y35580D01*
X527115Y35680D01*
X527175Y35790D01*
X527215Y35915D01*
X527225Y36040D01*
Y38165D01*
X527255Y38195D01*
X527280Y38230D01*
X527310Y38265D01*
X527330Y38300D01*
X527355Y38335D01*
X527395Y38415D01*
X527440Y38535D01*
X527450Y38575D01*
X527460Y38620D01*
X527465Y38660D01*
X527475Y38705D01*
Y38875D01*
X527465Y38920D01*
X527460Y38960D01*
X527450Y39005D01*
X527440Y39045D01*
X527395Y39165D01*
X527355Y39245D01*
X527330Y39280D01*
X527310Y39315D01*
X527280Y39350D01*
X527255Y39385D01*
X527225Y39415D01*
Y41840D01*
X527215Y41965D01*
X527175Y42090D01*
X527115Y42200D01*
X527035Y42300D01*
X526935Y42380D01*
X526825Y42440D01*
X526700Y42480D01*
X526575Y42490D01*
X526450Y42480D01*
X526325Y42440D01*
X526215Y42380D01*
X526115Y42300D01*
X526035Y42200D01*
X525975Y42090D01*
X525935Y41965D01*
X525925Y41840D01*
Y39410D01*
X525895Y39380D01*
X525795Y39240D01*
X525775Y39200D01*
X525760Y39165D01*
X525740Y39125D01*
X525725Y39085D01*
X525715Y39045D01*
X525700Y39000D01*
X525695Y38960D01*
X525685Y38920D01*
X525680Y38875D01*
Y38835D01*
X525675Y38790D01*
X525680Y38745D01*
Y38705D01*
X525685Y38660D01*
X525695Y38620D01*
X525700Y38580D01*
X525715Y38535D01*
X525725Y38495D01*
X525740Y38455D01*
X525760Y38415D01*
X525775Y38380D01*
X525795Y38340D01*
X525895Y38200D01*
X525925Y38170D01*
Y36040D01*
X525935Y35915D01*
X525975Y35790D01*
X526035Y35680D01*
X526115Y35580D01*
X526215Y35500D01*
X526325Y35440D01*
X526450Y35400D01*
X526575Y35390D01*
G37*
G36*
G01X554921D02*
X555046Y35400D01*
X555171Y35440D01*
X555281Y35500D01*
X555381Y35580D01*
X555461Y35680D01*
X555521Y35790D01*
X555561Y35915D01*
X555571Y36040D01*
Y38165D01*
X555601Y38195D01*
X555626Y38230D01*
X555656Y38265D01*
X555676Y38300D01*
X555701Y38335D01*
X555741Y38415D01*
X555786Y38535D01*
X555796Y38575D01*
X555806Y38620D01*
X555811Y38660D01*
X555821Y38705D01*
Y38875D01*
X555811Y38920D01*
X555806Y38960D01*
X555796Y39005D01*
X555786Y39045D01*
X555741Y39165D01*
X555701Y39245D01*
X555676Y39280D01*
X555656Y39315D01*
X555626Y39350D01*
X555601Y39385D01*
X555571Y39415D01*
Y41840D01*
X555561Y41965D01*
X555521Y42090D01*
X555461Y42200D01*
X555381Y42300D01*
X555281Y42380D01*
X555171Y42440D01*
X555046Y42480D01*
X554921Y42490D01*
X554796Y42480D01*
X554671Y42440D01*
X554561Y42380D01*
X554461Y42300D01*
X554381Y42200D01*
X554321Y42090D01*
X554281Y41965D01*
X554271Y41840D01*
Y39410D01*
X554241Y39380D01*
X554141Y39240D01*
X554121Y39200D01*
X554106Y39165D01*
X554086Y39125D01*
X554071Y39085D01*
X554061Y39045D01*
X554046Y39000D01*
X554041Y38960D01*
X554031Y38920D01*
X554026Y38875D01*
Y38835D01*
X554021Y38790D01*
X554026Y38745D01*
Y38705D01*
X554031Y38660D01*
X554041Y38620D01*
X554046Y38580D01*
X554061Y38535D01*
X554071Y38495D01*
X554086Y38455D01*
X554106Y38415D01*
X554121Y38380D01*
X554141Y38340D01*
X554241Y38200D01*
X554271Y38170D01*
Y36040D01*
X554281Y35915D01*
X554321Y35790D01*
X554381Y35680D01*
X554461Y35580D01*
X554561Y35500D01*
X554671Y35440D01*
X554796Y35400D01*
X554921Y35390D01*
G37*
G36*
G01X550197D02*
X550322Y35400D01*
X550447Y35440D01*
X550557Y35500D01*
X550657Y35580D01*
X550737Y35680D01*
X550797Y35790D01*
X550837Y35915D01*
X550847Y36040D01*
Y38165D01*
X550877Y38195D01*
X550902Y38230D01*
X550932Y38265D01*
X550952Y38300D01*
X550977Y38335D01*
X551017Y38415D01*
X551062Y38535D01*
X551072Y38575D01*
X551082Y38620D01*
X551087Y38660D01*
X551097Y38705D01*
Y38875D01*
X551087Y38920D01*
X551082Y38960D01*
X551072Y39005D01*
X551062Y39045D01*
X551017Y39165D01*
X550977Y39245D01*
X550952Y39280D01*
X550932Y39315D01*
X550902Y39350D01*
X550877Y39385D01*
X550847Y39415D01*
Y41840D01*
X550837Y41965D01*
X550797Y42090D01*
X550737Y42200D01*
X550657Y42300D01*
X550557Y42380D01*
X550447Y42440D01*
X550322Y42480D01*
X550197Y42490D01*
X550072Y42480D01*
X549947Y42440D01*
X549837Y42380D01*
X549737Y42300D01*
X549657Y42200D01*
X549597Y42090D01*
X549557Y41965D01*
X549547Y41840D01*
Y39410D01*
X549517Y39380D01*
X549417Y39240D01*
X549397Y39200D01*
X549382Y39165D01*
X549362Y39125D01*
X549347Y39085D01*
X549337Y39045D01*
X549322Y39000D01*
X549317Y38960D01*
X549307Y38920D01*
X549302Y38875D01*
Y38835D01*
X549297Y38790D01*
X549302Y38745D01*
Y38705D01*
X549307Y38660D01*
X549317Y38620D01*
X549322Y38580D01*
X549337Y38535D01*
X549347Y38495D01*
X549362Y38455D01*
X549382Y38415D01*
X549397Y38380D01*
X549417Y38340D01*
X549517Y38200D01*
X549547Y38170D01*
Y36040D01*
X549557Y35915D01*
X549597Y35790D01*
X549657Y35680D01*
X549737Y35580D01*
X549837Y35500D01*
X549947Y35440D01*
X550072Y35400D01*
X550197Y35390D01*
G37*
G36*
G01X545472D02*
X545597Y35400D01*
X545722Y35440D01*
X545832Y35500D01*
X545932Y35580D01*
X546012Y35680D01*
X546072Y35790D01*
X546112Y35915D01*
X546122Y36040D01*
Y38165D01*
X546152Y38195D01*
X546177Y38230D01*
X546207Y38265D01*
X546227Y38300D01*
X546252Y38335D01*
X546292Y38415D01*
X546337Y38535D01*
X546347Y38575D01*
X546357Y38620D01*
X546362Y38660D01*
X546372Y38705D01*
Y38875D01*
X546362Y38920D01*
X546357Y38960D01*
X546347Y39005D01*
X546337Y39045D01*
X546292Y39165D01*
X546252Y39245D01*
X546227Y39280D01*
X546207Y39315D01*
X546177Y39350D01*
X546152Y39385D01*
X546122Y39415D01*
Y41840D01*
X546112Y41965D01*
X546072Y42090D01*
X546012Y42200D01*
X545932Y42300D01*
X545832Y42380D01*
X545722Y42440D01*
X545597Y42480D01*
X545472Y42490D01*
X545347Y42480D01*
X545222Y42440D01*
X545112Y42380D01*
X545012Y42300D01*
X544932Y42200D01*
X544872Y42090D01*
X544832Y41965D01*
X544822Y41840D01*
Y39410D01*
X544792Y39380D01*
X544692Y39240D01*
X544672Y39200D01*
X544657Y39165D01*
X544637Y39125D01*
X544622Y39085D01*
X544612Y39045D01*
X544597Y39000D01*
X544592Y38960D01*
X544582Y38920D01*
X544577Y38875D01*
Y38835D01*
X544572Y38790D01*
X544577Y38745D01*
Y38705D01*
X544582Y38660D01*
X544592Y38620D01*
X544597Y38580D01*
X544612Y38535D01*
X544622Y38495D01*
X544637Y38455D01*
X544657Y38415D01*
X544672Y38380D01*
X544692Y38340D01*
X544792Y38200D01*
X544822Y38170D01*
Y36040D01*
X544832Y35915D01*
X544872Y35790D01*
X544932Y35680D01*
X545012Y35580D01*
X545112Y35500D01*
X545222Y35440D01*
X545347Y35400D01*
X545472Y35390D01*
G37*
G36*
G01X569094D02*
X569219Y35400D01*
X569344Y35440D01*
X569454Y35500D01*
X569554Y35580D01*
X569634Y35680D01*
X569694Y35790D01*
X569734Y35915D01*
X569744Y36040D01*
Y38165D01*
X569774Y38195D01*
X569799Y38230D01*
X569829Y38265D01*
X569849Y38300D01*
X569874Y38335D01*
X569914Y38415D01*
X569959Y38535D01*
X569969Y38575D01*
X569979Y38620D01*
X569984Y38660D01*
X569994Y38705D01*
Y38875D01*
X569984Y38920D01*
X569979Y38960D01*
X569969Y39005D01*
X569959Y39045D01*
X569914Y39165D01*
X569874Y39245D01*
X569849Y39280D01*
X569829Y39315D01*
X569799Y39350D01*
X569774Y39385D01*
X569744Y39415D01*
Y41840D01*
X569734Y41965D01*
X569694Y42090D01*
X569634Y42200D01*
X569554Y42300D01*
X569454Y42380D01*
X569344Y42440D01*
X569219Y42480D01*
X569094Y42490D01*
X568969Y42480D01*
X568844Y42440D01*
X568734Y42380D01*
X568634Y42300D01*
X568554Y42200D01*
X568494Y42090D01*
X568454Y41965D01*
X568444Y41840D01*
Y39410D01*
X568414Y39380D01*
X568314Y39240D01*
X568294Y39200D01*
X568279Y39165D01*
X568259Y39125D01*
X568244Y39085D01*
X568234Y39045D01*
X568219Y39000D01*
X568214Y38960D01*
X568204Y38920D01*
X568199Y38875D01*
Y38835D01*
X568194Y38790D01*
X568199Y38745D01*
Y38705D01*
X568204Y38660D01*
X568214Y38620D01*
X568219Y38580D01*
X568234Y38535D01*
X568244Y38495D01*
X568259Y38455D01*
X568279Y38415D01*
X568294Y38380D01*
X568314Y38340D01*
X568414Y38200D01*
X568444Y38170D01*
Y36040D01*
X568454Y35915D01*
X568494Y35790D01*
X568554Y35680D01*
X568634Y35580D01*
X568734Y35500D01*
X568844Y35440D01*
X568969Y35400D01*
X569094Y35390D01*
G37*
G36*
G01X564370D02*
X564495Y35400D01*
X564620Y35440D01*
X564730Y35500D01*
X564830Y35580D01*
X564910Y35680D01*
X564970Y35790D01*
X565010Y35915D01*
X565020Y36040D01*
Y38165D01*
X565050Y38195D01*
X565075Y38230D01*
X565105Y38265D01*
X565125Y38300D01*
X565150Y38335D01*
X565190Y38415D01*
X565235Y38535D01*
X565245Y38575D01*
X565255Y38620D01*
X565260Y38660D01*
X565270Y38705D01*
Y38875D01*
X565260Y38920D01*
X565255Y38960D01*
X565245Y39005D01*
X565235Y39045D01*
X565190Y39165D01*
X565150Y39245D01*
X565125Y39280D01*
X565105Y39315D01*
X565075Y39350D01*
X565050Y39385D01*
X565020Y39415D01*
Y41840D01*
X565010Y41965D01*
X564970Y42090D01*
X564910Y42200D01*
X564830Y42300D01*
X564730Y42380D01*
X564620Y42440D01*
X564495Y42480D01*
X564370Y42490D01*
X564245Y42480D01*
X564120Y42440D01*
X564010Y42380D01*
X563910Y42300D01*
X563830Y42200D01*
X563770Y42090D01*
X563730Y41965D01*
X563720Y41840D01*
Y39410D01*
X563690Y39380D01*
X563590Y39240D01*
X563570Y39200D01*
X563555Y39165D01*
X563535Y39125D01*
X563520Y39085D01*
X563510Y39045D01*
X563495Y39000D01*
X563490Y38960D01*
X563480Y38920D01*
X563475Y38875D01*
Y38835D01*
X563470Y38790D01*
X563475Y38745D01*
Y38705D01*
X563480Y38660D01*
X563490Y38620D01*
X563495Y38580D01*
X563510Y38535D01*
X563520Y38495D01*
X563535Y38455D01*
X563555Y38415D01*
X563570Y38380D01*
X563590Y38340D01*
X563690Y38200D01*
X563720Y38170D01*
Y36040D01*
X563730Y35915D01*
X563770Y35790D01*
X563830Y35680D01*
X563910Y35580D01*
X564010Y35500D01*
X564120Y35440D01*
X564245Y35400D01*
X564370Y35390D01*
G37*
G36*
G01X559645D02*
X559770Y35400D01*
X559895Y35440D01*
X560005Y35500D01*
X560105Y35580D01*
X560185Y35680D01*
X560245Y35790D01*
X560285Y35915D01*
X560295Y36040D01*
Y38165D01*
X560325Y38195D01*
X560350Y38230D01*
X560380Y38265D01*
X560400Y38300D01*
X560425Y38335D01*
X560465Y38415D01*
X560510Y38535D01*
X560520Y38575D01*
X560530Y38620D01*
X560535Y38660D01*
X560545Y38705D01*
Y38875D01*
X560535Y38920D01*
X560530Y38960D01*
X560520Y39005D01*
X560510Y39045D01*
X560465Y39165D01*
X560425Y39245D01*
X560400Y39280D01*
X560380Y39315D01*
X560350Y39350D01*
X560325Y39385D01*
X560295Y39415D01*
Y41840D01*
X560285Y41965D01*
X560245Y42090D01*
X560185Y42200D01*
X560105Y42300D01*
X560005Y42380D01*
X559895Y42440D01*
X559770Y42480D01*
X559645Y42490D01*
X559520Y42480D01*
X559395Y42440D01*
X559285Y42380D01*
X559185Y42300D01*
X559105Y42200D01*
X559045Y42090D01*
X559005Y41965D01*
X558995Y41840D01*
Y39410D01*
X558965Y39380D01*
X558865Y39240D01*
X558845Y39200D01*
X558830Y39165D01*
X558810Y39125D01*
X558795Y39085D01*
X558785Y39045D01*
X558770Y39000D01*
X558765Y38960D01*
X558755Y38920D01*
X558750Y38875D01*
Y38835D01*
X558745Y38790D01*
X558750Y38745D01*
Y38705D01*
X558755Y38660D01*
X558765Y38620D01*
X558770Y38580D01*
X558785Y38535D01*
X558795Y38495D01*
X558810Y38455D01*
X558830Y38415D01*
X558845Y38380D01*
X558865Y38340D01*
X558965Y38200D01*
X558995Y38170D01*
Y36040D01*
X559005Y35915D01*
X559045Y35790D01*
X559105Y35680D01*
X559185Y35580D01*
X559285Y35500D01*
X559395Y35440D01*
X559520Y35400D01*
X559645Y35390D01*
G37*
G36*
G01X587992D02*
X588117Y35400D01*
X588242Y35440D01*
X588352Y35500D01*
X588452Y35580D01*
X588532Y35680D01*
X588592Y35790D01*
X588632Y35915D01*
X588642Y36040D01*
Y38165D01*
X588672Y38195D01*
X588697Y38230D01*
X588727Y38265D01*
X588747Y38300D01*
X588772Y38335D01*
X588812Y38415D01*
X588857Y38535D01*
X588867Y38575D01*
X588877Y38620D01*
X588882Y38660D01*
X588892Y38705D01*
Y38875D01*
X588882Y38920D01*
X588877Y38960D01*
X588867Y39005D01*
X588857Y39045D01*
X588812Y39165D01*
X588772Y39245D01*
X588747Y39280D01*
X588727Y39315D01*
X588697Y39350D01*
X588672Y39385D01*
X588642Y39415D01*
Y41840D01*
X588632Y41965D01*
X588592Y42090D01*
X588532Y42200D01*
X588452Y42300D01*
X588352Y42380D01*
X588242Y42440D01*
X588117Y42480D01*
X587992Y42490D01*
X587867Y42480D01*
X587742Y42440D01*
X587632Y42380D01*
X587532Y42300D01*
X587452Y42200D01*
X587392Y42090D01*
X587352Y41965D01*
X587342Y41840D01*
Y39410D01*
X587312Y39380D01*
X587212Y39240D01*
X587192Y39200D01*
X587177Y39165D01*
X587157Y39125D01*
X587142Y39085D01*
X587132Y39045D01*
X587117Y39000D01*
X587112Y38960D01*
X587102Y38920D01*
X587097Y38875D01*
Y38835D01*
X587092Y38790D01*
X587097Y38745D01*
Y38705D01*
X587102Y38660D01*
X587112Y38620D01*
X587117Y38580D01*
X587132Y38535D01*
X587142Y38495D01*
X587157Y38455D01*
X587177Y38415D01*
X587192Y38380D01*
X587212Y38340D01*
X587312Y38200D01*
X587342Y38170D01*
Y36040D01*
X587352Y35915D01*
X587392Y35790D01*
X587452Y35680D01*
X587532Y35580D01*
X587632Y35500D01*
X587742Y35440D01*
X587867Y35400D01*
X587992Y35390D01*
G37*
G36*
G01X583267D02*
X583392Y35400D01*
X583517Y35440D01*
X583627Y35500D01*
X583727Y35580D01*
X583807Y35680D01*
X583867Y35790D01*
X583907Y35915D01*
X583917Y36040D01*
Y38165D01*
X583947Y38195D01*
X583972Y38230D01*
X584002Y38265D01*
X584022Y38300D01*
X584047Y38335D01*
X584087Y38415D01*
X584132Y38535D01*
X584142Y38575D01*
X584152Y38620D01*
X584157Y38660D01*
X584167Y38705D01*
Y38875D01*
X584157Y38920D01*
X584152Y38960D01*
X584142Y39005D01*
X584132Y39045D01*
X584087Y39165D01*
X584047Y39245D01*
X584022Y39280D01*
X584002Y39315D01*
X583972Y39350D01*
X583947Y39385D01*
X583917Y39415D01*
Y41840D01*
X583907Y41965D01*
X583867Y42090D01*
X583807Y42200D01*
X583727Y42300D01*
X583627Y42380D01*
X583517Y42440D01*
X583392Y42480D01*
X583267Y42490D01*
X583142Y42480D01*
X583017Y42440D01*
X582907Y42380D01*
X582807Y42300D01*
X582727Y42200D01*
X582667Y42090D01*
X582627Y41965D01*
X582617Y41840D01*
Y39410D01*
X582587Y39380D01*
X582487Y39240D01*
X582467Y39200D01*
X582452Y39165D01*
X582432Y39125D01*
X582417Y39085D01*
X582407Y39045D01*
X582392Y39000D01*
X582387Y38960D01*
X582377Y38920D01*
X582372Y38875D01*
Y38835D01*
X582367Y38790D01*
X582372Y38745D01*
Y38705D01*
X582377Y38660D01*
X582387Y38620D01*
X582392Y38580D01*
X582407Y38535D01*
X582417Y38495D01*
X582432Y38455D01*
X582452Y38415D01*
X582467Y38380D01*
X582487Y38340D01*
X582587Y38200D01*
X582617Y38170D01*
Y36040D01*
X582627Y35915D01*
X582667Y35790D01*
X582727Y35680D01*
X582807Y35580D01*
X582907Y35500D01*
X583017Y35440D01*
X583142Y35400D01*
X583267Y35390D01*
G37*
G36*
G01X578543D02*
X578668Y35400D01*
X578793Y35440D01*
X578903Y35500D01*
X579003Y35580D01*
X579083Y35680D01*
X579143Y35790D01*
X579183Y35915D01*
X579193Y36040D01*
Y38165D01*
X579223Y38195D01*
X579248Y38230D01*
X579278Y38265D01*
X579298Y38300D01*
X579323Y38335D01*
X579363Y38415D01*
X579408Y38535D01*
X579418Y38575D01*
X579428Y38620D01*
X579433Y38660D01*
X579443Y38705D01*
Y38875D01*
X579433Y38920D01*
X579428Y38960D01*
X579418Y39005D01*
X579408Y39045D01*
X579363Y39165D01*
X579323Y39245D01*
X579298Y39280D01*
X579278Y39315D01*
X579248Y39350D01*
X579223Y39385D01*
X579193Y39415D01*
Y41840D01*
X579183Y41965D01*
X579143Y42090D01*
X579083Y42200D01*
X579003Y42300D01*
X578903Y42380D01*
X578793Y42440D01*
X578668Y42480D01*
X578543Y42490D01*
X578418Y42480D01*
X578293Y42440D01*
X578183Y42380D01*
X578083Y42300D01*
X578003Y42200D01*
X577943Y42090D01*
X577903Y41965D01*
X577893Y41840D01*
Y39410D01*
X577863Y39380D01*
X577763Y39240D01*
X577743Y39200D01*
X577728Y39165D01*
X577708Y39125D01*
X577693Y39085D01*
X577683Y39045D01*
X577668Y39000D01*
X577663Y38960D01*
X577653Y38920D01*
X577648Y38875D01*
Y38835D01*
X577643Y38790D01*
X577648Y38745D01*
Y38705D01*
X577653Y38660D01*
X577663Y38620D01*
X577668Y38580D01*
X577683Y38535D01*
X577693Y38495D01*
X577708Y38455D01*
X577728Y38415D01*
X577743Y38380D01*
X577763Y38340D01*
X577863Y38200D01*
X577893Y38170D01*
Y36040D01*
X577903Y35915D01*
X577943Y35790D01*
X578003Y35680D01*
X578083Y35580D01*
X578183Y35500D01*
X578293Y35440D01*
X578418Y35400D01*
X578543Y35390D01*
G37*
G36*
G01X573819D02*
X573944Y35400D01*
X574069Y35440D01*
X574179Y35500D01*
X574279Y35580D01*
X574359Y35680D01*
X574419Y35790D01*
X574459Y35915D01*
X574469Y36040D01*
Y38165D01*
X574499Y38195D01*
X574524Y38230D01*
X574554Y38265D01*
X574574Y38300D01*
X574599Y38335D01*
X574639Y38415D01*
X574684Y38535D01*
X574694Y38575D01*
X574704Y38620D01*
X574709Y38660D01*
X574719Y38705D01*
Y38875D01*
X574709Y38920D01*
X574704Y38960D01*
X574694Y39005D01*
X574684Y39045D01*
X574639Y39165D01*
X574599Y39245D01*
X574574Y39280D01*
X574554Y39315D01*
X574524Y39350D01*
X574499Y39385D01*
X574469Y39415D01*
Y41840D01*
X574459Y41965D01*
X574419Y42090D01*
X574359Y42200D01*
X574279Y42300D01*
X574179Y42380D01*
X574069Y42440D01*
X573944Y42480D01*
X573819Y42490D01*
X573694Y42480D01*
X573569Y42440D01*
X573459Y42380D01*
X573359Y42300D01*
X573279Y42200D01*
X573219Y42090D01*
X573179Y41965D01*
X573169Y41840D01*
Y39410D01*
X573139Y39380D01*
X573039Y39240D01*
X573019Y39200D01*
X573004Y39165D01*
X572984Y39125D01*
X572969Y39085D01*
X572959Y39045D01*
X572944Y39000D01*
X572939Y38960D01*
X572929Y38920D01*
X572924Y38875D01*
Y38835D01*
X572919Y38790D01*
X572924Y38745D01*
Y38705D01*
X572929Y38660D01*
X572939Y38620D01*
X572944Y38580D01*
X572959Y38535D01*
X572969Y38495D01*
X572984Y38455D01*
X573004Y38415D01*
X573019Y38380D01*
X573039Y38340D01*
X573139Y38200D01*
X573169Y38170D01*
Y36040D01*
X573179Y35915D01*
X573219Y35790D01*
X573279Y35680D01*
X573359Y35580D01*
X573459Y35500D01*
X573569Y35440D01*
X573694Y35400D01*
X573819Y35390D01*
G37*
G36*
G01X602165D02*
X602290Y35400D01*
X602415Y35440D01*
X602525Y35500D01*
X602625Y35580D01*
X602705Y35680D01*
X602765Y35790D01*
X602805Y35915D01*
X602815Y36040D01*
Y38165D01*
X602845Y38195D01*
X602870Y38230D01*
X602900Y38265D01*
X602920Y38300D01*
X602945Y38335D01*
X602985Y38415D01*
X603030Y38535D01*
X603040Y38575D01*
X603050Y38620D01*
X603055Y38660D01*
X603065Y38705D01*
Y38875D01*
X603055Y38920D01*
X603050Y38960D01*
X603040Y39005D01*
X603030Y39045D01*
X602985Y39165D01*
X602945Y39245D01*
X602920Y39280D01*
X602900Y39315D01*
X602870Y39350D01*
X602845Y39385D01*
X602815Y39415D01*
Y41840D01*
X602805Y41965D01*
X602765Y42090D01*
X602705Y42200D01*
X602625Y42300D01*
X602525Y42380D01*
X602415Y42440D01*
X602290Y42480D01*
X602165Y42490D01*
X602040Y42480D01*
X601915Y42440D01*
X601805Y42380D01*
X601705Y42300D01*
X601625Y42200D01*
X601565Y42090D01*
X601525Y41965D01*
X601515Y41840D01*
Y39410D01*
X601485Y39380D01*
X601385Y39240D01*
X601365Y39200D01*
X601350Y39165D01*
X601330Y39125D01*
X601315Y39085D01*
X601305Y39045D01*
X601290Y39000D01*
X601285Y38960D01*
X601275Y38920D01*
X601270Y38875D01*
Y38835D01*
X601265Y38790D01*
X601270Y38745D01*
Y38705D01*
X601275Y38660D01*
X601285Y38620D01*
X601290Y38580D01*
X601305Y38535D01*
X601315Y38495D01*
X601330Y38455D01*
X601350Y38415D01*
X601365Y38380D01*
X601385Y38340D01*
X601485Y38200D01*
X601515Y38170D01*
Y36040D01*
X601525Y35915D01*
X601565Y35790D01*
X601625Y35680D01*
X601705Y35580D01*
X601805Y35500D01*
X601915Y35440D01*
X602040Y35400D01*
X602165Y35390D01*
G37*
G36*
G01X616338D02*
X616463Y35400D01*
X616588Y35440D01*
X616698Y35500D01*
X616798Y35580D01*
X616878Y35680D01*
X616938Y35790D01*
X616978Y35915D01*
X616988Y36040D01*
Y38165D01*
X617018Y38195D01*
X617043Y38230D01*
X617073Y38265D01*
X617093Y38300D01*
X617118Y38335D01*
X617158Y38415D01*
X617203Y38535D01*
X617213Y38575D01*
X617223Y38620D01*
X617228Y38660D01*
X617238Y38705D01*
Y38875D01*
X617228Y38920D01*
X617223Y38960D01*
X617213Y39005D01*
X617203Y39045D01*
X617158Y39165D01*
X617118Y39245D01*
X617093Y39280D01*
X617073Y39315D01*
X617043Y39350D01*
X617018Y39385D01*
X616988Y39415D01*
Y41840D01*
X616978Y41965D01*
X616938Y42090D01*
X616878Y42200D01*
X616798Y42300D01*
X616698Y42380D01*
X616588Y42440D01*
X616463Y42480D01*
X616338Y42490D01*
X616213Y42480D01*
X616088Y42440D01*
X615978Y42380D01*
X615878Y42300D01*
X615798Y42200D01*
X615738Y42090D01*
X615698Y41965D01*
X615688Y41840D01*
Y39410D01*
X615658Y39380D01*
X615558Y39240D01*
X615538Y39200D01*
X615523Y39165D01*
X615503Y39125D01*
X615488Y39085D01*
X615478Y39045D01*
X615463Y39000D01*
X615458Y38960D01*
X615448Y38920D01*
X615443Y38875D01*
Y38835D01*
X615438Y38790D01*
X615443Y38745D01*
Y38705D01*
X615448Y38660D01*
X615458Y38620D01*
X615463Y38580D01*
X615478Y38535D01*
X615488Y38495D01*
X615503Y38455D01*
X615523Y38415D01*
X615538Y38380D01*
X615558Y38340D01*
X615658Y38200D01*
X615688Y38170D01*
Y36040D01*
X615698Y35915D01*
X615738Y35790D01*
X615798Y35680D01*
X615878Y35580D01*
X615978Y35500D01*
X616088Y35440D01*
X616213Y35400D01*
X616338Y35390D01*
G37*
G36*
G01X611614D02*
X611739Y35400D01*
X611864Y35440D01*
X611974Y35500D01*
X612074Y35580D01*
X612154Y35680D01*
X612214Y35790D01*
X612254Y35915D01*
X612264Y36040D01*
Y38165D01*
X612294Y38195D01*
X612319Y38230D01*
X612349Y38265D01*
X612369Y38300D01*
X612394Y38335D01*
X612434Y38415D01*
X612479Y38535D01*
X612489Y38575D01*
X612499Y38620D01*
X612504Y38660D01*
X612514Y38705D01*
Y38875D01*
X612504Y38920D01*
X612499Y38960D01*
X612489Y39005D01*
X612479Y39045D01*
X612434Y39165D01*
X612394Y39245D01*
X612369Y39280D01*
X612349Y39315D01*
X612319Y39350D01*
X612294Y39385D01*
X612264Y39415D01*
Y41840D01*
X612254Y41965D01*
X612214Y42090D01*
X612154Y42200D01*
X612074Y42300D01*
X611974Y42380D01*
X611864Y42440D01*
X611739Y42480D01*
X611614Y42490D01*
X611489Y42480D01*
X611364Y42440D01*
X611254Y42380D01*
X611154Y42300D01*
X611074Y42200D01*
X611014Y42090D01*
X610974Y41965D01*
X610964Y41840D01*
Y39410D01*
X610934Y39380D01*
X610834Y39240D01*
X610814Y39200D01*
X610799Y39165D01*
X610779Y39125D01*
X610764Y39085D01*
X610754Y39045D01*
X610739Y39000D01*
X610734Y38960D01*
X610724Y38920D01*
X610719Y38875D01*
Y38835D01*
X610714Y38790D01*
X610719Y38745D01*
Y38705D01*
X610724Y38660D01*
X610734Y38620D01*
X610739Y38580D01*
X610754Y38535D01*
X610764Y38495D01*
X610779Y38455D01*
X610799Y38415D01*
X610814Y38380D01*
X610834Y38340D01*
X610934Y38200D01*
X610964Y38170D01*
Y36040D01*
X610974Y35915D01*
X611014Y35790D01*
X611074Y35680D01*
X611154Y35580D01*
X611254Y35500D01*
X611364Y35440D01*
X611489Y35400D01*
X611614Y35390D01*
G37*
G36*
G01X606890D02*
X607015Y35400D01*
X607140Y35440D01*
X607250Y35500D01*
X607350Y35580D01*
X607430Y35680D01*
X607490Y35790D01*
X607530Y35915D01*
X607540Y36040D01*
Y38165D01*
X607570Y38195D01*
X607595Y38230D01*
X607625Y38265D01*
X607645Y38300D01*
X607670Y38335D01*
X607710Y38415D01*
X607755Y38535D01*
X607765Y38575D01*
X607775Y38620D01*
X607780Y38660D01*
X607790Y38705D01*
Y38875D01*
X607780Y38920D01*
X607775Y38960D01*
X607765Y39005D01*
X607755Y39045D01*
X607710Y39165D01*
X607670Y39245D01*
X607645Y39280D01*
X607625Y39315D01*
X607595Y39350D01*
X607570Y39385D01*
X607540Y39415D01*
Y41840D01*
X607530Y41965D01*
X607490Y42090D01*
X607430Y42200D01*
X607350Y42300D01*
X607250Y42380D01*
X607140Y42440D01*
X607015Y42480D01*
X606890Y42490D01*
X606765Y42480D01*
X606640Y42440D01*
X606530Y42380D01*
X606430Y42300D01*
X606350Y42200D01*
X606290Y42090D01*
X606250Y41965D01*
X606240Y41840D01*
Y39410D01*
X606210Y39380D01*
X606110Y39240D01*
X606090Y39200D01*
X606075Y39165D01*
X606055Y39125D01*
X606040Y39085D01*
X606030Y39045D01*
X606015Y39000D01*
X606010Y38960D01*
X606000Y38920D01*
X605995Y38875D01*
Y38835D01*
X605990Y38790D01*
X605995Y38745D01*
Y38705D01*
X606000Y38660D01*
X606010Y38620D01*
X606015Y38580D01*
X606030Y38535D01*
X606040Y38495D01*
X606055Y38455D01*
X606075Y38415D01*
X606090Y38380D01*
X606110Y38340D01*
X606210Y38200D01*
X606240Y38170D01*
Y36040D01*
X606250Y35915D01*
X606290Y35790D01*
X606350Y35680D01*
X606430Y35580D01*
X606530Y35500D01*
X606640Y35440D01*
X606765Y35400D01*
X606890Y35390D01*
G37*
G36*
G01X630512D02*
X630637Y35400D01*
X630762Y35440D01*
X630872Y35500D01*
X630972Y35580D01*
X631052Y35680D01*
X631112Y35790D01*
X631152Y35915D01*
X631162Y36040D01*
Y38165D01*
X631192Y38195D01*
X631217Y38230D01*
X631247Y38265D01*
X631267Y38300D01*
X631292Y38335D01*
X631332Y38415D01*
X631377Y38535D01*
X631387Y38575D01*
X631397Y38620D01*
X631402Y38660D01*
X631412Y38705D01*
Y38875D01*
X631402Y38920D01*
X631397Y38960D01*
X631387Y39005D01*
X631377Y39045D01*
X631332Y39165D01*
X631292Y39245D01*
X631267Y39280D01*
X631247Y39315D01*
X631217Y39350D01*
X631192Y39385D01*
X631162Y39415D01*
Y41840D01*
X631152Y41965D01*
X631112Y42090D01*
X631052Y42200D01*
X630972Y42300D01*
X630872Y42380D01*
X630762Y42440D01*
X630637Y42480D01*
X630512Y42490D01*
X630387Y42480D01*
X630262Y42440D01*
X630152Y42380D01*
X630052Y42300D01*
X629972Y42200D01*
X629912Y42090D01*
X629872Y41965D01*
X629862Y41840D01*
Y39410D01*
X629832Y39380D01*
X629732Y39240D01*
X629712Y39200D01*
X629697Y39165D01*
X629677Y39125D01*
X629662Y39085D01*
X629652Y39045D01*
X629637Y39000D01*
X629632Y38960D01*
X629622Y38920D01*
X629617Y38875D01*
Y38835D01*
X629612Y38790D01*
X629617Y38745D01*
Y38705D01*
X629622Y38660D01*
X629632Y38620D01*
X629637Y38580D01*
X629652Y38535D01*
X629662Y38495D01*
X629677Y38455D01*
X629697Y38415D01*
X629712Y38380D01*
X629732Y38340D01*
X629832Y38200D01*
X629862Y38170D01*
Y36040D01*
X629872Y35915D01*
X629912Y35790D01*
X629972Y35680D01*
X630052Y35580D01*
X630152Y35500D01*
X630262Y35440D01*
X630387Y35400D01*
X630512Y35390D01*
G37*
G36*
G01X625787D02*
X625912Y35400D01*
X626037Y35440D01*
X626147Y35500D01*
X626247Y35580D01*
X626327Y35680D01*
X626387Y35790D01*
X626427Y35915D01*
X626437Y36040D01*
Y38165D01*
X626467Y38195D01*
X626492Y38230D01*
X626522Y38265D01*
X626542Y38300D01*
X626567Y38335D01*
X626607Y38415D01*
X626652Y38535D01*
X626662Y38575D01*
X626672Y38620D01*
X626677Y38660D01*
X626687Y38705D01*
Y38875D01*
X626677Y38920D01*
X626672Y38960D01*
X626662Y39005D01*
X626652Y39045D01*
X626607Y39165D01*
X626567Y39245D01*
X626542Y39280D01*
X626522Y39315D01*
X626492Y39350D01*
X626467Y39385D01*
X626437Y39415D01*
Y41840D01*
X626427Y41965D01*
X626387Y42090D01*
X626327Y42200D01*
X626247Y42300D01*
X626147Y42380D01*
X626037Y42440D01*
X625912Y42480D01*
X625787Y42490D01*
X625662Y42480D01*
X625537Y42440D01*
X625427Y42380D01*
X625327Y42300D01*
X625247Y42200D01*
X625187Y42090D01*
X625147Y41965D01*
X625137Y41840D01*
Y39410D01*
X625107Y39380D01*
X625007Y39240D01*
X624987Y39200D01*
X624972Y39165D01*
X624952Y39125D01*
X624937Y39085D01*
X624927Y39045D01*
X624912Y39000D01*
X624907Y38960D01*
X624897Y38920D01*
X624892Y38875D01*
Y38835D01*
X624887Y38790D01*
X624892Y38745D01*
Y38705D01*
X624897Y38660D01*
X624907Y38620D01*
X624912Y38580D01*
X624927Y38535D01*
X624937Y38495D01*
X624952Y38455D01*
X624972Y38415D01*
X624987Y38380D01*
X625007Y38340D01*
X625107Y38200D01*
X625137Y38170D01*
Y36040D01*
X625147Y35915D01*
X625187Y35790D01*
X625247Y35680D01*
X625327Y35580D01*
X625427Y35500D01*
X625537Y35440D01*
X625662Y35400D01*
X625787Y35390D01*
G37*
G36*
G01X621063D02*
X621188Y35400D01*
X621313Y35440D01*
X621423Y35500D01*
X621523Y35580D01*
X621603Y35680D01*
X621663Y35790D01*
X621703Y35915D01*
X621713Y36040D01*
Y38165D01*
X621743Y38195D01*
X621768Y38230D01*
X621798Y38265D01*
X621818Y38300D01*
X621843Y38335D01*
X621883Y38415D01*
X621928Y38535D01*
X621938Y38575D01*
X621948Y38620D01*
X621953Y38660D01*
X621963Y38705D01*
Y38875D01*
X621953Y38920D01*
X621948Y38960D01*
X621938Y39005D01*
X621928Y39045D01*
X621883Y39165D01*
X621843Y39245D01*
X621818Y39280D01*
X621798Y39315D01*
X621768Y39350D01*
X621743Y39385D01*
X621713Y39415D01*
Y41840D01*
X621703Y41965D01*
X621663Y42090D01*
X621603Y42200D01*
X621523Y42300D01*
X621423Y42380D01*
X621313Y42440D01*
X621188Y42480D01*
X621063Y42490D01*
X620938Y42480D01*
X620813Y42440D01*
X620703Y42380D01*
X620603Y42300D01*
X620523Y42200D01*
X620463Y42090D01*
X620423Y41965D01*
X620413Y41840D01*
Y39410D01*
X620383Y39380D01*
X620283Y39240D01*
X620263Y39200D01*
X620248Y39165D01*
X620228Y39125D01*
X620213Y39085D01*
X620203Y39045D01*
X620188Y39000D01*
X620183Y38960D01*
X620173Y38920D01*
X620168Y38875D01*
Y38835D01*
X620163Y38790D01*
X620168Y38745D01*
Y38705D01*
X620173Y38660D01*
X620183Y38620D01*
X620188Y38580D01*
X620203Y38535D01*
X620213Y38495D01*
X620228Y38455D01*
X620248Y38415D01*
X620263Y38380D01*
X620283Y38340D01*
X620383Y38200D01*
X620413Y38170D01*
Y36040D01*
X620423Y35915D01*
X620463Y35790D01*
X620523Y35680D01*
X620603Y35580D01*
X620703Y35500D01*
X620813Y35440D01*
X620938Y35400D01*
X621063Y35390D01*
G37*
G36*
G01X649409D02*
X649534Y35400D01*
X649659Y35440D01*
X649769Y35500D01*
X649869Y35580D01*
X649949Y35680D01*
X650009Y35790D01*
X650049Y35915D01*
X650059Y36040D01*
Y38165D01*
X650089Y38195D01*
X650114Y38230D01*
X650144Y38265D01*
X650164Y38300D01*
X650189Y38335D01*
X650229Y38415D01*
X650274Y38535D01*
X650284Y38575D01*
X650294Y38620D01*
X650299Y38660D01*
X650309Y38705D01*
Y38875D01*
X650299Y38920D01*
X650294Y38960D01*
X650284Y39005D01*
X650274Y39045D01*
X650229Y39165D01*
X650189Y39245D01*
X650164Y39280D01*
X650144Y39315D01*
X650114Y39350D01*
X650089Y39385D01*
X650059Y39415D01*
Y41840D01*
X650049Y41965D01*
X650009Y42090D01*
X649949Y42200D01*
X649869Y42300D01*
X649769Y42380D01*
X649659Y42440D01*
X649534Y42480D01*
X649409Y42490D01*
X649284Y42480D01*
X649159Y42440D01*
X649049Y42380D01*
X648949Y42300D01*
X648869Y42200D01*
X648809Y42090D01*
X648769Y41965D01*
X648759Y41840D01*
Y39410D01*
X648729Y39380D01*
X648629Y39240D01*
X648609Y39200D01*
X648594Y39165D01*
X648574Y39125D01*
X648559Y39085D01*
X648549Y39045D01*
X648534Y39000D01*
X648529Y38960D01*
X648519Y38920D01*
X648514Y38875D01*
Y38835D01*
X648509Y38790D01*
X648514Y38745D01*
Y38705D01*
X648519Y38660D01*
X648529Y38620D01*
X648534Y38580D01*
X648549Y38535D01*
X648559Y38495D01*
X648574Y38455D01*
X648594Y38415D01*
X648609Y38380D01*
X648629Y38340D01*
X648729Y38200D01*
X648759Y38170D01*
Y36040D01*
X648769Y35915D01*
X648809Y35790D01*
X648869Y35680D01*
X648949Y35580D01*
X649049Y35500D01*
X649159Y35440D01*
X649284Y35400D01*
X649409Y35390D01*
G37*
G36*
G01X644685D02*
X644810Y35400D01*
X644935Y35440D01*
X645045Y35500D01*
X645145Y35580D01*
X645225Y35680D01*
X645285Y35790D01*
X645325Y35915D01*
X645335Y36040D01*
Y38165D01*
X645365Y38195D01*
X645390Y38230D01*
X645420Y38265D01*
X645440Y38300D01*
X645465Y38335D01*
X645505Y38415D01*
X645550Y38535D01*
X645560Y38575D01*
X645570Y38620D01*
X645575Y38660D01*
X645585Y38705D01*
Y38875D01*
X645575Y38920D01*
X645570Y38960D01*
X645560Y39005D01*
X645550Y39045D01*
X645505Y39165D01*
X645465Y39245D01*
X645440Y39280D01*
X645420Y39315D01*
X645390Y39350D01*
X645365Y39385D01*
X645335Y39415D01*
Y41840D01*
X645325Y41965D01*
X645285Y42090D01*
X645225Y42200D01*
X645145Y42300D01*
X645045Y42380D01*
X644935Y42440D01*
X644810Y42480D01*
X644685Y42490D01*
X644560Y42480D01*
X644435Y42440D01*
X644325Y42380D01*
X644225Y42300D01*
X644145Y42200D01*
X644085Y42090D01*
X644045Y41965D01*
X644035Y41840D01*
Y39410D01*
X644005Y39380D01*
X643905Y39240D01*
X643885Y39200D01*
X643870Y39165D01*
X643850Y39125D01*
X643835Y39085D01*
X643825Y39045D01*
X643810Y39000D01*
X643805Y38960D01*
X643795Y38920D01*
X643790Y38875D01*
Y38835D01*
X643785Y38790D01*
X643790Y38745D01*
Y38705D01*
X643795Y38660D01*
X643805Y38620D01*
X643810Y38580D01*
X643825Y38535D01*
X643835Y38495D01*
X643850Y38455D01*
X643870Y38415D01*
X643885Y38380D01*
X643905Y38340D01*
X644005Y38200D01*
X644035Y38170D01*
Y36040D01*
X644045Y35915D01*
X644085Y35790D01*
X644145Y35680D01*
X644225Y35580D01*
X644325Y35500D01*
X644435Y35440D01*
X644560Y35400D01*
X644685Y35390D01*
G37*
G36*
G01X639960D02*
X640085Y35400D01*
X640210Y35440D01*
X640320Y35500D01*
X640420Y35580D01*
X640500Y35680D01*
X640560Y35790D01*
X640600Y35915D01*
X640610Y36040D01*
Y38165D01*
X640640Y38195D01*
X640665Y38230D01*
X640695Y38265D01*
X640715Y38300D01*
X640740Y38335D01*
X640780Y38415D01*
X640825Y38535D01*
X640835Y38575D01*
X640845Y38620D01*
X640850Y38660D01*
X640860Y38705D01*
Y38875D01*
X640850Y38920D01*
X640845Y38960D01*
X640835Y39005D01*
X640825Y39045D01*
X640780Y39165D01*
X640740Y39245D01*
X640715Y39280D01*
X640695Y39315D01*
X640665Y39350D01*
X640640Y39385D01*
X640610Y39415D01*
Y41840D01*
X640600Y41965D01*
X640560Y42090D01*
X640500Y42200D01*
X640420Y42300D01*
X640320Y42380D01*
X640210Y42440D01*
X640085Y42480D01*
X639960Y42490D01*
X639835Y42480D01*
X639710Y42440D01*
X639600Y42380D01*
X639500Y42300D01*
X639420Y42200D01*
X639360Y42090D01*
X639320Y41965D01*
X639310Y41840D01*
Y39410D01*
X639280Y39380D01*
X639180Y39240D01*
X639160Y39200D01*
X639145Y39165D01*
X639125Y39125D01*
X639110Y39085D01*
X639100Y39045D01*
X639085Y39000D01*
X639080Y38960D01*
X639070Y38920D01*
X639065Y38875D01*
Y38835D01*
X639060Y38790D01*
X639065Y38745D01*
Y38705D01*
X639070Y38660D01*
X639080Y38620D01*
X639085Y38580D01*
X639100Y38535D01*
X639110Y38495D01*
X639125Y38455D01*
X639145Y38415D01*
X639160Y38380D01*
X639180Y38340D01*
X639280Y38200D01*
X639310Y38170D01*
Y36040D01*
X639320Y35915D01*
X639360Y35790D01*
X639420Y35680D01*
X639500Y35580D01*
X639600Y35500D01*
X639710Y35440D01*
X639835Y35400D01*
X639960Y35390D01*
G37*
G36*
G01X635236D02*
X635361Y35400D01*
X635486Y35440D01*
X635596Y35500D01*
X635696Y35580D01*
X635776Y35680D01*
X635836Y35790D01*
X635876Y35915D01*
X635886Y36040D01*
Y38165D01*
X635916Y38195D01*
X635941Y38230D01*
X635971Y38265D01*
X635991Y38300D01*
X636016Y38335D01*
X636056Y38415D01*
X636101Y38535D01*
X636111Y38575D01*
X636121Y38620D01*
X636126Y38660D01*
X636136Y38705D01*
Y38875D01*
X636126Y38920D01*
X636121Y38960D01*
X636111Y39005D01*
X636101Y39045D01*
X636056Y39165D01*
X636016Y39245D01*
X635991Y39280D01*
X635971Y39315D01*
X635941Y39350D01*
X635916Y39385D01*
X635886Y39415D01*
Y41840D01*
X635876Y41965D01*
X635836Y42090D01*
X635776Y42200D01*
X635696Y42300D01*
X635596Y42380D01*
X635486Y42440D01*
X635361Y42480D01*
X635236Y42490D01*
X635111Y42480D01*
X634986Y42440D01*
X634876Y42380D01*
X634776Y42300D01*
X634696Y42200D01*
X634636Y42090D01*
X634596Y41965D01*
X634586Y41840D01*
Y39410D01*
X634556Y39380D01*
X634456Y39240D01*
X634436Y39200D01*
X634421Y39165D01*
X634401Y39125D01*
X634386Y39085D01*
X634376Y39045D01*
X634361Y39000D01*
X634356Y38960D01*
X634346Y38920D01*
X634341Y38875D01*
Y38835D01*
X634336Y38790D01*
X634341Y38745D01*
Y38705D01*
X634346Y38660D01*
X634356Y38620D01*
X634361Y38580D01*
X634376Y38535D01*
X634386Y38495D01*
X634401Y38455D01*
X634421Y38415D01*
X634436Y38380D01*
X634456Y38340D01*
X634556Y38200D01*
X634586Y38170D01*
Y36040D01*
X634596Y35915D01*
X634636Y35790D01*
X634696Y35680D01*
X634776Y35580D01*
X634876Y35500D01*
X634986Y35440D01*
X635111Y35400D01*
X635236Y35390D01*
G37*
G36*
G01X663582D02*
X663707Y35400D01*
X663832Y35440D01*
X663942Y35500D01*
X664042Y35580D01*
X664122Y35680D01*
X664182Y35790D01*
X664222Y35915D01*
X664232Y36040D01*
Y38165D01*
X664262Y38195D01*
X664287Y38230D01*
X664317Y38265D01*
X664337Y38300D01*
X664362Y38335D01*
X664402Y38415D01*
X664447Y38535D01*
X664457Y38575D01*
X664467Y38620D01*
X664472Y38660D01*
X664482Y38705D01*
Y38875D01*
X664472Y38920D01*
X664467Y38960D01*
X664457Y39005D01*
X664447Y39045D01*
X664402Y39165D01*
X664362Y39245D01*
X664337Y39280D01*
X664317Y39315D01*
X664287Y39350D01*
X664262Y39385D01*
X664232Y39415D01*
Y41840D01*
X664222Y41965D01*
X664182Y42090D01*
X664122Y42200D01*
X664042Y42300D01*
X663942Y42380D01*
X663832Y42440D01*
X663707Y42480D01*
X663582Y42490D01*
X663457Y42480D01*
X663332Y42440D01*
X663222Y42380D01*
X663122Y42300D01*
X663042Y42200D01*
X662982Y42090D01*
X662942Y41965D01*
X662932Y41840D01*
Y39410D01*
X662902Y39380D01*
X662802Y39240D01*
X662782Y39200D01*
X662767Y39165D01*
X662747Y39125D01*
X662732Y39085D01*
X662722Y39045D01*
X662707Y39000D01*
X662702Y38960D01*
X662692Y38920D01*
X662687Y38875D01*
Y38835D01*
X662682Y38790D01*
X662687Y38745D01*
Y38705D01*
X662692Y38660D01*
X662702Y38620D01*
X662707Y38580D01*
X662722Y38535D01*
X662732Y38495D01*
X662747Y38455D01*
X662767Y38415D01*
X662782Y38380D01*
X662802Y38340D01*
X662902Y38200D01*
X662932Y38170D01*
Y36040D01*
X662942Y35915D01*
X662982Y35790D01*
X663042Y35680D01*
X663122Y35580D01*
X663222Y35500D01*
X663332Y35440D01*
X663457Y35400D01*
X663582Y35390D01*
G37*
G36*
G01X658858D02*
X658983Y35400D01*
X659108Y35440D01*
X659218Y35500D01*
X659318Y35580D01*
X659398Y35680D01*
X659458Y35790D01*
X659498Y35915D01*
X659508Y36040D01*
Y38165D01*
X659538Y38195D01*
X659563Y38230D01*
X659593Y38265D01*
X659613Y38300D01*
X659638Y38335D01*
X659678Y38415D01*
X659723Y38535D01*
X659733Y38575D01*
X659743Y38620D01*
X659748Y38660D01*
X659758Y38705D01*
Y38875D01*
X659748Y38920D01*
X659743Y38960D01*
X659733Y39005D01*
X659723Y39045D01*
X659678Y39165D01*
X659638Y39245D01*
X659613Y39280D01*
X659593Y39315D01*
X659563Y39350D01*
X659538Y39385D01*
X659508Y39415D01*
Y41840D01*
X659498Y41965D01*
X659458Y42090D01*
X659398Y42200D01*
X659318Y42300D01*
X659218Y42380D01*
X659108Y42440D01*
X658983Y42480D01*
X658858Y42490D01*
X658733Y42480D01*
X658608Y42440D01*
X658498Y42380D01*
X658398Y42300D01*
X658318Y42200D01*
X658258Y42090D01*
X658218Y41965D01*
X658208Y41840D01*
Y39410D01*
X658178Y39380D01*
X658078Y39240D01*
X658058Y39200D01*
X658043Y39165D01*
X658023Y39125D01*
X658008Y39085D01*
X657998Y39045D01*
X657983Y39000D01*
X657978Y38960D01*
X657968Y38920D01*
X657963Y38875D01*
Y38835D01*
X657958Y38790D01*
X657963Y38745D01*
Y38705D01*
X657968Y38660D01*
X657978Y38620D01*
X657983Y38580D01*
X657998Y38535D01*
X658008Y38495D01*
X658023Y38455D01*
X658043Y38415D01*
X658058Y38380D01*
X658078Y38340D01*
X658178Y38200D01*
X658208Y38170D01*
Y36040D01*
X658218Y35915D01*
X658258Y35790D01*
X658318Y35680D01*
X658398Y35580D01*
X658498Y35500D01*
X658608Y35440D01*
X658733Y35400D01*
X658858Y35390D01*
G37*
G36*
G01X654134D02*
X654259Y35400D01*
X654384Y35440D01*
X654494Y35500D01*
X654594Y35580D01*
X654674Y35680D01*
X654734Y35790D01*
X654774Y35915D01*
X654784Y36040D01*
Y38165D01*
X654814Y38195D01*
X654839Y38230D01*
X654869Y38265D01*
X654889Y38300D01*
X654914Y38335D01*
X654954Y38415D01*
X654999Y38535D01*
X655009Y38575D01*
X655019Y38620D01*
X655024Y38660D01*
X655034Y38705D01*
Y38875D01*
X655024Y38920D01*
X655019Y38960D01*
X655009Y39005D01*
X654999Y39045D01*
X654954Y39165D01*
X654914Y39245D01*
X654889Y39280D01*
X654869Y39315D01*
X654839Y39350D01*
X654814Y39385D01*
X654784Y39415D01*
Y41840D01*
X654774Y41965D01*
X654734Y42090D01*
X654674Y42200D01*
X654594Y42300D01*
X654494Y42380D01*
X654384Y42440D01*
X654259Y42480D01*
X654134Y42490D01*
X654009Y42480D01*
X653884Y42440D01*
X653774Y42380D01*
X653674Y42300D01*
X653594Y42200D01*
X653534Y42090D01*
X653494Y41965D01*
X653484Y41840D01*
Y39410D01*
X653454Y39380D01*
X653354Y39240D01*
X653334Y39200D01*
X653319Y39165D01*
X653299Y39125D01*
X653284Y39085D01*
X653274Y39045D01*
X653259Y39000D01*
X653254Y38960D01*
X653244Y38920D01*
X653239Y38875D01*
Y38835D01*
X653234Y38790D01*
X653239Y38745D01*
Y38705D01*
X653244Y38660D01*
X653254Y38620D01*
X653259Y38580D01*
X653274Y38535D01*
X653284Y38495D01*
X653299Y38455D01*
X653319Y38415D01*
X653334Y38380D01*
X653354Y38340D01*
X653454Y38200D01*
X653484Y38170D01*
Y36040D01*
X653494Y35915D01*
X653534Y35790D01*
X653594Y35680D01*
X653674Y35580D01*
X653774Y35500D01*
X653884Y35440D01*
X654009Y35400D01*
X654134Y35390D01*
G37*
G36*
G01X677756D02*
X677881Y35400D01*
X678006Y35440D01*
X678116Y35500D01*
X678216Y35580D01*
X678296Y35680D01*
X678356Y35790D01*
X678396Y35915D01*
X678406Y36040D01*
Y38165D01*
X678436Y38195D01*
X678461Y38230D01*
X678491Y38265D01*
X678511Y38300D01*
X678536Y38335D01*
X678576Y38415D01*
X678621Y38535D01*
X678631Y38575D01*
X678641Y38620D01*
X678646Y38660D01*
X678656Y38705D01*
Y38875D01*
X678646Y38920D01*
X678641Y38960D01*
X678631Y39005D01*
X678621Y39045D01*
X678576Y39165D01*
X678536Y39245D01*
X678511Y39280D01*
X678491Y39315D01*
X678461Y39350D01*
X678436Y39385D01*
X678406Y39415D01*
Y41840D01*
X678396Y41965D01*
X678356Y42090D01*
X678296Y42200D01*
X678216Y42300D01*
X678116Y42380D01*
X678006Y42440D01*
X677881Y42480D01*
X677756Y42490D01*
X677631Y42480D01*
X677506Y42440D01*
X677396Y42380D01*
X677296Y42300D01*
X677216Y42200D01*
X677156Y42090D01*
X677116Y41965D01*
X677106Y41840D01*
Y39410D01*
X677076Y39380D01*
X676976Y39240D01*
X676956Y39200D01*
X676941Y39165D01*
X676921Y39125D01*
X676906Y39085D01*
X676896Y39045D01*
X676881Y39000D01*
X676876Y38960D01*
X676866Y38920D01*
X676861Y38875D01*
Y38835D01*
X676856Y38790D01*
X676861Y38745D01*
Y38705D01*
X676866Y38660D01*
X676876Y38620D01*
X676881Y38580D01*
X676896Y38535D01*
X676906Y38495D01*
X676921Y38455D01*
X676941Y38415D01*
X676956Y38380D01*
X676976Y38340D01*
X677076Y38200D01*
X677106Y38170D01*
Y36040D01*
X677116Y35915D01*
X677156Y35790D01*
X677216Y35680D01*
X677296Y35580D01*
X677396Y35500D01*
X677506Y35440D01*
X677631Y35400D01*
X677756Y35390D01*
G37*
G36*
G01X673031D02*
X673156Y35400D01*
X673281Y35440D01*
X673391Y35500D01*
X673491Y35580D01*
X673571Y35680D01*
X673631Y35790D01*
X673671Y35915D01*
X673681Y36040D01*
Y38165D01*
X673711Y38195D01*
X673736Y38230D01*
X673766Y38265D01*
X673786Y38300D01*
X673811Y38335D01*
X673851Y38415D01*
X673896Y38535D01*
X673906Y38575D01*
X673916Y38620D01*
X673921Y38660D01*
X673931Y38705D01*
Y38875D01*
X673921Y38920D01*
X673916Y38960D01*
X673906Y39005D01*
X673896Y39045D01*
X673851Y39165D01*
X673811Y39245D01*
X673786Y39280D01*
X673766Y39315D01*
X673736Y39350D01*
X673711Y39385D01*
X673681Y39415D01*
Y41840D01*
X673671Y41965D01*
X673631Y42090D01*
X673571Y42200D01*
X673491Y42300D01*
X673391Y42380D01*
X673281Y42440D01*
X673156Y42480D01*
X673031Y42490D01*
X672906Y42480D01*
X672781Y42440D01*
X672671Y42380D01*
X672571Y42300D01*
X672491Y42200D01*
X672431Y42090D01*
X672391Y41965D01*
X672381Y41840D01*
Y39410D01*
X672351Y39380D01*
X672251Y39240D01*
X672231Y39200D01*
X672216Y39165D01*
X672196Y39125D01*
X672181Y39085D01*
X672171Y39045D01*
X672156Y39000D01*
X672151Y38960D01*
X672141Y38920D01*
X672136Y38875D01*
Y38835D01*
X672131Y38790D01*
X672136Y38745D01*
Y38705D01*
X672141Y38660D01*
X672151Y38620D01*
X672156Y38580D01*
X672171Y38535D01*
X672181Y38495D01*
X672196Y38455D01*
X672216Y38415D01*
X672231Y38380D01*
X672251Y38340D01*
X672351Y38200D01*
X672381Y38170D01*
Y36040D01*
X672391Y35915D01*
X672431Y35790D01*
X672491Y35680D01*
X672571Y35580D01*
X672671Y35500D01*
X672781Y35440D01*
X672906Y35400D01*
X673031Y35390D01*
G37*
G36*
G01X668307D02*
X668432Y35400D01*
X668557Y35440D01*
X668667Y35500D01*
X668767Y35580D01*
X668847Y35680D01*
X668907Y35790D01*
X668947Y35915D01*
X668957Y36040D01*
Y38165D01*
X668987Y38195D01*
X669012Y38230D01*
X669042Y38265D01*
X669062Y38300D01*
X669087Y38335D01*
X669127Y38415D01*
X669172Y38535D01*
X669182Y38575D01*
X669192Y38620D01*
X669197Y38660D01*
X669207Y38705D01*
Y38875D01*
X669197Y38920D01*
X669192Y38960D01*
X669182Y39005D01*
X669172Y39045D01*
X669127Y39165D01*
X669087Y39245D01*
X669062Y39280D01*
X669042Y39315D01*
X669012Y39350D01*
X668987Y39385D01*
X668957Y39415D01*
Y41840D01*
X668947Y41965D01*
X668907Y42090D01*
X668847Y42200D01*
X668767Y42300D01*
X668667Y42380D01*
X668557Y42440D01*
X668432Y42480D01*
X668307Y42490D01*
X668182Y42480D01*
X668057Y42440D01*
X667947Y42380D01*
X667847Y42300D01*
X667767Y42200D01*
X667707Y42090D01*
X667667Y41965D01*
X667657Y41840D01*
Y39410D01*
X667627Y39380D01*
X667527Y39240D01*
X667507Y39200D01*
X667492Y39165D01*
X667472Y39125D01*
X667457Y39085D01*
X667447Y39045D01*
X667432Y39000D01*
X667427Y38960D01*
X667417Y38920D01*
X667412Y38875D01*
Y38835D01*
X667407Y38790D01*
X667412Y38745D01*
Y38705D01*
X667417Y38660D01*
X667427Y38620D01*
X667432Y38580D01*
X667447Y38535D01*
X667457Y38495D01*
X667472Y38455D01*
X667492Y38415D01*
X667507Y38380D01*
X667527Y38340D01*
X667627Y38200D01*
X667657Y38170D01*
Y36040D01*
X667667Y35915D01*
X667707Y35790D01*
X667767Y35680D01*
X667847Y35580D01*
X667947Y35500D01*
X668057Y35440D01*
X668182Y35400D01*
X668307Y35390D01*
G37*
G36*
G01X691929D02*
X692054Y35400D01*
X692179Y35440D01*
X692289Y35500D01*
X692389Y35580D01*
X692469Y35680D01*
X692529Y35790D01*
X692569Y35915D01*
X692579Y36040D01*
Y38165D01*
X692609Y38195D01*
X692634Y38230D01*
X692664Y38265D01*
X692684Y38300D01*
X692709Y38335D01*
X692749Y38415D01*
X692794Y38535D01*
X692804Y38575D01*
X692814Y38620D01*
X692819Y38660D01*
X692829Y38705D01*
Y38875D01*
X692819Y38920D01*
X692814Y38960D01*
X692804Y39005D01*
X692794Y39045D01*
X692749Y39165D01*
X692709Y39245D01*
X692684Y39280D01*
X692664Y39315D01*
X692634Y39350D01*
X692609Y39385D01*
X692579Y39415D01*
Y41840D01*
X692569Y41965D01*
X692529Y42090D01*
X692469Y42200D01*
X692389Y42300D01*
X692289Y42380D01*
X692179Y42440D01*
X692054Y42480D01*
X691929Y42490D01*
X691804Y42480D01*
X691679Y42440D01*
X691569Y42380D01*
X691469Y42300D01*
X691389Y42200D01*
X691329Y42090D01*
X691289Y41965D01*
X691279Y41840D01*
Y39410D01*
X691249Y39380D01*
X691149Y39240D01*
X691129Y39200D01*
X691114Y39165D01*
X691094Y39125D01*
X691079Y39085D01*
X691069Y39045D01*
X691054Y39000D01*
X691049Y38960D01*
X691039Y38920D01*
X691034Y38875D01*
Y38835D01*
X691029Y38790D01*
X691034Y38745D01*
Y38705D01*
X691039Y38660D01*
X691049Y38620D01*
X691054Y38580D01*
X691069Y38535D01*
X691079Y38495D01*
X691094Y38455D01*
X691114Y38415D01*
X691129Y38380D01*
X691149Y38340D01*
X691249Y38200D01*
X691279Y38170D01*
Y36040D01*
X691289Y35915D01*
X691329Y35790D01*
X691389Y35680D01*
X691469Y35580D01*
X691569Y35500D01*
X691679Y35440D01*
X691804Y35400D01*
X691929Y35390D01*
G37*
G36*
G01X687204D02*
X687329Y35400D01*
X687454Y35440D01*
X687564Y35500D01*
X687664Y35580D01*
X687744Y35680D01*
X687804Y35790D01*
X687844Y35915D01*
X687854Y36040D01*
Y38165D01*
X687884Y38195D01*
X687909Y38230D01*
X687939Y38265D01*
X687959Y38300D01*
X687984Y38335D01*
X688024Y38415D01*
X688069Y38535D01*
X688079Y38575D01*
X688089Y38620D01*
X688094Y38660D01*
X688104Y38705D01*
Y38875D01*
X688094Y38920D01*
X688089Y38960D01*
X688079Y39005D01*
X688069Y39045D01*
X688024Y39165D01*
X687984Y39245D01*
X687959Y39280D01*
X687939Y39315D01*
X687909Y39350D01*
X687884Y39385D01*
X687854Y39415D01*
Y41840D01*
X687844Y41965D01*
X687804Y42090D01*
X687744Y42200D01*
X687664Y42300D01*
X687564Y42380D01*
X687454Y42440D01*
X687329Y42480D01*
X687204Y42490D01*
X687079Y42480D01*
X686954Y42440D01*
X686844Y42380D01*
X686744Y42300D01*
X686664Y42200D01*
X686604Y42090D01*
X686564Y41965D01*
X686554Y41840D01*
Y39410D01*
X686524Y39380D01*
X686424Y39240D01*
X686404Y39200D01*
X686389Y39165D01*
X686369Y39125D01*
X686354Y39085D01*
X686344Y39045D01*
X686329Y39000D01*
X686324Y38960D01*
X686314Y38920D01*
X686309Y38875D01*
Y38835D01*
X686304Y38790D01*
X686309Y38745D01*
Y38705D01*
X686314Y38660D01*
X686324Y38620D01*
X686329Y38580D01*
X686344Y38535D01*
X686354Y38495D01*
X686369Y38455D01*
X686389Y38415D01*
X686404Y38380D01*
X686424Y38340D01*
X686524Y38200D01*
X686554Y38170D01*
Y36040D01*
X686564Y35915D01*
X686604Y35790D01*
X686664Y35680D01*
X686744Y35580D01*
X686844Y35500D01*
X686954Y35440D01*
X687079Y35400D01*
X687204Y35390D01*
G37*
G36*
G01X682480D02*
X682605Y35400D01*
X682730Y35440D01*
X682840Y35500D01*
X682940Y35580D01*
X683020Y35680D01*
X683080Y35790D01*
X683120Y35915D01*
X683130Y36040D01*
Y38165D01*
X683160Y38195D01*
X683185Y38230D01*
X683215Y38265D01*
X683235Y38300D01*
X683260Y38335D01*
X683300Y38415D01*
X683345Y38535D01*
X683355Y38575D01*
X683365Y38620D01*
X683370Y38660D01*
X683380Y38705D01*
Y38875D01*
X683370Y38920D01*
X683365Y38960D01*
X683355Y39005D01*
X683345Y39045D01*
X683300Y39165D01*
X683260Y39245D01*
X683235Y39280D01*
X683215Y39315D01*
X683185Y39350D01*
X683160Y39385D01*
X683130Y39415D01*
Y41840D01*
X683120Y41965D01*
X683080Y42090D01*
X683020Y42200D01*
X682940Y42300D01*
X682840Y42380D01*
X682730Y42440D01*
X682605Y42480D01*
X682480Y42490D01*
X682355Y42480D01*
X682230Y42440D01*
X682120Y42380D01*
X682020Y42300D01*
X681940Y42200D01*
X681880Y42090D01*
X681840Y41965D01*
X681830Y41840D01*
Y39410D01*
X681800Y39380D01*
X681700Y39240D01*
X681680Y39200D01*
X681665Y39165D01*
X681645Y39125D01*
X681630Y39085D01*
X681620Y39045D01*
X681605Y39000D01*
X681600Y38960D01*
X681590Y38920D01*
X681585Y38875D01*
Y38835D01*
X681580Y38790D01*
X681585Y38745D01*
Y38705D01*
X681590Y38660D01*
X681600Y38620D01*
X681605Y38580D01*
X681620Y38535D01*
X681630Y38495D01*
X681645Y38455D01*
X681665Y38415D01*
X681680Y38380D01*
X681700Y38340D01*
X681800Y38200D01*
X681830Y38170D01*
Y36040D01*
X681840Y35915D01*
X681880Y35790D01*
X681940Y35680D01*
X682020Y35580D01*
X682120Y35500D01*
X682230Y35440D01*
X682355Y35400D01*
X682480Y35390D01*
G37*
G36*
G01X710827D02*
X710952Y35400D01*
X711077Y35440D01*
X711187Y35500D01*
X711287Y35580D01*
X711367Y35680D01*
X711427Y35790D01*
X711467Y35915D01*
X711477Y36040D01*
Y38165D01*
X711507Y38195D01*
X711532Y38230D01*
X711562Y38265D01*
X711582Y38300D01*
X711607Y38335D01*
X711647Y38415D01*
X711692Y38535D01*
X711702Y38575D01*
X711712Y38620D01*
X711717Y38660D01*
X711727Y38705D01*
Y38875D01*
X711717Y38920D01*
X711712Y38960D01*
X711702Y39005D01*
X711692Y39045D01*
X711647Y39165D01*
X711607Y39245D01*
X711582Y39280D01*
X711562Y39315D01*
X711532Y39350D01*
X711507Y39385D01*
X711477Y39415D01*
Y41840D01*
X711467Y41965D01*
X711427Y42090D01*
X711367Y42200D01*
X711287Y42300D01*
X711187Y42380D01*
X711077Y42440D01*
X710952Y42480D01*
X710827Y42490D01*
X710702Y42480D01*
X710577Y42440D01*
X710467Y42380D01*
X710367Y42300D01*
X710287Y42200D01*
X710227Y42090D01*
X710187Y41965D01*
X710177Y41840D01*
Y39410D01*
X710147Y39380D01*
X710047Y39240D01*
X710027Y39200D01*
X710012Y39165D01*
X709992Y39125D01*
X709977Y39085D01*
X709967Y39045D01*
X709952Y39000D01*
X709947Y38960D01*
X709937Y38920D01*
X709932Y38875D01*
Y38835D01*
X709927Y38790D01*
X709932Y38745D01*
Y38705D01*
X709937Y38660D01*
X709947Y38620D01*
X709952Y38580D01*
X709967Y38535D01*
X709977Y38495D01*
X709992Y38455D01*
X710012Y38415D01*
X710027Y38380D01*
X710047Y38340D01*
X710147Y38200D01*
X710177Y38170D01*
Y36040D01*
X710187Y35915D01*
X710227Y35790D01*
X710287Y35680D01*
X710367Y35580D01*
X710467Y35500D01*
X710577Y35440D01*
X710702Y35400D01*
X710827Y35390D01*
G37*
G36*
G01X706102D02*
X706227Y35400D01*
X706352Y35440D01*
X706462Y35500D01*
X706562Y35580D01*
X706642Y35680D01*
X706702Y35790D01*
X706742Y35915D01*
X706752Y36040D01*
Y38165D01*
X706782Y38195D01*
X706807Y38230D01*
X706837Y38265D01*
X706857Y38300D01*
X706882Y38335D01*
X706922Y38415D01*
X706967Y38535D01*
X706977Y38575D01*
X706987Y38620D01*
X706992Y38660D01*
X707002Y38705D01*
Y38875D01*
X706992Y38920D01*
X706987Y38960D01*
X706977Y39005D01*
X706967Y39045D01*
X706922Y39165D01*
X706882Y39245D01*
X706857Y39280D01*
X706837Y39315D01*
X706807Y39350D01*
X706782Y39385D01*
X706752Y39415D01*
Y41840D01*
X706742Y41965D01*
X706702Y42090D01*
X706642Y42200D01*
X706562Y42300D01*
X706462Y42380D01*
X706352Y42440D01*
X706227Y42480D01*
X706102Y42490D01*
X705977Y42480D01*
X705852Y42440D01*
X705742Y42380D01*
X705642Y42300D01*
X705562Y42200D01*
X705502Y42090D01*
X705462Y41965D01*
X705452Y41840D01*
Y39410D01*
X705422Y39380D01*
X705322Y39240D01*
X705302Y39200D01*
X705287Y39165D01*
X705267Y39125D01*
X705252Y39085D01*
X705242Y39045D01*
X705227Y39000D01*
X705222Y38960D01*
X705212Y38920D01*
X705207Y38875D01*
Y38835D01*
X705202Y38790D01*
X705207Y38745D01*
Y38705D01*
X705212Y38660D01*
X705222Y38620D01*
X705227Y38580D01*
X705242Y38535D01*
X705252Y38495D01*
X705267Y38455D01*
X705287Y38415D01*
X705302Y38380D01*
X705322Y38340D01*
X705422Y38200D01*
X705452Y38170D01*
Y36040D01*
X705462Y35915D01*
X705502Y35790D01*
X705562Y35680D01*
X705642Y35580D01*
X705742Y35500D01*
X705852Y35440D01*
X705977Y35400D01*
X706102Y35390D01*
G37*
G36*
G01X701378D02*
X701503Y35400D01*
X701628Y35440D01*
X701738Y35500D01*
X701838Y35580D01*
X701918Y35680D01*
X701978Y35790D01*
X702018Y35915D01*
X702028Y36040D01*
Y38165D01*
X702058Y38195D01*
X702083Y38230D01*
X702113Y38265D01*
X702133Y38300D01*
X702158Y38335D01*
X702198Y38415D01*
X702243Y38535D01*
X702253Y38575D01*
X702263Y38620D01*
X702268Y38660D01*
X702278Y38705D01*
Y38875D01*
X702268Y38920D01*
X702263Y38960D01*
X702253Y39005D01*
X702243Y39045D01*
X702198Y39165D01*
X702158Y39245D01*
X702133Y39280D01*
X702113Y39315D01*
X702083Y39350D01*
X702058Y39385D01*
X702028Y39415D01*
Y41840D01*
X702018Y41965D01*
X701978Y42090D01*
X701918Y42200D01*
X701838Y42300D01*
X701738Y42380D01*
X701628Y42440D01*
X701503Y42480D01*
X701378Y42490D01*
X701253Y42480D01*
X701128Y42440D01*
X701018Y42380D01*
X700918Y42300D01*
X700838Y42200D01*
X700778Y42090D01*
X700738Y41965D01*
X700728Y41840D01*
Y39410D01*
X700698Y39380D01*
X700598Y39240D01*
X700578Y39200D01*
X700563Y39165D01*
X700543Y39125D01*
X700528Y39085D01*
X700518Y39045D01*
X700503Y39000D01*
X700498Y38960D01*
X700488Y38920D01*
X700483Y38875D01*
Y38835D01*
X700478Y38790D01*
X700483Y38745D01*
Y38705D01*
X700488Y38660D01*
X700498Y38620D01*
X700503Y38580D01*
X700518Y38535D01*
X700528Y38495D01*
X700543Y38455D01*
X700563Y38415D01*
X700578Y38380D01*
X700598Y38340D01*
X700698Y38200D01*
X700728Y38170D01*
Y36040D01*
X700738Y35915D01*
X700778Y35790D01*
X700838Y35680D01*
X700918Y35580D01*
X701018Y35500D01*
X701128Y35440D01*
X701253Y35400D01*
X701378Y35390D01*
G37*
G36*
G01X696653D02*
X696778Y35400D01*
X696903Y35440D01*
X697013Y35500D01*
X697113Y35580D01*
X697193Y35680D01*
X697253Y35790D01*
X697293Y35915D01*
X697303Y36040D01*
Y38165D01*
X697333Y38195D01*
X697358Y38230D01*
X697388Y38265D01*
X697408Y38300D01*
X697433Y38335D01*
X697473Y38415D01*
X697518Y38535D01*
X697528Y38575D01*
X697538Y38620D01*
X697543Y38660D01*
X697553Y38705D01*
Y38875D01*
X697543Y38920D01*
X697538Y38960D01*
X697528Y39005D01*
X697518Y39045D01*
X697473Y39165D01*
X697433Y39245D01*
X697408Y39280D01*
X697388Y39315D01*
X697358Y39350D01*
X697333Y39385D01*
X697303Y39415D01*
Y41840D01*
X697293Y41965D01*
X697253Y42090D01*
X697193Y42200D01*
X697113Y42300D01*
X697013Y42380D01*
X696903Y42440D01*
X696778Y42480D01*
X696653Y42490D01*
X696528Y42480D01*
X696403Y42440D01*
X696293Y42380D01*
X696193Y42300D01*
X696113Y42200D01*
X696053Y42090D01*
X696013Y41965D01*
X696003Y41840D01*
Y39410D01*
X695973Y39380D01*
X695873Y39240D01*
X695853Y39200D01*
X695838Y39165D01*
X695818Y39125D01*
X695803Y39085D01*
X695793Y39045D01*
X695778Y39000D01*
X695773Y38960D01*
X695763Y38920D01*
X695758Y38875D01*
Y38835D01*
X695753Y38790D01*
X695758Y38745D01*
Y38705D01*
X695763Y38660D01*
X695773Y38620D01*
X695778Y38580D01*
X695793Y38535D01*
X695803Y38495D01*
X695818Y38455D01*
X695838Y38415D01*
X695853Y38380D01*
X695873Y38340D01*
X695973Y38200D01*
X696003Y38170D01*
Y36040D01*
X696013Y35915D01*
X696053Y35790D01*
X696113Y35680D01*
X696193Y35580D01*
X696293Y35500D01*
X696403Y35440D01*
X696528Y35400D01*
X696653Y35390D01*
G37*
G36*
G01X725000D02*
X725125Y35400D01*
X725250Y35440D01*
X725360Y35500D01*
X725460Y35580D01*
X725540Y35680D01*
X725600Y35790D01*
X725640Y35915D01*
X725650Y36040D01*
Y38165D01*
X725680Y38195D01*
X725705Y38230D01*
X725735Y38265D01*
X725755Y38300D01*
X725780Y38335D01*
X725820Y38415D01*
X725865Y38535D01*
X725875Y38575D01*
X725885Y38620D01*
X725890Y38660D01*
X725900Y38705D01*
Y38875D01*
X725890Y38920D01*
X725885Y38960D01*
X725875Y39005D01*
X725865Y39045D01*
X725820Y39165D01*
X725780Y39245D01*
X725755Y39280D01*
X725735Y39315D01*
X725705Y39350D01*
X725680Y39385D01*
X725650Y39415D01*
Y41840D01*
X725640Y41965D01*
X725600Y42090D01*
X725540Y42200D01*
X725460Y42300D01*
X725360Y42380D01*
X725250Y42440D01*
X725125Y42480D01*
X725000Y42490D01*
X724875Y42480D01*
X724750Y42440D01*
X724640Y42380D01*
X724540Y42300D01*
X724460Y42200D01*
X724400Y42090D01*
X724360Y41965D01*
X724350Y41840D01*
Y39410D01*
X724320Y39380D01*
X724220Y39240D01*
X724200Y39200D01*
X724185Y39165D01*
X724165Y39125D01*
X724150Y39085D01*
X724140Y39045D01*
X724125Y39000D01*
X724120Y38960D01*
X724110Y38920D01*
X724105Y38875D01*
Y38835D01*
X724100Y38790D01*
X724105Y38745D01*
Y38705D01*
X724110Y38660D01*
X724120Y38620D01*
X724125Y38580D01*
X724140Y38535D01*
X724150Y38495D01*
X724165Y38455D01*
X724185Y38415D01*
X724200Y38380D01*
X724220Y38340D01*
X724320Y38200D01*
X724350Y38170D01*
Y36040D01*
X724360Y35915D01*
X724400Y35790D01*
X724460Y35680D01*
X724540Y35580D01*
X724640Y35500D01*
X724750Y35440D01*
X724875Y35400D01*
X725000Y35390D01*
G37*
G36*
G01X720275D02*
X720400Y35400D01*
X720525Y35440D01*
X720635Y35500D01*
X720735Y35580D01*
X720815Y35680D01*
X720875Y35790D01*
X720915Y35915D01*
X720925Y36040D01*
Y38165D01*
X720955Y38195D01*
X720980Y38230D01*
X721010Y38265D01*
X721030Y38300D01*
X721055Y38335D01*
X721095Y38415D01*
X721140Y38535D01*
X721150Y38575D01*
X721160Y38620D01*
X721165Y38660D01*
X721175Y38705D01*
Y38875D01*
X721165Y38920D01*
X721160Y38960D01*
X721150Y39005D01*
X721140Y39045D01*
X721095Y39165D01*
X721055Y39245D01*
X721030Y39280D01*
X721010Y39315D01*
X720980Y39350D01*
X720955Y39385D01*
X720925Y39415D01*
Y41840D01*
X720915Y41965D01*
X720875Y42090D01*
X720815Y42200D01*
X720735Y42300D01*
X720635Y42380D01*
X720525Y42440D01*
X720400Y42480D01*
X720275Y42490D01*
X720150Y42480D01*
X720025Y42440D01*
X719915Y42380D01*
X719815Y42300D01*
X719735Y42200D01*
X719675Y42090D01*
X719635Y41965D01*
X719625Y41840D01*
Y39410D01*
X719595Y39380D01*
X719495Y39240D01*
X719475Y39200D01*
X719460Y39165D01*
X719440Y39125D01*
X719425Y39085D01*
X719415Y39045D01*
X719400Y39000D01*
X719395Y38960D01*
X719385Y38920D01*
X719380Y38875D01*
Y38835D01*
X719375Y38790D01*
X719380Y38745D01*
Y38705D01*
X719385Y38660D01*
X719395Y38620D01*
X719400Y38580D01*
X719415Y38535D01*
X719425Y38495D01*
X719440Y38455D01*
X719460Y38415D01*
X719475Y38380D01*
X719495Y38340D01*
X719595Y38200D01*
X719625Y38170D01*
Y36040D01*
X719635Y35915D01*
X719675Y35790D01*
X719735Y35680D01*
X719815Y35580D01*
X719915Y35500D01*
X720025Y35440D01*
X720150Y35400D01*
X720275Y35390D01*
G37*
G36*
G01X715551D02*
X715676Y35400D01*
X715801Y35440D01*
X715911Y35500D01*
X716011Y35580D01*
X716091Y35680D01*
X716151Y35790D01*
X716191Y35915D01*
X716201Y36040D01*
Y38165D01*
X716231Y38195D01*
X716256Y38230D01*
X716286Y38265D01*
X716306Y38300D01*
X716331Y38335D01*
X716371Y38415D01*
X716416Y38535D01*
X716426Y38575D01*
X716436Y38620D01*
X716441Y38660D01*
X716451Y38705D01*
Y38875D01*
X716441Y38920D01*
X716436Y38960D01*
X716426Y39005D01*
X716416Y39045D01*
X716371Y39165D01*
X716331Y39245D01*
X716306Y39280D01*
X716286Y39315D01*
X716256Y39350D01*
X716231Y39385D01*
X716201Y39415D01*
Y41840D01*
X716191Y41965D01*
X716151Y42090D01*
X716091Y42200D01*
X716011Y42300D01*
X715911Y42380D01*
X715801Y42440D01*
X715676Y42480D01*
X715551Y42490D01*
X715426Y42480D01*
X715301Y42440D01*
X715191Y42380D01*
X715091Y42300D01*
X715011Y42200D01*
X714951Y42090D01*
X714911Y41965D01*
X714901Y41840D01*
Y39410D01*
X714871Y39380D01*
X714771Y39240D01*
X714751Y39200D01*
X714736Y39165D01*
X714716Y39125D01*
X714701Y39085D01*
X714691Y39045D01*
X714676Y39000D01*
X714671Y38960D01*
X714661Y38920D01*
X714656Y38875D01*
Y38835D01*
X714651Y38790D01*
X714656Y38745D01*
Y38705D01*
X714661Y38660D01*
X714671Y38620D01*
X714676Y38580D01*
X714691Y38535D01*
X714701Y38495D01*
X714716Y38455D01*
X714736Y38415D01*
X714751Y38380D01*
X714771Y38340D01*
X714871Y38200D01*
X714901Y38170D01*
Y36040D01*
X714911Y35915D01*
X714951Y35790D01*
X715011Y35680D01*
X715091Y35580D01*
X715191Y35500D01*
X715301Y35440D01*
X715426Y35400D01*
X715551Y35390D01*
G37*
G36*
G01X739173D02*
X739298Y35400D01*
X739423Y35440D01*
X739533Y35500D01*
X739633Y35580D01*
X739713Y35680D01*
X739773Y35790D01*
X739813Y35915D01*
X739823Y36040D01*
Y38165D01*
X739853Y38195D01*
X739878Y38230D01*
X739908Y38265D01*
X739928Y38300D01*
X739953Y38335D01*
X739993Y38415D01*
X740038Y38535D01*
X740048Y38575D01*
X740058Y38620D01*
X740063Y38660D01*
X740073Y38705D01*
Y38875D01*
X740063Y38920D01*
X740058Y38960D01*
X740048Y39005D01*
X740038Y39045D01*
X739993Y39165D01*
X739953Y39245D01*
X739928Y39280D01*
X739908Y39315D01*
X739878Y39350D01*
X739853Y39385D01*
X739823Y39415D01*
Y41840D01*
X739813Y41965D01*
X739773Y42090D01*
X739713Y42200D01*
X739633Y42300D01*
X739533Y42380D01*
X739423Y42440D01*
X739298Y42480D01*
X739173Y42490D01*
X739048Y42480D01*
X738923Y42440D01*
X738813Y42380D01*
X738713Y42300D01*
X738633Y42200D01*
X738573Y42090D01*
X738533Y41965D01*
X738523Y41840D01*
Y39410D01*
X738493Y39380D01*
X738393Y39240D01*
X738373Y39200D01*
X738358Y39165D01*
X738338Y39125D01*
X738323Y39085D01*
X738313Y39045D01*
X738298Y39000D01*
X738293Y38960D01*
X738283Y38920D01*
X738278Y38875D01*
Y38835D01*
X738273Y38790D01*
X738278Y38745D01*
Y38705D01*
X738283Y38660D01*
X738293Y38620D01*
X738298Y38580D01*
X738313Y38535D01*
X738323Y38495D01*
X738338Y38455D01*
X738358Y38415D01*
X738373Y38380D01*
X738393Y38340D01*
X738493Y38200D01*
X738523Y38170D01*
Y36040D01*
X738533Y35915D01*
X738573Y35790D01*
X738633Y35680D01*
X738713Y35580D01*
X738813Y35500D01*
X738923Y35440D01*
X739048Y35400D01*
X739173Y35390D01*
G37*
G36*
G01X734449D02*
X734574Y35400D01*
X734699Y35440D01*
X734809Y35500D01*
X734909Y35580D01*
X734989Y35680D01*
X735049Y35790D01*
X735089Y35915D01*
X735099Y36040D01*
Y38165D01*
X735129Y38195D01*
X735154Y38230D01*
X735184Y38265D01*
X735204Y38300D01*
X735229Y38335D01*
X735269Y38415D01*
X735314Y38535D01*
X735324Y38575D01*
X735334Y38620D01*
X735339Y38660D01*
X735349Y38705D01*
Y38875D01*
X735339Y38920D01*
X735334Y38960D01*
X735324Y39005D01*
X735314Y39045D01*
X735269Y39165D01*
X735229Y39245D01*
X735204Y39280D01*
X735184Y39315D01*
X735154Y39350D01*
X735129Y39385D01*
X735099Y39415D01*
Y41840D01*
X735089Y41965D01*
X735049Y42090D01*
X734989Y42200D01*
X734909Y42300D01*
X734809Y42380D01*
X734699Y42440D01*
X734574Y42480D01*
X734449Y42490D01*
X734324Y42480D01*
X734199Y42440D01*
X734089Y42380D01*
X733989Y42300D01*
X733909Y42200D01*
X733849Y42090D01*
X733809Y41965D01*
X733799Y41840D01*
Y39410D01*
X733769Y39380D01*
X733669Y39240D01*
X733649Y39200D01*
X733634Y39165D01*
X733614Y39125D01*
X733599Y39085D01*
X733589Y39045D01*
X733574Y39000D01*
X733569Y38960D01*
X733559Y38920D01*
X733554Y38875D01*
Y38835D01*
X733549Y38790D01*
X733554Y38745D01*
Y38705D01*
X733559Y38660D01*
X733569Y38620D01*
X733574Y38580D01*
X733589Y38535D01*
X733599Y38495D01*
X733614Y38455D01*
X733634Y38415D01*
X733649Y38380D01*
X733669Y38340D01*
X733769Y38200D01*
X733799Y38170D01*
Y36040D01*
X733809Y35915D01*
X733849Y35790D01*
X733909Y35680D01*
X733989Y35580D01*
X734089Y35500D01*
X734199Y35440D01*
X734324Y35400D01*
X734449Y35390D01*
G37*
G36*
G01X729724D02*
X729849Y35400D01*
X729974Y35440D01*
X730084Y35500D01*
X730184Y35580D01*
X730264Y35680D01*
X730324Y35790D01*
X730364Y35915D01*
X730374Y36040D01*
Y38165D01*
X730404Y38195D01*
X730429Y38230D01*
X730459Y38265D01*
X730479Y38300D01*
X730504Y38335D01*
X730544Y38415D01*
X730589Y38535D01*
X730599Y38575D01*
X730609Y38620D01*
X730614Y38660D01*
X730624Y38705D01*
Y38875D01*
X730614Y38920D01*
X730609Y38960D01*
X730599Y39005D01*
X730589Y39045D01*
X730544Y39165D01*
X730504Y39245D01*
X730479Y39280D01*
X730459Y39315D01*
X730429Y39350D01*
X730404Y39385D01*
X730374Y39415D01*
Y41840D01*
X730364Y41965D01*
X730324Y42090D01*
X730264Y42200D01*
X730184Y42300D01*
X730084Y42380D01*
X729974Y42440D01*
X729849Y42480D01*
X729724Y42490D01*
X729599Y42480D01*
X729474Y42440D01*
X729364Y42380D01*
X729264Y42300D01*
X729184Y42200D01*
X729124Y42090D01*
X729084Y41965D01*
X729074Y41840D01*
Y39410D01*
X729044Y39380D01*
X728944Y39240D01*
X728924Y39200D01*
X728909Y39165D01*
X728889Y39125D01*
X728874Y39085D01*
X728864Y39045D01*
X728849Y39000D01*
X728844Y38960D01*
X728834Y38920D01*
X728829Y38875D01*
Y38835D01*
X728824Y38790D01*
X728829Y38745D01*
Y38705D01*
X728834Y38660D01*
X728844Y38620D01*
X728849Y38580D01*
X728864Y38535D01*
X728874Y38495D01*
X728889Y38455D01*
X728909Y38415D01*
X728924Y38380D01*
X728944Y38340D01*
X729044Y38200D01*
X729074Y38170D01*
Y36040D01*
X729084Y35915D01*
X729124Y35790D01*
X729184Y35680D01*
X729264Y35580D01*
X729364Y35500D01*
X729474Y35440D01*
X729599Y35400D01*
X729724Y35390D01*
G37*
G36*
G01X753346D02*
X753471Y35400D01*
X753596Y35440D01*
X753706Y35500D01*
X753806Y35580D01*
X753886Y35680D01*
X753946Y35790D01*
X753986Y35915D01*
X753996Y36040D01*
Y38165D01*
X754026Y38195D01*
X754051Y38230D01*
X754081Y38265D01*
X754101Y38300D01*
X754126Y38335D01*
X754166Y38415D01*
X754211Y38535D01*
X754221Y38575D01*
X754231Y38620D01*
X754236Y38660D01*
X754246Y38705D01*
Y38875D01*
X754236Y38920D01*
X754231Y38960D01*
X754221Y39005D01*
X754211Y39045D01*
X754166Y39165D01*
X754126Y39245D01*
X754101Y39280D01*
X754081Y39315D01*
X754051Y39350D01*
X754026Y39385D01*
X753996Y39415D01*
Y41840D01*
X753986Y41965D01*
X753946Y42090D01*
X753886Y42200D01*
X753806Y42300D01*
X753706Y42380D01*
X753596Y42440D01*
X753471Y42480D01*
X753346Y42490D01*
X753221Y42480D01*
X753096Y42440D01*
X752986Y42380D01*
X752886Y42300D01*
X752806Y42200D01*
X752746Y42090D01*
X752706Y41965D01*
X752696Y41840D01*
Y39410D01*
X752666Y39380D01*
X752566Y39240D01*
X752546Y39200D01*
X752531Y39165D01*
X752511Y39125D01*
X752496Y39085D01*
X752486Y39045D01*
X752471Y39000D01*
X752466Y38960D01*
X752456Y38920D01*
X752451Y38875D01*
Y38835D01*
X752446Y38790D01*
X752451Y38745D01*
Y38705D01*
X752456Y38660D01*
X752466Y38620D01*
X752471Y38580D01*
X752486Y38535D01*
X752496Y38495D01*
X752511Y38455D01*
X752531Y38415D01*
X752546Y38380D01*
X752566Y38340D01*
X752666Y38200D01*
X752696Y38170D01*
Y36040D01*
X752706Y35915D01*
X752746Y35790D01*
X752806Y35680D01*
X752886Y35580D01*
X752986Y35500D01*
X753096Y35440D01*
X753221Y35400D01*
X753346Y35390D01*
G37*
G36*
G01X748622D02*
X748747Y35400D01*
X748872Y35440D01*
X748982Y35500D01*
X749082Y35580D01*
X749162Y35680D01*
X749222Y35790D01*
X749262Y35915D01*
X749272Y36040D01*
Y38165D01*
X749302Y38195D01*
X749327Y38230D01*
X749357Y38265D01*
X749377Y38300D01*
X749402Y38335D01*
X749442Y38415D01*
X749487Y38535D01*
X749497Y38575D01*
X749507Y38620D01*
X749512Y38660D01*
X749522Y38705D01*
Y38875D01*
X749512Y38920D01*
X749507Y38960D01*
X749497Y39005D01*
X749487Y39045D01*
X749442Y39165D01*
X749402Y39245D01*
X749377Y39280D01*
X749357Y39315D01*
X749327Y39350D01*
X749302Y39385D01*
X749272Y39415D01*
Y41840D01*
X749262Y41965D01*
X749222Y42090D01*
X749162Y42200D01*
X749082Y42300D01*
X748982Y42380D01*
X748872Y42440D01*
X748747Y42480D01*
X748622Y42490D01*
X748497Y42480D01*
X748372Y42440D01*
X748262Y42380D01*
X748162Y42300D01*
X748082Y42200D01*
X748022Y42090D01*
X747982Y41965D01*
X747972Y41840D01*
Y39410D01*
X747942Y39380D01*
X747842Y39240D01*
X747822Y39200D01*
X747807Y39165D01*
X747787Y39125D01*
X747772Y39085D01*
X747762Y39045D01*
X747747Y39000D01*
X747742Y38960D01*
X747732Y38920D01*
X747727Y38875D01*
Y38835D01*
X747722Y38790D01*
X747727Y38745D01*
Y38705D01*
X747732Y38660D01*
X747742Y38620D01*
X747747Y38580D01*
X747762Y38535D01*
X747772Y38495D01*
X747787Y38455D01*
X747807Y38415D01*
X747822Y38380D01*
X747842Y38340D01*
X747942Y38200D01*
X747972Y38170D01*
Y36040D01*
X747982Y35915D01*
X748022Y35790D01*
X748082Y35680D01*
X748162Y35580D01*
X748262Y35500D01*
X748372Y35440D01*
X748497Y35400D01*
X748622Y35390D01*
G37*
G36*
G01X743897D02*
X744022Y35400D01*
X744147Y35440D01*
X744257Y35500D01*
X744357Y35580D01*
X744437Y35680D01*
X744497Y35790D01*
X744537Y35915D01*
X744547Y36040D01*
Y38165D01*
X744577Y38195D01*
X744602Y38230D01*
X744632Y38265D01*
X744652Y38300D01*
X744677Y38335D01*
X744717Y38415D01*
X744762Y38535D01*
X744772Y38575D01*
X744782Y38620D01*
X744787Y38660D01*
X744797Y38705D01*
Y38875D01*
X744787Y38920D01*
X744782Y38960D01*
X744772Y39005D01*
X744762Y39045D01*
X744717Y39165D01*
X744677Y39245D01*
X744652Y39280D01*
X744632Y39315D01*
X744602Y39350D01*
X744577Y39385D01*
X744547Y39415D01*
Y41840D01*
X744537Y41965D01*
X744497Y42090D01*
X744437Y42200D01*
X744357Y42300D01*
X744257Y42380D01*
X744147Y42440D01*
X744022Y42480D01*
X743897Y42490D01*
X743772Y42480D01*
X743647Y42440D01*
X743537Y42380D01*
X743437Y42300D01*
X743357Y42200D01*
X743297Y42090D01*
X743257Y41965D01*
X743247Y41840D01*
Y39410D01*
X743217Y39380D01*
X743117Y39240D01*
X743097Y39200D01*
X743082Y39165D01*
X743062Y39125D01*
X743047Y39085D01*
X743037Y39045D01*
X743022Y39000D01*
X743017Y38960D01*
X743007Y38920D01*
X743002Y38875D01*
Y38835D01*
X742997Y38790D01*
X743002Y38745D01*
Y38705D01*
X743007Y38660D01*
X743017Y38620D01*
X743022Y38580D01*
X743037Y38535D01*
X743047Y38495D01*
X743062Y38455D01*
X743082Y38415D01*
X743097Y38380D01*
X743117Y38340D01*
X743217Y38200D01*
X743247Y38170D01*
Y36040D01*
X743257Y35915D01*
X743297Y35790D01*
X743357Y35680D01*
X743437Y35580D01*
X743537Y35500D01*
X743647Y35440D01*
X743772Y35400D01*
X743897Y35390D01*
G37*
G54D44*
X169485Y198021D03*
Y196446D03*
Y194871D03*
Y193296D03*
Y191722D03*
Y190147D03*
Y188572D03*
Y186997D03*
Y185422D03*
Y199596D03*
X191607Y185422D03*
Y186997D03*
Y188572D03*
Y190147D03*
Y191722D03*
Y193296D03*
Y194871D03*
Y196446D03*
Y198021D03*
Y199596D03*
G54D18*
X31800Y96000D03*
X35200D03*
X60800Y91000D03*
X64200D03*
X60800Y218000D03*
X64200D03*
X72800Y88000D03*
X76200D03*
X72800Y84500D03*
X76200D03*
X72300Y97500D03*
X75700D03*
X72300Y94500D03*
X75700D03*
X105800Y255000D03*
X109200D03*
X128800Y175000D03*
X132200D03*
X139300Y201000D03*
X153300Y57500D03*
X156700D03*
X146800Y89500D03*
X150200D03*
X146800Y92500D03*
X150200D03*
X143800Y109000D03*
X147200D03*
X150800Y162000D03*
X154200D03*
X150800Y171500D03*
X154200D03*
X151800Y192000D03*
X155200D03*
X142700Y201000D03*
X167300Y61300D03*
X170700D03*
X161400Y113200D03*
X164800D03*
X162300Y257000D03*
X165700D03*
X182800Y57500D03*
X186200D03*
X178300Y213000D03*
X181700D03*
X195300Y230500D03*
X198700D03*
X211800Y206500D03*
X215200D03*
X226800Y60000D03*
X230200D03*
X279800Y135500D03*
X271500Y141400D03*
X274900D03*
X278700Y244400D03*
X283000Y132500D03*
X286400D03*
X283200Y135500D03*
X289800Y141500D03*
X293200D03*
X290300Y157500D03*
X293700D03*
X283700Y168000D03*
X287100D03*
X293300Y199500D03*
X286300D03*
X289700D03*
X282100Y244400D03*
X297300Y157500D03*
X300700D03*
X296700Y199500D03*
X295800Y228000D03*
X299200D03*
X295800Y231000D03*
X299200D03*
X313300Y103500D03*
X316700D03*
X313300Y148000D03*
X316700D03*
X337300Y81500D03*
X340700D03*
X349400Y159400D03*
X352800D03*
X369900Y128100D03*
X361396Y199563D03*
X364796D03*
X373300Y128100D03*
X387800Y207500D03*
X393170Y197103D03*
X396570D03*
X391200Y207500D03*
X406800Y55500D03*
X410200D03*
X404300Y208000D03*
X407700D03*
X409200Y262800D03*
X412600D03*
X440300Y36000D03*
X443700D03*
X522800Y93000D03*
X526200D03*
X520800Y110500D03*
X524200D03*
X520800Y107500D03*
X524200D03*
X545800Y119500D03*
X549200D03*
X551300Y187500D03*
X554700D03*
X566800Y179000D03*
X570200D03*
X566800Y176000D03*
X570200D03*
X560300Y187000D03*
X563700D03*
X566900Y190000D03*
X570300D03*
X573300Y92500D03*
X576700D03*
X718682Y119685D03*
X722082D03*
X741500Y46507D03*
X734800D03*
X738200D03*
X732800Y102500D03*
X736200D03*
X744900Y46507D03*
X775800Y133000D03*
X779200D03*
X775800Y129500D03*
X779200D03*
X775800Y126000D03*
X779200D03*
X775800Y122500D03*
X779200D03*
X777800Y162000D03*
X781200D03*
X777800Y165000D03*
X781200D03*
X777800Y168000D03*
X781200D03*
X777800Y171000D03*
X781200D03*
G54D54*
X271795Y79984D03*
Y78016D03*
X282205D03*
Y79984D03*
G54D63*
X318764Y62400D03*
X321323D03*
X323882D03*
Y80886D03*
X321323D03*
X318764D03*
X326441Y62400D03*
X329000D03*
Y80886D03*
X326441D03*
G54D36*
X81500Y237500D03*
X127000Y212500D03*
X154000Y121500D03*
X150500Y180000D03*
X160000Y168000D03*
X161000Y206000D03*
X212500Y172500D03*
X259000Y55000D03*
X262000D03*
X353000Y149500D03*
X356000Y161600D03*
Y183000D03*
X352500Y177000D03*
X359000Y148800D03*
X370742Y142924D03*
X361300Y165200D03*
X364300Y162850D03*
X359000Y171000D03*
Y183000D03*
X371500Y190600D03*
X376390Y190650D03*
X385500Y203700D03*
X401866Y165000D03*
X389500Y153463D03*
X396142Y168024D03*
X400500Y204063D03*
X395000Y270500D03*
X406500Y71500D03*
X411500Y133000D03*
X403500Y204063D03*
X406500D03*
X409500D03*
X424500Y163000D03*
X420000Y209000D03*
X423000Y209063D03*
X517000Y59507D03*
X626500Y50507D03*
X633300D03*
X636600D03*
X661500Y51107D03*
X658500D03*
X664500D03*
X735000Y69500D03*
X739300Y112000D03*
G54D90*
X782046Y280709D03*
G54D72*
X404750Y254500D03*
G54D45*
X171885Y181048D03*
Y203970D03*
X189207Y181048D03*
Y203970D03*
G36*
G01X510039Y35390D02*
X510164Y35400D01*
X510289Y35440D01*
X510399Y35500D01*
X510499Y35580D01*
X510579Y35680D01*
X510639Y35790D01*
X510679Y35915D01*
X510689Y36040D01*
Y37170D01*
X510719Y37200D01*
X510819Y37340D01*
X510839Y37380D01*
X510854Y37415D01*
X510874Y37455D01*
X510889Y37495D01*
X510899Y37535D01*
X510914Y37580D01*
X510919Y37620D01*
X510929Y37660D01*
X510934Y37705D01*
Y37745D01*
X510939Y37790D01*
X510934Y37835D01*
Y37875D01*
X510929Y37920D01*
X510919Y37960D01*
X510914Y38000D01*
X510899Y38045D01*
X510889Y38085D01*
X510874Y38125D01*
X510854Y38165D01*
X510839Y38200D01*
X510819Y38240D01*
X510719Y38380D01*
X510689Y38410D01*
Y41840D01*
X510679Y41965D01*
X510639Y42090D01*
X510579Y42200D01*
X510499Y42300D01*
X510399Y42380D01*
X510289Y42440D01*
X510164Y42480D01*
X510039Y42490D01*
X509914Y42480D01*
X509789Y42440D01*
X509679Y42380D01*
X509579Y42300D01*
X509499Y42200D01*
X509439Y42090D01*
X509399Y41965D01*
X509389Y41840D01*
Y38410D01*
X509359Y38380D01*
X509259Y38240D01*
X509239Y38200D01*
X509224Y38165D01*
X509204Y38125D01*
X509189Y38085D01*
X509179Y38045D01*
X509164Y38000D01*
X509159Y37960D01*
X509149Y37920D01*
X509144Y37875D01*
Y37835D01*
X509139Y37790D01*
X509144Y37745D01*
Y37705D01*
X509149Y37660D01*
X509159Y37620D01*
X509164Y37580D01*
X509179Y37535D01*
X509189Y37495D01*
X509204Y37455D01*
X509224Y37415D01*
X509239Y37380D01*
X509259Y37340D01*
X509359Y37200D01*
X509389Y37170D01*
Y36040D01*
X509399Y35915D01*
X509439Y35790D01*
X509499Y35680D01*
X509579Y35580D01*
X509679Y35500D01*
X509789Y35440D01*
X509914Y35400D01*
X510039Y35390D01*
G37*
G36*
G01X505315D02*
X505440Y35400D01*
X505565Y35440D01*
X505675Y35500D01*
X505775Y35580D01*
X505855Y35680D01*
X505915Y35790D01*
X505955Y35915D01*
X505965Y36040D01*
Y37170D01*
X505995Y37200D01*
X506095Y37340D01*
X506115Y37380D01*
X506130Y37415D01*
X506150Y37455D01*
X506165Y37495D01*
X506175Y37535D01*
X506190Y37580D01*
X506195Y37620D01*
X506205Y37660D01*
X506210Y37705D01*
Y37745D01*
X506215Y37790D01*
X506210Y37835D01*
Y37875D01*
X506205Y37920D01*
X506195Y37960D01*
X506190Y38000D01*
X506175Y38045D01*
X506165Y38085D01*
X506150Y38125D01*
X506130Y38165D01*
X506115Y38200D01*
X506095Y38240D01*
X505995Y38380D01*
X505965Y38410D01*
Y41840D01*
X505955Y41965D01*
X505915Y42090D01*
X505855Y42200D01*
X505775Y42300D01*
X505675Y42380D01*
X505565Y42440D01*
X505440Y42480D01*
X505315Y42490D01*
X505190Y42480D01*
X505065Y42440D01*
X504955Y42380D01*
X504855Y42300D01*
X504775Y42200D01*
X504715Y42090D01*
X504675Y41965D01*
X504665Y41840D01*
Y38410D01*
X504635Y38380D01*
X504535Y38240D01*
X504515Y38200D01*
X504500Y38165D01*
X504480Y38125D01*
X504465Y38085D01*
X504455Y38045D01*
X504440Y38000D01*
X504435Y37960D01*
X504425Y37920D01*
X504420Y37875D01*
Y37835D01*
X504415Y37790D01*
X504420Y37745D01*
Y37705D01*
X504425Y37660D01*
X504435Y37620D01*
X504440Y37580D01*
X504455Y37535D01*
X504465Y37495D01*
X504480Y37455D01*
X504500Y37415D01*
X504515Y37380D01*
X504535Y37340D01*
X504635Y37200D01*
X504665Y37170D01*
Y36040D01*
X504675Y35915D01*
X504715Y35790D01*
X504775Y35680D01*
X504855Y35580D01*
X504955Y35500D01*
X505065Y35440D01*
X505190Y35400D01*
X505315Y35390D01*
G37*
G36*
G01X524212D02*
X524337Y35400D01*
X524462Y35440D01*
X524572Y35500D01*
X524672Y35580D01*
X524752Y35680D01*
X524812Y35790D01*
X524852Y35915D01*
X524862Y36040D01*
Y37170D01*
X524892Y37200D01*
X524992Y37340D01*
X525012Y37380D01*
X525027Y37415D01*
X525047Y37455D01*
X525062Y37495D01*
X525072Y37535D01*
X525087Y37580D01*
X525092Y37620D01*
X525102Y37660D01*
X525107Y37705D01*
Y37745D01*
X525112Y37790D01*
X525107Y37835D01*
Y37875D01*
X525102Y37920D01*
X525092Y37960D01*
X525087Y38000D01*
X525072Y38045D01*
X525062Y38085D01*
X525047Y38125D01*
X525027Y38165D01*
X525012Y38200D01*
X524992Y38240D01*
X524892Y38380D01*
X524862Y38410D01*
Y41840D01*
X524852Y41965D01*
X524812Y42090D01*
X524752Y42200D01*
X524672Y42300D01*
X524572Y42380D01*
X524462Y42440D01*
X524337Y42480D01*
X524212Y42490D01*
X524087Y42480D01*
X523962Y42440D01*
X523852Y42380D01*
X523752Y42300D01*
X523672Y42200D01*
X523612Y42090D01*
X523572Y41965D01*
X523562Y41840D01*
Y38410D01*
X523532Y38380D01*
X523432Y38240D01*
X523412Y38200D01*
X523397Y38165D01*
X523377Y38125D01*
X523362Y38085D01*
X523352Y38045D01*
X523337Y38000D01*
X523332Y37960D01*
X523322Y37920D01*
X523317Y37875D01*
Y37835D01*
X523312Y37790D01*
X523317Y37745D01*
Y37705D01*
X523322Y37660D01*
X523332Y37620D01*
X523337Y37580D01*
X523352Y37535D01*
X523362Y37495D01*
X523377Y37455D01*
X523397Y37415D01*
X523412Y37380D01*
X523432Y37340D01*
X523532Y37200D01*
X523562Y37170D01*
Y36040D01*
X523572Y35915D01*
X523612Y35790D01*
X523672Y35680D01*
X523752Y35580D01*
X523852Y35500D01*
X523962Y35440D01*
X524087Y35400D01*
X524212Y35390D01*
G37*
G36*
G01X519488D02*
X519613Y35400D01*
X519738Y35440D01*
X519848Y35500D01*
X519948Y35580D01*
X520028Y35680D01*
X520088Y35790D01*
X520128Y35915D01*
X520138Y36040D01*
Y37170D01*
X520168Y37200D01*
X520268Y37340D01*
X520288Y37380D01*
X520303Y37415D01*
X520323Y37455D01*
X520338Y37495D01*
X520348Y37535D01*
X520363Y37580D01*
X520368Y37620D01*
X520378Y37660D01*
X520383Y37705D01*
Y37745D01*
X520388Y37790D01*
X520383Y37835D01*
Y37875D01*
X520378Y37920D01*
X520368Y37960D01*
X520363Y38000D01*
X520348Y38045D01*
X520338Y38085D01*
X520323Y38125D01*
X520303Y38165D01*
X520288Y38200D01*
X520268Y38240D01*
X520168Y38380D01*
X520138Y38410D01*
Y41840D01*
X520128Y41965D01*
X520088Y42090D01*
X520028Y42200D01*
X519948Y42300D01*
X519848Y42380D01*
X519738Y42440D01*
X519613Y42480D01*
X519488Y42490D01*
X519363Y42480D01*
X519238Y42440D01*
X519128Y42380D01*
X519028Y42300D01*
X518948Y42200D01*
X518888Y42090D01*
X518848Y41965D01*
X518838Y41840D01*
Y38410D01*
X518808Y38380D01*
X518708Y38240D01*
X518688Y38200D01*
X518673Y38165D01*
X518653Y38125D01*
X518638Y38085D01*
X518628Y38045D01*
X518613Y38000D01*
X518608Y37960D01*
X518598Y37920D01*
X518593Y37875D01*
Y37835D01*
X518588Y37790D01*
X518593Y37745D01*
Y37705D01*
X518598Y37660D01*
X518608Y37620D01*
X518613Y37580D01*
X518628Y37535D01*
X518638Y37495D01*
X518653Y37455D01*
X518673Y37415D01*
X518688Y37380D01*
X518708Y37340D01*
X518808Y37200D01*
X518838Y37170D01*
Y36040D01*
X518848Y35915D01*
X518888Y35790D01*
X518948Y35680D01*
X519028Y35580D01*
X519128Y35500D01*
X519238Y35440D01*
X519363Y35400D01*
X519488Y35390D01*
G37*
G36*
G01X514764D02*
X514889Y35400D01*
X515014Y35440D01*
X515124Y35500D01*
X515224Y35580D01*
X515304Y35680D01*
X515364Y35790D01*
X515404Y35915D01*
X515414Y36040D01*
Y37170D01*
X515444Y37200D01*
X515544Y37340D01*
X515564Y37380D01*
X515579Y37415D01*
X515599Y37455D01*
X515614Y37495D01*
X515624Y37535D01*
X515639Y37580D01*
X515644Y37620D01*
X515654Y37660D01*
X515659Y37705D01*
Y37745D01*
X515664Y37790D01*
X515659Y37835D01*
Y37875D01*
X515654Y37920D01*
X515644Y37960D01*
X515639Y38000D01*
X515624Y38045D01*
X515614Y38085D01*
X515599Y38125D01*
X515579Y38165D01*
X515564Y38200D01*
X515544Y38240D01*
X515444Y38380D01*
X515414Y38410D01*
Y41840D01*
X515404Y41965D01*
X515364Y42090D01*
X515304Y42200D01*
X515224Y42300D01*
X515124Y42380D01*
X515014Y42440D01*
X514889Y42480D01*
X514764Y42490D01*
X514639Y42480D01*
X514514Y42440D01*
X514404Y42380D01*
X514304Y42300D01*
X514224Y42200D01*
X514164Y42090D01*
X514124Y41965D01*
X514114Y41840D01*
Y38410D01*
X514084Y38380D01*
X513984Y38240D01*
X513964Y38200D01*
X513949Y38165D01*
X513929Y38125D01*
X513914Y38085D01*
X513904Y38045D01*
X513889Y38000D01*
X513884Y37960D01*
X513874Y37920D01*
X513869Y37875D01*
Y37835D01*
X513864Y37790D01*
X513869Y37745D01*
Y37705D01*
X513874Y37660D01*
X513884Y37620D01*
X513889Y37580D01*
X513904Y37535D01*
X513914Y37495D01*
X513929Y37455D01*
X513949Y37415D01*
X513964Y37380D01*
X513984Y37340D01*
X514084Y37200D01*
X514114Y37170D01*
Y36040D01*
X514124Y35915D01*
X514164Y35790D01*
X514224Y35680D01*
X514304Y35580D01*
X514404Y35500D01*
X514514Y35440D01*
X514639Y35400D01*
X514764Y35390D01*
G37*
G36*
G01X538386D02*
X538511Y35400D01*
X538636Y35440D01*
X538746Y35500D01*
X538846Y35580D01*
X538926Y35680D01*
X538986Y35790D01*
X539026Y35915D01*
X539036Y36040D01*
Y37170D01*
X539066Y37200D01*
X539166Y37340D01*
X539186Y37380D01*
X539201Y37415D01*
X539221Y37455D01*
X539236Y37495D01*
X539246Y37535D01*
X539261Y37580D01*
X539266Y37620D01*
X539276Y37660D01*
X539281Y37705D01*
Y37745D01*
X539286Y37790D01*
X539281Y37835D01*
Y37875D01*
X539276Y37920D01*
X539266Y37960D01*
X539261Y38000D01*
X539246Y38045D01*
X539236Y38085D01*
X539221Y38125D01*
X539201Y38165D01*
X539186Y38200D01*
X539166Y38240D01*
X539066Y38380D01*
X539036Y38410D01*
Y41840D01*
X539026Y41965D01*
X538986Y42090D01*
X538926Y42200D01*
X538846Y42300D01*
X538746Y42380D01*
X538636Y42440D01*
X538511Y42480D01*
X538386Y42490D01*
X538261Y42480D01*
X538136Y42440D01*
X538026Y42380D01*
X537926Y42300D01*
X537846Y42200D01*
X537786Y42090D01*
X537746Y41965D01*
X537736Y41840D01*
Y38410D01*
X537706Y38380D01*
X537606Y38240D01*
X537586Y38200D01*
X537571Y38165D01*
X537551Y38125D01*
X537536Y38085D01*
X537526Y38045D01*
X537511Y38000D01*
X537506Y37960D01*
X537496Y37920D01*
X537491Y37875D01*
Y37835D01*
X537486Y37790D01*
X537491Y37745D01*
Y37705D01*
X537496Y37660D01*
X537506Y37620D01*
X537511Y37580D01*
X537526Y37535D01*
X537536Y37495D01*
X537551Y37455D01*
X537571Y37415D01*
X537586Y37380D01*
X537606Y37340D01*
X537706Y37200D01*
X537736Y37170D01*
Y36040D01*
X537746Y35915D01*
X537786Y35790D01*
X537846Y35680D01*
X537926Y35580D01*
X538026Y35500D01*
X538136Y35440D01*
X538261Y35400D01*
X538386Y35390D01*
G37*
G36*
G01X533661D02*
X533786Y35400D01*
X533911Y35440D01*
X534021Y35500D01*
X534121Y35580D01*
X534201Y35680D01*
X534261Y35790D01*
X534301Y35915D01*
X534311Y36040D01*
Y37170D01*
X534341Y37200D01*
X534441Y37340D01*
X534461Y37380D01*
X534476Y37415D01*
X534496Y37455D01*
X534511Y37495D01*
X534521Y37535D01*
X534536Y37580D01*
X534541Y37620D01*
X534551Y37660D01*
X534556Y37705D01*
Y37745D01*
X534561Y37790D01*
X534556Y37835D01*
Y37875D01*
X534551Y37920D01*
X534541Y37960D01*
X534536Y38000D01*
X534521Y38045D01*
X534511Y38085D01*
X534496Y38125D01*
X534476Y38165D01*
X534461Y38200D01*
X534441Y38240D01*
X534341Y38380D01*
X534311Y38410D01*
Y41840D01*
X534301Y41965D01*
X534261Y42090D01*
X534201Y42200D01*
X534121Y42300D01*
X534021Y42380D01*
X533911Y42440D01*
X533786Y42480D01*
X533661Y42490D01*
X533536Y42480D01*
X533411Y42440D01*
X533301Y42380D01*
X533201Y42300D01*
X533121Y42200D01*
X533061Y42090D01*
X533021Y41965D01*
X533011Y41840D01*
Y38410D01*
X532981Y38380D01*
X532881Y38240D01*
X532861Y38200D01*
X532846Y38165D01*
X532826Y38125D01*
X532811Y38085D01*
X532801Y38045D01*
X532786Y38000D01*
X532781Y37960D01*
X532771Y37920D01*
X532766Y37875D01*
Y37835D01*
X532761Y37790D01*
X532766Y37745D01*
Y37705D01*
X532771Y37660D01*
X532781Y37620D01*
X532786Y37580D01*
X532801Y37535D01*
X532811Y37495D01*
X532826Y37455D01*
X532846Y37415D01*
X532861Y37380D01*
X532881Y37340D01*
X532981Y37200D01*
X533011Y37170D01*
Y36040D01*
X533021Y35915D01*
X533061Y35790D01*
X533121Y35680D01*
X533201Y35580D01*
X533301Y35500D01*
X533411Y35440D01*
X533536Y35400D01*
X533661Y35390D01*
G37*
G36*
G01X528937D02*
X529062Y35400D01*
X529187Y35440D01*
X529297Y35500D01*
X529397Y35580D01*
X529477Y35680D01*
X529537Y35790D01*
X529577Y35915D01*
X529587Y36040D01*
Y37170D01*
X529617Y37200D01*
X529717Y37340D01*
X529737Y37380D01*
X529752Y37415D01*
X529772Y37455D01*
X529787Y37495D01*
X529797Y37535D01*
X529812Y37580D01*
X529817Y37620D01*
X529827Y37660D01*
X529832Y37705D01*
Y37745D01*
X529837Y37790D01*
X529832Y37835D01*
Y37875D01*
X529827Y37920D01*
X529817Y37960D01*
X529812Y38000D01*
X529797Y38045D01*
X529787Y38085D01*
X529772Y38125D01*
X529752Y38165D01*
X529737Y38200D01*
X529717Y38240D01*
X529617Y38380D01*
X529587Y38410D01*
Y41840D01*
X529577Y41965D01*
X529537Y42090D01*
X529477Y42200D01*
X529397Y42300D01*
X529297Y42380D01*
X529187Y42440D01*
X529062Y42480D01*
X528937Y42490D01*
X528812Y42480D01*
X528687Y42440D01*
X528577Y42380D01*
X528477Y42300D01*
X528397Y42200D01*
X528337Y42090D01*
X528297Y41965D01*
X528287Y41840D01*
Y38410D01*
X528257Y38380D01*
X528157Y38240D01*
X528137Y38200D01*
X528122Y38165D01*
X528102Y38125D01*
X528087Y38085D01*
X528077Y38045D01*
X528062Y38000D01*
X528057Y37960D01*
X528047Y37920D01*
X528042Y37875D01*
Y37835D01*
X528037Y37790D01*
X528042Y37745D01*
Y37705D01*
X528047Y37660D01*
X528057Y37620D01*
X528062Y37580D01*
X528077Y37535D01*
X528087Y37495D01*
X528102Y37455D01*
X528122Y37415D01*
X528137Y37380D01*
X528157Y37340D01*
X528257Y37200D01*
X528287Y37170D01*
Y36040D01*
X528297Y35915D01*
X528337Y35790D01*
X528397Y35680D01*
X528477Y35580D01*
X528577Y35500D01*
X528687Y35440D01*
X528812Y35400D01*
X528937Y35390D01*
G37*
G36*
G01X557283D02*
X557408Y35400D01*
X557533Y35440D01*
X557643Y35500D01*
X557743Y35580D01*
X557823Y35680D01*
X557883Y35790D01*
X557923Y35915D01*
X557933Y36040D01*
Y37170D01*
X557963Y37200D01*
X558063Y37340D01*
X558083Y37380D01*
X558098Y37415D01*
X558118Y37455D01*
X558133Y37495D01*
X558143Y37535D01*
X558158Y37580D01*
X558163Y37620D01*
X558173Y37660D01*
X558178Y37705D01*
Y37745D01*
X558183Y37790D01*
X558178Y37835D01*
Y37875D01*
X558173Y37920D01*
X558163Y37960D01*
X558158Y38000D01*
X558143Y38045D01*
X558133Y38085D01*
X558118Y38125D01*
X558098Y38165D01*
X558083Y38200D01*
X558063Y38240D01*
X557963Y38380D01*
X557933Y38410D01*
Y41840D01*
X557923Y41965D01*
X557883Y42090D01*
X557823Y42200D01*
X557743Y42300D01*
X557643Y42380D01*
X557533Y42440D01*
X557408Y42480D01*
X557283Y42490D01*
X557158Y42480D01*
X557033Y42440D01*
X556923Y42380D01*
X556823Y42300D01*
X556743Y42200D01*
X556683Y42090D01*
X556643Y41965D01*
X556633Y41840D01*
Y38410D01*
X556603Y38380D01*
X556503Y38240D01*
X556483Y38200D01*
X556468Y38165D01*
X556448Y38125D01*
X556433Y38085D01*
X556423Y38045D01*
X556408Y38000D01*
X556403Y37960D01*
X556393Y37920D01*
X556388Y37875D01*
Y37835D01*
X556383Y37790D01*
X556388Y37745D01*
Y37705D01*
X556393Y37660D01*
X556403Y37620D01*
X556408Y37580D01*
X556423Y37535D01*
X556433Y37495D01*
X556448Y37455D01*
X556468Y37415D01*
X556483Y37380D01*
X556503Y37340D01*
X556603Y37200D01*
X556633Y37170D01*
Y36040D01*
X556643Y35915D01*
X556683Y35790D01*
X556743Y35680D01*
X556823Y35580D01*
X556923Y35500D01*
X557033Y35440D01*
X557158Y35400D01*
X557283Y35390D01*
G37*
G36*
G01X552559D02*
X552684Y35400D01*
X552809Y35440D01*
X552919Y35500D01*
X553019Y35580D01*
X553099Y35680D01*
X553159Y35790D01*
X553199Y35915D01*
X553209Y36040D01*
Y37170D01*
X553239Y37200D01*
X553339Y37340D01*
X553359Y37380D01*
X553374Y37415D01*
X553394Y37455D01*
X553409Y37495D01*
X553419Y37535D01*
X553434Y37580D01*
X553439Y37620D01*
X553449Y37660D01*
X553454Y37705D01*
Y37745D01*
X553459Y37790D01*
X553454Y37835D01*
Y37875D01*
X553449Y37920D01*
X553439Y37960D01*
X553434Y38000D01*
X553419Y38045D01*
X553409Y38085D01*
X553394Y38125D01*
X553374Y38165D01*
X553359Y38200D01*
X553339Y38240D01*
X553239Y38380D01*
X553209Y38410D01*
Y41840D01*
X553199Y41965D01*
X553159Y42090D01*
X553099Y42200D01*
X553019Y42300D01*
X552919Y42380D01*
X552809Y42440D01*
X552684Y42480D01*
X552559Y42490D01*
X552434Y42480D01*
X552309Y42440D01*
X552199Y42380D01*
X552099Y42300D01*
X552019Y42200D01*
X551959Y42090D01*
X551919Y41965D01*
X551909Y41840D01*
Y38410D01*
X551879Y38380D01*
X551779Y38240D01*
X551759Y38200D01*
X551744Y38165D01*
X551724Y38125D01*
X551709Y38085D01*
X551699Y38045D01*
X551684Y38000D01*
X551679Y37960D01*
X551669Y37920D01*
X551664Y37875D01*
Y37835D01*
X551659Y37790D01*
X551664Y37745D01*
Y37705D01*
X551669Y37660D01*
X551679Y37620D01*
X551684Y37580D01*
X551699Y37535D01*
X551709Y37495D01*
X551724Y37455D01*
X551744Y37415D01*
X551759Y37380D01*
X551779Y37340D01*
X551879Y37200D01*
X551909Y37170D01*
Y36040D01*
X551919Y35915D01*
X551959Y35790D01*
X552019Y35680D01*
X552099Y35580D01*
X552199Y35500D01*
X552309Y35440D01*
X552434Y35400D01*
X552559Y35390D01*
G37*
G36*
G01X547834D02*
X547959Y35400D01*
X548084Y35440D01*
X548194Y35500D01*
X548294Y35580D01*
X548374Y35680D01*
X548434Y35790D01*
X548474Y35915D01*
X548484Y36040D01*
Y37170D01*
X548514Y37200D01*
X548614Y37340D01*
X548634Y37380D01*
X548649Y37415D01*
X548669Y37455D01*
X548684Y37495D01*
X548694Y37535D01*
X548709Y37580D01*
X548714Y37620D01*
X548724Y37660D01*
X548729Y37705D01*
Y37745D01*
X548734Y37790D01*
X548729Y37835D01*
Y37875D01*
X548724Y37920D01*
X548714Y37960D01*
X548709Y38000D01*
X548694Y38045D01*
X548684Y38085D01*
X548669Y38125D01*
X548649Y38165D01*
X548634Y38200D01*
X548614Y38240D01*
X548514Y38380D01*
X548484Y38410D01*
Y41840D01*
X548474Y41965D01*
X548434Y42090D01*
X548374Y42200D01*
X548294Y42300D01*
X548194Y42380D01*
X548084Y42440D01*
X547959Y42480D01*
X547834Y42490D01*
X547709Y42480D01*
X547584Y42440D01*
X547474Y42380D01*
X547374Y42300D01*
X547294Y42200D01*
X547234Y42090D01*
X547194Y41965D01*
X547184Y41840D01*
Y38410D01*
X547154Y38380D01*
X547054Y38240D01*
X547034Y38200D01*
X547019Y38165D01*
X546999Y38125D01*
X546984Y38085D01*
X546974Y38045D01*
X546959Y38000D01*
X546954Y37960D01*
X546944Y37920D01*
X546939Y37875D01*
Y37835D01*
X546934Y37790D01*
X546939Y37745D01*
Y37705D01*
X546944Y37660D01*
X546954Y37620D01*
X546959Y37580D01*
X546974Y37535D01*
X546984Y37495D01*
X546999Y37455D01*
X547019Y37415D01*
X547034Y37380D01*
X547054Y37340D01*
X547154Y37200D01*
X547184Y37170D01*
Y36040D01*
X547194Y35915D01*
X547234Y35790D01*
X547294Y35680D01*
X547374Y35580D01*
X547474Y35500D01*
X547584Y35440D01*
X547709Y35400D01*
X547834Y35390D01*
G37*
G36*
G01X543110D02*
X543235Y35400D01*
X543360Y35440D01*
X543470Y35500D01*
X543570Y35580D01*
X543650Y35680D01*
X543710Y35790D01*
X543750Y35915D01*
X543760Y36040D01*
Y37170D01*
X543790Y37200D01*
X543890Y37340D01*
X543910Y37380D01*
X543925Y37415D01*
X543945Y37455D01*
X543960Y37495D01*
X543970Y37535D01*
X543985Y37580D01*
X543990Y37620D01*
X544000Y37660D01*
X544005Y37705D01*
Y37745D01*
X544010Y37790D01*
X544005Y37835D01*
Y37875D01*
X544000Y37920D01*
X543990Y37960D01*
X543985Y38000D01*
X543970Y38045D01*
X543960Y38085D01*
X543945Y38125D01*
X543925Y38165D01*
X543910Y38200D01*
X543890Y38240D01*
X543790Y38380D01*
X543760Y38410D01*
Y41840D01*
X543750Y41965D01*
X543710Y42090D01*
X543650Y42200D01*
X543570Y42300D01*
X543470Y42380D01*
X543360Y42440D01*
X543235Y42480D01*
X543110Y42490D01*
X542985Y42480D01*
X542860Y42440D01*
X542750Y42380D01*
X542650Y42300D01*
X542570Y42200D01*
X542510Y42090D01*
X542470Y41965D01*
X542460Y41840D01*
Y38410D01*
X542430Y38380D01*
X542330Y38240D01*
X542310Y38200D01*
X542295Y38165D01*
X542275Y38125D01*
X542260Y38085D01*
X542250Y38045D01*
X542235Y38000D01*
X542230Y37960D01*
X542220Y37920D01*
X542215Y37875D01*
Y37835D01*
X542210Y37790D01*
X542215Y37745D01*
Y37705D01*
X542220Y37660D01*
X542230Y37620D01*
X542235Y37580D01*
X542250Y37535D01*
X542260Y37495D01*
X542275Y37455D01*
X542295Y37415D01*
X542310Y37380D01*
X542330Y37340D01*
X542430Y37200D01*
X542460Y37170D01*
Y36040D01*
X542470Y35915D01*
X542510Y35790D01*
X542570Y35680D01*
X542650Y35580D01*
X542750Y35500D01*
X542860Y35440D01*
X542985Y35400D01*
X543110Y35390D01*
G37*
G36*
G01X571456D02*
X571581Y35400D01*
X571706Y35440D01*
X571816Y35500D01*
X571916Y35580D01*
X571996Y35680D01*
X572056Y35790D01*
X572096Y35915D01*
X572106Y36040D01*
Y37170D01*
X572136Y37200D01*
X572236Y37340D01*
X572256Y37380D01*
X572271Y37415D01*
X572291Y37455D01*
X572306Y37495D01*
X572316Y37535D01*
X572331Y37580D01*
X572336Y37620D01*
X572346Y37660D01*
X572351Y37705D01*
Y37745D01*
X572356Y37790D01*
X572351Y37835D01*
Y37875D01*
X572346Y37920D01*
X572336Y37960D01*
X572331Y38000D01*
X572316Y38045D01*
X572306Y38085D01*
X572291Y38125D01*
X572271Y38165D01*
X572256Y38200D01*
X572236Y38240D01*
X572136Y38380D01*
X572106Y38410D01*
Y41840D01*
X572096Y41965D01*
X572056Y42090D01*
X571996Y42200D01*
X571916Y42300D01*
X571816Y42380D01*
X571706Y42440D01*
X571581Y42480D01*
X571456Y42490D01*
X571331Y42480D01*
X571206Y42440D01*
X571096Y42380D01*
X570996Y42300D01*
X570916Y42200D01*
X570856Y42090D01*
X570816Y41965D01*
X570806Y41840D01*
Y38410D01*
X570776Y38380D01*
X570676Y38240D01*
X570656Y38200D01*
X570641Y38165D01*
X570621Y38125D01*
X570606Y38085D01*
X570596Y38045D01*
X570581Y38000D01*
X570576Y37960D01*
X570566Y37920D01*
X570561Y37875D01*
Y37835D01*
X570556Y37790D01*
X570561Y37745D01*
Y37705D01*
X570566Y37660D01*
X570576Y37620D01*
X570581Y37580D01*
X570596Y37535D01*
X570606Y37495D01*
X570621Y37455D01*
X570641Y37415D01*
X570656Y37380D01*
X570676Y37340D01*
X570776Y37200D01*
X570806Y37170D01*
Y36040D01*
X570816Y35915D01*
X570856Y35790D01*
X570916Y35680D01*
X570996Y35580D01*
X571096Y35500D01*
X571206Y35440D01*
X571331Y35400D01*
X571456Y35390D01*
G37*
G36*
G01X566732D02*
X566857Y35400D01*
X566982Y35440D01*
X567092Y35500D01*
X567192Y35580D01*
X567272Y35680D01*
X567332Y35790D01*
X567372Y35915D01*
X567382Y36040D01*
Y37170D01*
X567412Y37200D01*
X567512Y37340D01*
X567532Y37380D01*
X567547Y37415D01*
X567567Y37455D01*
X567582Y37495D01*
X567592Y37535D01*
X567607Y37580D01*
X567612Y37620D01*
X567622Y37660D01*
X567627Y37705D01*
Y37745D01*
X567632Y37790D01*
X567627Y37835D01*
Y37875D01*
X567622Y37920D01*
X567612Y37960D01*
X567607Y38000D01*
X567592Y38045D01*
X567582Y38085D01*
X567567Y38125D01*
X567547Y38165D01*
X567532Y38200D01*
X567512Y38240D01*
X567412Y38380D01*
X567382Y38410D01*
Y41840D01*
X567372Y41965D01*
X567332Y42090D01*
X567272Y42200D01*
X567192Y42300D01*
X567092Y42380D01*
X566982Y42440D01*
X566857Y42480D01*
X566732Y42490D01*
X566607Y42480D01*
X566482Y42440D01*
X566372Y42380D01*
X566272Y42300D01*
X566192Y42200D01*
X566132Y42090D01*
X566092Y41965D01*
X566082Y41840D01*
Y38410D01*
X566052Y38380D01*
X565952Y38240D01*
X565932Y38200D01*
X565917Y38165D01*
X565897Y38125D01*
X565882Y38085D01*
X565872Y38045D01*
X565857Y38000D01*
X565852Y37960D01*
X565842Y37920D01*
X565837Y37875D01*
Y37835D01*
X565832Y37790D01*
X565837Y37745D01*
Y37705D01*
X565842Y37660D01*
X565852Y37620D01*
X565857Y37580D01*
X565872Y37535D01*
X565882Y37495D01*
X565897Y37455D01*
X565917Y37415D01*
X565932Y37380D01*
X565952Y37340D01*
X566052Y37200D01*
X566082Y37170D01*
Y36040D01*
X566092Y35915D01*
X566132Y35790D01*
X566192Y35680D01*
X566272Y35580D01*
X566372Y35500D01*
X566482Y35440D01*
X566607Y35400D01*
X566732Y35390D01*
G37*
G36*
G01X562008D02*
X562133Y35400D01*
X562258Y35440D01*
X562368Y35500D01*
X562468Y35580D01*
X562548Y35680D01*
X562608Y35790D01*
X562648Y35915D01*
X562658Y36040D01*
Y37170D01*
X562688Y37200D01*
X562788Y37340D01*
X562808Y37380D01*
X562823Y37415D01*
X562843Y37455D01*
X562858Y37495D01*
X562868Y37535D01*
X562883Y37580D01*
X562888Y37620D01*
X562898Y37660D01*
X562903Y37705D01*
Y37745D01*
X562908Y37790D01*
X562903Y37835D01*
Y37875D01*
X562898Y37920D01*
X562888Y37960D01*
X562883Y38000D01*
X562868Y38045D01*
X562858Y38085D01*
X562843Y38125D01*
X562823Y38165D01*
X562808Y38200D01*
X562788Y38240D01*
X562688Y38380D01*
X562658Y38410D01*
Y41840D01*
X562648Y41965D01*
X562608Y42090D01*
X562548Y42200D01*
X562468Y42300D01*
X562368Y42380D01*
X562258Y42440D01*
X562133Y42480D01*
X562008Y42490D01*
X561883Y42480D01*
X561758Y42440D01*
X561648Y42380D01*
X561548Y42300D01*
X561468Y42200D01*
X561408Y42090D01*
X561368Y41965D01*
X561358Y41840D01*
Y38410D01*
X561328Y38380D01*
X561228Y38240D01*
X561208Y38200D01*
X561193Y38165D01*
X561173Y38125D01*
X561158Y38085D01*
X561148Y38045D01*
X561133Y38000D01*
X561128Y37960D01*
X561118Y37920D01*
X561113Y37875D01*
Y37835D01*
X561108Y37790D01*
X561113Y37745D01*
Y37705D01*
X561118Y37660D01*
X561128Y37620D01*
X561133Y37580D01*
X561148Y37535D01*
X561158Y37495D01*
X561173Y37455D01*
X561193Y37415D01*
X561208Y37380D01*
X561228Y37340D01*
X561328Y37200D01*
X561358Y37170D01*
Y36040D01*
X561368Y35915D01*
X561408Y35790D01*
X561468Y35680D01*
X561548Y35580D01*
X561648Y35500D01*
X561758Y35440D01*
X561883Y35400D01*
X562008Y35390D01*
G37*
G36*
G01X585630D02*
X585755Y35400D01*
X585880Y35440D01*
X585990Y35500D01*
X586090Y35580D01*
X586170Y35680D01*
X586230Y35790D01*
X586270Y35915D01*
X586280Y36040D01*
Y37170D01*
X586310Y37200D01*
X586410Y37340D01*
X586430Y37380D01*
X586445Y37415D01*
X586465Y37455D01*
X586480Y37495D01*
X586490Y37535D01*
X586505Y37580D01*
X586510Y37620D01*
X586520Y37660D01*
X586525Y37705D01*
Y37745D01*
X586530Y37790D01*
X586525Y37835D01*
Y37875D01*
X586520Y37920D01*
X586510Y37960D01*
X586505Y38000D01*
X586490Y38045D01*
X586480Y38085D01*
X586465Y38125D01*
X586445Y38165D01*
X586430Y38200D01*
X586410Y38240D01*
X586310Y38380D01*
X586280Y38410D01*
Y41840D01*
X586270Y41965D01*
X586230Y42090D01*
X586170Y42200D01*
X586090Y42300D01*
X585990Y42380D01*
X585880Y42440D01*
X585755Y42480D01*
X585630Y42490D01*
X585505Y42480D01*
X585380Y42440D01*
X585270Y42380D01*
X585170Y42300D01*
X585090Y42200D01*
X585030Y42090D01*
X584990Y41965D01*
X584980Y41840D01*
Y38410D01*
X584950Y38380D01*
X584850Y38240D01*
X584830Y38200D01*
X584815Y38165D01*
X584795Y38125D01*
X584780Y38085D01*
X584770Y38045D01*
X584755Y38000D01*
X584750Y37960D01*
X584740Y37920D01*
X584735Y37875D01*
Y37835D01*
X584730Y37790D01*
X584735Y37745D01*
Y37705D01*
X584740Y37660D01*
X584750Y37620D01*
X584755Y37580D01*
X584770Y37535D01*
X584780Y37495D01*
X584795Y37455D01*
X584815Y37415D01*
X584830Y37380D01*
X584850Y37340D01*
X584950Y37200D01*
X584980Y37170D01*
Y36040D01*
X584990Y35915D01*
X585030Y35790D01*
X585090Y35680D01*
X585170Y35580D01*
X585270Y35500D01*
X585380Y35440D01*
X585505Y35400D01*
X585630Y35390D01*
G37*
G36*
G01X580905D02*
X581030Y35400D01*
X581155Y35440D01*
X581265Y35500D01*
X581365Y35580D01*
X581445Y35680D01*
X581505Y35790D01*
X581545Y35915D01*
X581555Y36040D01*
Y37170D01*
X581585Y37200D01*
X581685Y37340D01*
X581705Y37380D01*
X581720Y37415D01*
X581740Y37455D01*
X581755Y37495D01*
X581765Y37535D01*
X581780Y37580D01*
X581785Y37620D01*
X581795Y37660D01*
X581800Y37705D01*
Y37745D01*
X581805Y37790D01*
X581800Y37835D01*
Y37875D01*
X581795Y37920D01*
X581785Y37960D01*
X581780Y38000D01*
X581765Y38045D01*
X581755Y38085D01*
X581740Y38125D01*
X581720Y38165D01*
X581705Y38200D01*
X581685Y38240D01*
X581585Y38380D01*
X581555Y38410D01*
Y41840D01*
X581545Y41965D01*
X581505Y42090D01*
X581445Y42200D01*
X581365Y42300D01*
X581265Y42380D01*
X581155Y42440D01*
X581030Y42480D01*
X580905Y42490D01*
X580780Y42480D01*
X580655Y42440D01*
X580545Y42380D01*
X580445Y42300D01*
X580365Y42200D01*
X580305Y42090D01*
X580265Y41965D01*
X580255Y41840D01*
Y38410D01*
X580225Y38380D01*
X580125Y38240D01*
X580105Y38200D01*
X580090Y38165D01*
X580070Y38125D01*
X580055Y38085D01*
X580045Y38045D01*
X580030Y38000D01*
X580025Y37960D01*
X580015Y37920D01*
X580010Y37875D01*
Y37835D01*
X580005Y37790D01*
X580010Y37745D01*
Y37705D01*
X580015Y37660D01*
X580025Y37620D01*
X580030Y37580D01*
X580045Y37535D01*
X580055Y37495D01*
X580070Y37455D01*
X580090Y37415D01*
X580105Y37380D01*
X580125Y37340D01*
X580225Y37200D01*
X580255Y37170D01*
Y36040D01*
X580265Y35915D01*
X580305Y35790D01*
X580365Y35680D01*
X580445Y35580D01*
X580545Y35500D01*
X580655Y35440D01*
X580780Y35400D01*
X580905Y35390D01*
G37*
G36*
G01X576181D02*
X576306Y35400D01*
X576431Y35440D01*
X576541Y35500D01*
X576641Y35580D01*
X576721Y35680D01*
X576781Y35790D01*
X576821Y35915D01*
X576831Y36040D01*
Y37170D01*
X576861Y37200D01*
X576961Y37340D01*
X576981Y37380D01*
X576996Y37415D01*
X577016Y37455D01*
X577031Y37495D01*
X577041Y37535D01*
X577056Y37580D01*
X577061Y37620D01*
X577071Y37660D01*
X577076Y37705D01*
Y37745D01*
X577081Y37790D01*
X577076Y37835D01*
Y37875D01*
X577071Y37920D01*
X577061Y37960D01*
X577056Y38000D01*
X577041Y38045D01*
X577031Y38085D01*
X577016Y38125D01*
X576996Y38165D01*
X576981Y38200D01*
X576961Y38240D01*
X576861Y38380D01*
X576831Y38410D01*
Y41840D01*
X576821Y41965D01*
X576781Y42090D01*
X576721Y42200D01*
X576641Y42300D01*
X576541Y42380D01*
X576431Y42440D01*
X576306Y42480D01*
X576181Y42490D01*
X576056Y42480D01*
X575931Y42440D01*
X575821Y42380D01*
X575721Y42300D01*
X575641Y42200D01*
X575581Y42090D01*
X575541Y41965D01*
X575531Y41840D01*
Y38410D01*
X575501Y38380D01*
X575401Y38240D01*
X575381Y38200D01*
X575366Y38165D01*
X575346Y38125D01*
X575331Y38085D01*
X575321Y38045D01*
X575306Y38000D01*
X575301Y37960D01*
X575291Y37920D01*
X575286Y37875D01*
Y37835D01*
X575281Y37790D01*
X575286Y37745D01*
Y37705D01*
X575291Y37660D01*
X575301Y37620D01*
X575306Y37580D01*
X575321Y37535D01*
X575331Y37495D01*
X575346Y37455D01*
X575366Y37415D01*
X575381Y37380D01*
X575401Y37340D01*
X575501Y37200D01*
X575531Y37170D01*
Y36040D01*
X575541Y35915D01*
X575581Y35790D01*
X575641Y35680D01*
X575721Y35580D01*
X575821Y35500D01*
X575931Y35440D01*
X576056Y35400D01*
X576181Y35390D01*
G37*
G36*
G01X599803D02*
X599928Y35400D01*
X600053Y35440D01*
X600163Y35500D01*
X600263Y35580D01*
X600343Y35680D01*
X600403Y35790D01*
X600443Y35915D01*
X600453Y36040D01*
Y37170D01*
X600483Y37200D01*
X600583Y37340D01*
X600603Y37380D01*
X600618Y37415D01*
X600638Y37455D01*
X600653Y37495D01*
X600663Y37535D01*
X600678Y37580D01*
X600683Y37620D01*
X600693Y37660D01*
X600698Y37705D01*
Y37745D01*
X600703Y37790D01*
X600698Y37835D01*
Y37875D01*
X600693Y37920D01*
X600683Y37960D01*
X600678Y38000D01*
X600663Y38045D01*
X600653Y38085D01*
X600638Y38125D01*
X600618Y38165D01*
X600603Y38200D01*
X600583Y38240D01*
X600483Y38380D01*
X600453Y38410D01*
Y41840D01*
X600443Y41965D01*
X600403Y42090D01*
X600343Y42200D01*
X600263Y42300D01*
X600163Y42380D01*
X600053Y42440D01*
X599928Y42480D01*
X599803Y42490D01*
X599678Y42480D01*
X599553Y42440D01*
X599443Y42380D01*
X599343Y42300D01*
X599263Y42200D01*
X599203Y42090D01*
X599163Y41965D01*
X599153Y41840D01*
Y38410D01*
X599123Y38380D01*
X599023Y38240D01*
X599003Y38200D01*
X598988Y38165D01*
X598968Y38125D01*
X598953Y38085D01*
X598943Y38045D01*
X598928Y38000D01*
X598923Y37960D01*
X598913Y37920D01*
X598908Y37875D01*
Y37835D01*
X598903Y37790D01*
X598908Y37745D01*
Y37705D01*
X598913Y37660D01*
X598923Y37620D01*
X598928Y37580D01*
X598943Y37535D01*
X598953Y37495D01*
X598968Y37455D01*
X598988Y37415D01*
X599003Y37380D01*
X599023Y37340D01*
X599123Y37200D01*
X599153Y37170D01*
Y36040D01*
X599163Y35915D01*
X599203Y35790D01*
X599263Y35680D01*
X599343Y35580D01*
X599443Y35500D01*
X599553Y35440D01*
X599678Y35400D01*
X599803Y35390D01*
G37*
G36*
G01X618701D02*
X618826Y35400D01*
X618951Y35440D01*
X619061Y35500D01*
X619161Y35580D01*
X619241Y35680D01*
X619301Y35790D01*
X619341Y35915D01*
X619351Y36040D01*
Y37170D01*
X619381Y37200D01*
X619481Y37340D01*
X619501Y37380D01*
X619516Y37415D01*
X619536Y37455D01*
X619551Y37495D01*
X619561Y37535D01*
X619576Y37580D01*
X619581Y37620D01*
X619591Y37660D01*
X619596Y37705D01*
Y37745D01*
X619601Y37790D01*
X619596Y37835D01*
Y37875D01*
X619591Y37920D01*
X619581Y37960D01*
X619576Y38000D01*
X619561Y38045D01*
X619551Y38085D01*
X619536Y38125D01*
X619516Y38165D01*
X619501Y38200D01*
X619481Y38240D01*
X619381Y38380D01*
X619351Y38410D01*
Y41840D01*
X619341Y41965D01*
X619301Y42090D01*
X619241Y42200D01*
X619161Y42300D01*
X619061Y42380D01*
X618951Y42440D01*
X618826Y42480D01*
X618701Y42490D01*
X618576Y42480D01*
X618451Y42440D01*
X618341Y42380D01*
X618241Y42300D01*
X618161Y42200D01*
X618101Y42090D01*
X618061Y41965D01*
X618051Y41840D01*
Y38410D01*
X618021Y38380D01*
X617921Y38240D01*
X617901Y38200D01*
X617886Y38165D01*
X617866Y38125D01*
X617851Y38085D01*
X617841Y38045D01*
X617826Y38000D01*
X617821Y37960D01*
X617811Y37920D01*
X617806Y37875D01*
Y37835D01*
X617801Y37790D01*
X617806Y37745D01*
Y37705D01*
X617811Y37660D01*
X617821Y37620D01*
X617826Y37580D01*
X617841Y37535D01*
X617851Y37495D01*
X617866Y37455D01*
X617886Y37415D01*
X617901Y37380D01*
X617921Y37340D01*
X618021Y37200D01*
X618051Y37170D01*
Y36040D01*
X618061Y35915D01*
X618101Y35790D01*
X618161Y35680D01*
X618241Y35580D01*
X618341Y35500D01*
X618451Y35440D01*
X618576Y35400D01*
X618701Y35390D01*
G37*
G36*
G01X613976D02*
X614101Y35400D01*
X614226Y35440D01*
X614336Y35500D01*
X614436Y35580D01*
X614516Y35680D01*
X614576Y35790D01*
X614616Y35915D01*
X614626Y36040D01*
Y37170D01*
X614656Y37200D01*
X614756Y37340D01*
X614776Y37380D01*
X614791Y37415D01*
X614811Y37455D01*
X614826Y37495D01*
X614836Y37535D01*
X614851Y37580D01*
X614856Y37620D01*
X614866Y37660D01*
X614871Y37705D01*
Y37745D01*
X614876Y37790D01*
X614871Y37835D01*
Y37875D01*
X614866Y37920D01*
X614856Y37960D01*
X614851Y38000D01*
X614836Y38045D01*
X614826Y38085D01*
X614811Y38125D01*
X614791Y38165D01*
X614776Y38200D01*
X614756Y38240D01*
X614656Y38380D01*
X614626Y38410D01*
Y41840D01*
X614616Y41965D01*
X614576Y42090D01*
X614516Y42200D01*
X614436Y42300D01*
X614336Y42380D01*
X614226Y42440D01*
X614101Y42480D01*
X613976Y42490D01*
X613851Y42480D01*
X613726Y42440D01*
X613616Y42380D01*
X613516Y42300D01*
X613436Y42200D01*
X613376Y42090D01*
X613336Y41965D01*
X613326Y41840D01*
Y38410D01*
X613296Y38380D01*
X613196Y38240D01*
X613176Y38200D01*
X613161Y38165D01*
X613141Y38125D01*
X613126Y38085D01*
X613116Y38045D01*
X613101Y38000D01*
X613096Y37960D01*
X613086Y37920D01*
X613081Y37875D01*
Y37835D01*
X613076Y37790D01*
X613081Y37745D01*
Y37705D01*
X613086Y37660D01*
X613096Y37620D01*
X613101Y37580D01*
X613116Y37535D01*
X613126Y37495D01*
X613141Y37455D01*
X613161Y37415D01*
X613176Y37380D01*
X613196Y37340D01*
X613296Y37200D01*
X613326Y37170D01*
Y36040D01*
X613336Y35915D01*
X613376Y35790D01*
X613436Y35680D01*
X613516Y35580D01*
X613616Y35500D01*
X613726Y35440D01*
X613851Y35400D01*
X613976Y35390D01*
G37*
G36*
G01X609252D02*
X609377Y35400D01*
X609502Y35440D01*
X609612Y35500D01*
X609712Y35580D01*
X609792Y35680D01*
X609852Y35790D01*
X609892Y35915D01*
X609902Y36040D01*
Y37170D01*
X609932Y37200D01*
X610032Y37340D01*
X610052Y37380D01*
X610067Y37415D01*
X610087Y37455D01*
X610102Y37495D01*
X610112Y37535D01*
X610127Y37580D01*
X610132Y37620D01*
X610142Y37660D01*
X610147Y37705D01*
Y37745D01*
X610152Y37790D01*
X610147Y37835D01*
Y37875D01*
X610142Y37920D01*
X610132Y37960D01*
X610127Y38000D01*
X610112Y38045D01*
X610102Y38085D01*
X610087Y38125D01*
X610067Y38165D01*
X610052Y38200D01*
X610032Y38240D01*
X609932Y38380D01*
X609902Y38410D01*
Y41840D01*
X609892Y41965D01*
X609852Y42090D01*
X609792Y42200D01*
X609712Y42300D01*
X609612Y42380D01*
X609502Y42440D01*
X609377Y42480D01*
X609252Y42490D01*
X609127Y42480D01*
X609002Y42440D01*
X608892Y42380D01*
X608792Y42300D01*
X608712Y42200D01*
X608652Y42090D01*
X608612Y41965D01*
X608602Y41840D01*
Y38410D01*
X608572Y38380D01*
X608472Y38240D01*
X608452Y38200D01*
X608437Y38165D01*
X608417Y38125D01*
X608402Y38085D01*
X608392Y38045D01*
X608377Y38000D01*
X608372Y37960D01*
X608362Y37920D01*
X608357Y37875D01*
Y37835D01*
X608352Y37790D01*
X608357Y37745D01*
Y37705D01*
X608362Y37660D01*
X608372Y37620D01*
X608377Y37580D01*
X608392Y37535D01*
X608402Y37495D01*
X608417Y37455D01*
X608437Y37415D01*
X608452Y37380D01*
X608472Y37340D01*
X608572Y37200D01*
X608602Y37170D01*
Y36040D01*
X608612Y35915D01*
X608652Y35790D01*
X608712Y35680D01*
X608792Y35580D01*
X608892Y35500D01*
X609002Y35440D01*
X609127Y35400D01*
X609252Y35390D01*
G37*
G36*
G01X604527D02*
X604652Y35400D01*
X604777Y35440D01*
X604887Y35500D01*
X604987Y35580D01*
X605067Y35680D01*
X605127Y35790D01*
X605167Y35915D01*
X605177Y36040D01*
Y37170D01*
X605207Y37200D01*
X605307Y37340D01*
X605327Y37380D01*
X605342Y37415D01*
X605362Y37455D01*
X605377Y37495D01*
X605387Y37535D01*
X605402Y37580D01*
X605407Y37620D01*
X605417Y37660D01*
X605422Y37705D01*
Y37745D01*
X605427Y37790D01*
X605422Y37835D01*
Y37875D01*
X605417Y37920D01*
X605407Y37960D01*
X605402Y38000D01*
X605387Y38045D01*
X605377Y38085D01*
X605362Y38125D01*
X605342Y38165D01*
X605327Y38200D01*
X605307Y38240D01*
X605207Y38380D01*
X605177Y38410D01*
Y41840D01*
X605167Y41965D01*
X605127Y42090D01*
X605067Y42200D01*
X604987Y42300D01*
X604887Y42380D01*
X604777Y42440D01*
X604652Y42480D01*
X604527Y42490D01*
X604402Y42480D01*
X604277Y42440D01*
X604167Y42380D01*
X604067Y42300D01*
X603987Y42200D01*
X603927Y42090D01*
X603887Y41965D01*
X603877Y41840D01*
Y38410D01*
X603847Y38380D01*
X603747Y38240D01*
X603727Y38200D01*
X603712Y38165D01*
X603692Y38125D01*
X603677Y38085D01*
X603667Y38045D01*
X603652Y38000D01*
X603647Y37960D01*
X603637Y37920D01*
X603632Y37875D01*
Y37835D01*
X603627Y37790D01*
X603632Y37745D01*
Y37705D01*
X603637Y37660D01*
X603647Y37620D01*
X603652Y37580D01*
X603667Y37535D01*
X603677Y37495D01*
X603692Y37455D01*
X603712Y37415D01*
X603727Y37380D01*
X603747Y37340D01*
X603847Y37200D01*
X603877Y37170D01*
Y36040D01*
X603887Y35915D01*
X603927Y35790D01*
X603987Y35680D01*
X604067Y35580D01*
X604167Y35500D01*
X604277Y35440D01*
X604402Y35400D01*
X604527Y35390D01*
G37*
G36*
G01X632874D02*
X632999Y35400D01*
X633124Y35440D01*
X633234Y35500D01*
X633334Y35580D01*
X633414Y35680D01*
X633474Y35790D01*
X633514Y35915D01*
X633524Y36040D01*
Y37170D01*
X633554Y37200D01*
X633654Y37340D01*
X633674Y37380D01*
X633689Y37415D01*
X633709Y37455D01*
X633724Y37495D01*
X633734Y37535D01*
X633749Y37580D01*
X633754Y37620D01*
X633764Y37660D01*
X633769Y37705D01*
Y37745D01*
X633774Y37790D01*
X633769Y37835D01*
Y37875D01*
X633764Y37920D01*
X633754Y37960D01*
X633749Y38000D01*
X633734Y38045D01*
X633724Y38085D01*
X633709Y38125D01*
X633689Y38165D01*
X633674Y38200D01*
X633654Y38240D01*
X633554Y38380D01*
X633524Y38410D01*
Y41840D01*
X633514Y41965D01*
X633474Y42090D01*
X633414Y42200D01*
X633334Y42300D01*
X633234Y42380D01*
X633124Y42440D01*
X632999Y42480D01*
X632874Y42490D01*
X632749Y42480D01*
X632624Y42440D01*
X632514Y42380D01*
X632414Y42300D01*
X632334Y42200D01*
X632274Y42090D01*
X632234Y41965D01*
X632224Y41840D01*
Y38410D01*
X632194Y38380D01*
X632094Y38240D01*
X632074Y38200D01*
X632059Y38165D01*
X632039Y38125D01*
X632024Y38085D01*
X632014Y38045D01*
X631999Y38000D01*
X631994Y37960D01*
X631984Y37920D01*
X631979Y37875D01*
Y37835D01*
X631974Y37790D01*
X631979Y37745D01*
Y37705D01*
X631984Y37660D01*
X631994Y37620D01*
X631999Y37580D01*
X632014Y37535D01*
X632024Y37495D01*
X632039Y37455D01*
X632059Y37415D01*
X632074Y37380D01*
X632094Y37340D01*
X632194Y37200D01*
X632224Y37170D01*
Y36040D01*
X632234Y35915D01*
X632274Y35790D01*
X632334Y35680D01*
X632414Y35580D01*
X632514Y35500D01*
X632624Y35440D01*
X632749Y35400D01*
X632874Y35390D01*
G37*
G36*
G01X628149D02*
X628274Y35400D01*
X628399Y35440D01*
X628509Y35500D01*
X628609Y35580D01*
X628689Y35680D01*
X628749Y35790D01*
X628789Y35915D01*
X628799Y36040D01*
Y37170D01*
X628829Y37200D01*
X628929Y37340D01*
X628949Y37380D01*
X628964Y37415D01*
X628984Y37455D01*
X628999Y37495D01*
X629009Y37535D01*
X629024Y37580D01*
X629029Y37620D01*
X629039Y37660D01*
X629044Y37705D01*
Y37745D01*
X629049Y37790D01*
X629044Y37835D01*
Y37875D01*
X629039Y37920D01*
X629029Y37960D01*
X629024Y38000D01*
X629009Y38045D01*
X628999Y38085D01*
X628984Y38125D01*
X628964Y38165D01*
X628949Y38200D01*
X628929Y38240D01*
X628829Y38380D01*
X628799Y38410D01*
Y41840D01*
X628789Y41965D01*
X628749Y42090D01*
X628689Y42200D01*
X628609Y42300D01*
X628509Y42380D01*
X628399Y42440D01*
X628274Y42480D01*
X628149Y42490D01*
X628024Y42480D01*
X627899Y42440D01*
X627789Y42380D01*
X627689Y42300D01*
X627609Y42200D01*
X627549Y42090D01*
X627509Y41965D01*
X627499Y41840D01*
Y38410D01*
X627469Y38380D01*
X627369Y38240D01*
X627349Y38200D01*
X627334Y38165D01*
X627314Y38125D01*
X627299Y38085D01*
X627289Y38045D01*
X627274Y38000D01*
X627269Y37960D01*
X627259Y37920D01*
X627254Y37875D01*
Y37835D01*
X627249Y37790D01*
X627254Y37745D01*
Y37705D01*
X627259Y37660D01*
X627269Y37620D01*
X627274Y37580D01*
X627289Y37535D01*
X627299Y37495D01*
X627314Y37455D01*
X627334Y37415D01*
X627349Y37380D01*
X627369Y37340D01*
X627469Y37200D01*
X627499Y37170D01*
Y36040D01*
X627509Y35915D01*
X627549Y35790D01*
X627609Y35680D01*
X627689Y35580D01*
X627789Y35500D01*
X627899Y35440D01*
X628024Y35400D01*
X628149Y35390D01*
G37*
G36*
G01X623425D02*
X623550Y35400D01*
X623675Y35440D01*
X623785Y35500D01*
X623885Y35580D01*
X623965Y35680D01*
X624025Y35790D01*
X624065Y35915D01*
X624075Y36040D01*
Y37170D01*
X624105Y37200D01*
X624205Y37340D01*
X624225Y37380D01*
X624240Y37415D01*
X624260Y37455D01*
X624275Y37495D01*
X624285Y37535D01*
X624300Y37580D01*
X624305Y37620D01*
X624315Y37660D01*
X624320Y37705D01*
Y37745D01*
X624325Y37790D01*
X624320Y37835D01*
Y37875D01*
X624315Y37920D01*
X624305Y37960D01*
X624300Y38000D01*
X624285Y38045D01*
X624275Y38085D01*
X624260Y38125D01*
X624240Y38165D01*
X624225Y38200D01*
X624205Y38240D01*
X624105Y38380D01*
X624075Y38410D01*
Y41840D01*
X624065Y41965D01*
X624025Y42090D01*
X623965Y42200D01*
X623885Y42300D01*
X623785Y42380D01*
X623675Y42440D01*
X623550Y42480D01*
X623425Y42490D01*
X623300Y42480D01*
X623175Y42440D01*
X623065Y42380D01*
X622965Y42300D01*
X622885Y42200D01*
X622825Y42090D01*
X622785Y41965D01*
X622775Y41840D01*
Y38410D01*
X622745Y38380D01*
X622645Y38240D01*
X622625Y38200D01*
X622610Y38165D01*
X622590Y38125D01*
X622575Y38085D01*
X622565Y38045D01*
X622550Y38000D01*
X622545Y37960D01*
X622535Y37920D01*
X622530Y37875D01*
Y37835D01*
X622525Y37790D01*
X622530Y37745D01*
Y37705D01*
X622535Y37660D01*
X622545Y37620D01*
X622550Y37580D01*
X622565Y37535D01*
X622575Y37495D01*
X622590Y37455D01*
X622610Y37415D01*
X622625Y37380D01*
X622645Y37340D01*
X622745Y37200D01*
X622775Y37170D01*
Y36040D01*
X622785Y35915D01*
X622825Y35790D01*
X622885Y35680D01*
X622965Y35580D01*
X623065Y35500D01*
X623175Y35440D01*
X623300Y35400D01*
X623425Y35390D01*
G37*
G36*
G01X647047D02*
X647172Y35400D01*
X647297Y35440D01*
X647407Y35500D01*
X647507Y35580D01*
X647587Y35680D01*
X647647Y35790D01*
X647687Y35915D01*
X647697Y36040D01*
Y37170D01*
X647727Y37200D01*
X647827Y37340D01*
X647847Y37380D01*
X647862Y37415D01*
X647882Y37455D01*
X647897Y37495D01*
X647907Y37535D01*
X647922Y37580D01*
X647927Y37620D01*
X647937Y37660D01*
X647942Y37705D01*
Y37745D01*
X647947Y37790D01*
X647942Y37835D01*
Y37875D01*
X647937Y37920D01*
X647927Y37960D01*
X647922Y38000D01*
X647907Y38045D01*
X647897Y38085D01*
X647882Y38125D01*
X647862Y38165D01*
X647847Y38200D01*
X647827Y38240D01*
X647727Y38380D01*
X647697Y38410D01*
Y41840D01*
X647687Y41965D01*
X647647Y42090D01*
X647587Y42200D01*
X647507Y42300D01*
X647407Y42380D01*
X647297Y42440D01*
X647172Y42480D01*
X647047Y42490D01*
X646922Y42480D01*
X646797Y42440D01*
X646687Y42380D01*
X646587Y42300D01*
X646507Y42200D01*
X646447Y42090D01*
X646407Y41965D01*
X646397Y41840D01*
Y38410D01*
X646367Y38380D01*
X646267Y38240D01*
X646247Y38200D01*
X646232Y38165D01*
X646212Y38125D01*
X646197Y38085D01*
X646187Y38045D01*
X646172Y38000D01*
X646167Y37960D01*
X646157Y37920D01*
X646152Y37875D01*
Y37835D01*
X646147Y37790D01*
X646152Y37745D01*
Y37705D01*
X646157Y37660D01*
X646167Y37620D01*
X646172Y37580D01*
X646187Y37535D01*
X646197Y37495D01*
X646212Y37455D01*
X646232Y37415D01*
X646247Y37380D01*
X646267Y37340D01*
X646367Y37200D01*
X646397Y37170D01*
Y36040D01*
X646407Y35915D01*
X646447Y35790D01*
X646507Y35680D01*
X646587Y35580D01*
X646687Y35500D01*
X646797Y35440D01*
X646922Y35400D01*
X647047Y35390D01*
G37*
G36*
G01X642323D02*
X642448Y35400D01*
X642573Y35440D01*
X642683Y35500D01*
X642783Y35580D01*
X642863Y35680D01*
X642923Y35790D01*
X642963Y35915D01*
X642973Y36040D01*
Y37170D01*
X643003Y37200D01*
X643103Y37340D01*
X643123Y37380D01*
X643138Y37415D01*
X643158Y37455D01*
X643173Y37495D01*
X643183Y37535D01*
X643198Y37580D01*
X643203Y37620D01*
X643213Y37660D01*
X643218Y37705D01*
Y37745D01*
X643223Y37790D01*
X643218Y37835D01*
Y37875D01*
X643213Y37920D01*
X643203Y37960D01*
X643198Y38000D01*
X643183Y38045D01*
X643173Y38085D01*
X643158Y38125D01*
X643138Y38165D01*
X643123Y38200D01*
X643103Y38240D01*
X643003Y38380D01*
X642973Y38410D01*
Y41840D01*
X642963Y41965D01*
X642923Y42090D01*
X642863Y42200D01*
X642783Y42300D01*
X642683Y42380D01*
X642573Y42440D01*
X642448Y42480D01*
X642323Y42490D01*
X642198Y42480D01*
X642073Y42440D01*
X641963Y42380D01*
X641863Y42300D01*
X641783Y42200D01*
X641723Y42090D01*
X641683Y41965D01*
X641673Y41840D01*
Y38410D01*
X641643Y38380D01*
X641543Y38240D01*
X641523Y38200D01*
X641508Y38165D01*
X641488Y38125D01*
X641473Y38085D01*
X641463Y38045D01*
X641448Y38000D01*
X641443Y37960D01*
X641433Y37920D01*
X641428Y37875D01*
Y37835D01*
X641423Y37790D01*
X641428Y37745D01*
Y37705D01*
X641433Y37660D01*
X641443Y37620D01*
X641448Y37580D01*
X641463Y37535D01*
X641473Y37495D01*
X641488Y37455D01*
X641508Y37415D01*
X641523Y37380D01*
X641543Y37340D01*
X641643Y37200D01*
X641673Y37170D01*
Y36040D01*
X641683Y35915D01*
X641723Y35790D01*
X641783Y35680D01*
X641863Y35580D01*
X641963Y35500D01*
X642073Y35440D01*
X642198Y35400D01*
X642323Y35390D01*
G37*
G36*
G01X637598D02*
X637723Y35400D01*
X637848Y35440D01*
X637958Y35500D01*
X638058Y35580D01*
X638138Y35680D01*
X638198Y35790D01*
X638238Y35915D01*
X638248Y36040D01*
Y37170D01*
X638278Y37200D01*
X638378Y37340D01*
X638398Y37380D01*
X638413Y37415D01*
X638433Y37455D01*
X638448Y37495D01*
X638458Y37535D01*
X638473Y37580D01*
X638478Y37620D01*
X638488Y37660D01*
X638493Y37705D01*
Y37745D01*
X638498Y37790D01*
X638493Y37835D01*
Y37875D01*
X638488Y37920D01*
X638478Y37960D01*
X638473Y38000D01*
X638458Y38045D01*
X638448Y38085D01*
X638433Y38125D01*
X638413Y38165D01*
X638398Y38200D01*
X638378Y38240D01*
X638278Y38380D01*
X638248Y38410D01*
Y41840D01*
X638238Y41965D01*
X638198Y42090D01*
X638138Y42200D01*
X638058Y42300D01*
X637958Y42380D01*
X637848Y42440D01*
X637723Y42480D01*
X637598Y42490D01*
X637473Y42480D01*
X637348Y42440D01*
X637238Y42380D01*
X637138Y42300D01*
X637058Y42200D01*
X636998Y42090D01*
X636958Y41965D01*
X636948Y41840D01*
Y38410D01*
X636918Y38380D01*
X636818Y38240D01*
X636798Y38200D01*
X636783Y38165D01*
X636763Y38125D01*
X636748Y38085D01*
X636738Y38045D01*
X636723Y38000D01*
X636718Y37960D01*
X636708Y37920D01*
X636703Y37875D01*
Y37835D01*
X636698Y37790D01*
X636703Y37745D01*
Y37705D01*
X636708Y37660D01*
X636718Y37620D01*
X636723Y37580D01*
X636738Y37535D01*
X636748Y37495D01*
X636763Y37455D01*
X636783Y37415D01*
X636798Y37380D01*
X636818Y37340D01*
X636918Y37200D01*
X636948Y37170D01*
Y36040D01*
X636958Y35915D01*
X636998Y35790D01*
X637058Y35680D01*
X637138Y35580D01*
X637238Y35500D01*
X637348Y35440D01*
X637473Y35400D01*
X637598Y35390D01*
G37*
G36*
G01X661220D02*
X661345Y35400D01*
X661470Y35440D01*
X661580Y35500D01*
X661680Y35580D01*
X661760Y35680D01*
X661820Y35790D01*
X661860Y35915D01*
X661870Y36040D01*
Y37170D01*
X661900Y37200D01*
X662000Y37340D01*
X662020Y37380D01*
X662035Y37415D01*
X662055Y37455D01*
X662070Y37495D01*
X662080Y37535D01*
X662095Y37580D01*
X662100Y37620D01*
X662110Y37660D01*
X662115Y37705D01*
Y37745D01*
X662120Y37790D01*
X662115Y37835D01*
Y37875D01*
X662110Y37920D01*
X662100Y37960D01*
X662095Y38000D01*
X662080Y38045D01*
X662070Y38085D01*
X662055Y38125D01*
X662035Y38165D01*
X662020Y38200D01*
X662000Y38240D01*
X661900Y38380D01*
X661870Y38410D01*
Y41840D01*
X661860Y41965D01*
X661820Y42090D01*
X661760Y42200D01*
X661680Y42300D01*
X661580Y42380D01*
X661470Y42440D01*
X661345Y42480D01*
X661220Y42490D01*
X661095Y42480D01*
X660970Y42440D01*
X660860Y42380D01*
X660760Y42300D01*
X660680Y42200D01*
X660620Y42090D01*
X660580Y41965D01*
X660570Y41840D01*
Y38410D01*
X660540Y38380D01*
X660440Y38240D01*
X660420Y38200D01*
X660405Y38165D01*
X660385Y38125D01*
X660370Y38085D01*
X660360Y38045D01*
X660345Y38000D01*
X660340Y37960D01*
X660330Y37920D01*
X660325Y37875D01*
Y37835D01*
X660320Y37790D01*
X660325Y37745D01*
Y37705D01*
X660330Y37660D01*
X660340Y37620D01*
X660345Y37580D01*
X660360Y37535D01*
X660370Y37495D01*
X660385Y37455D01*
X660405Y37415D01*
X660420Y37380D01*
X660440Y37340D01*
X660540Y37200D01*
X660570Y37170D01*
Y36040D01*
X660580Y35915D01*
X660620Y35790D01*
X660680Y35680D01*
X660760Y35580D01*
X660860Y35500D01*
X660970Y35440D01*
X661095Y35400D01*
X661220Y35390D01*
G37*
G36*
G01X656496D02*
X656621Y35400D01*
X656746Y35440D01*
X656856Y35500D01*
X656956Y35580D01*
X657036Y35680D01*
X657096Y35790D01*
X657136Y35915D01*
X657146Y36040D01*
Y37170D01*
X657176Y37200D01*
X657276Y37340D01*
X657296Y37380D01*
X657311Y37415D01*
X657331Y37455D01*
X657346Y37495D01*
X657356Y37535D01*
X657371Y37580D01*
X657376Y37620D01*
X657386Y37660D01*
X657391Y37705D01*
Y37745D01*
X657396Y37790D01*
X657391Y37835D01*
Y37875D01*
X657386Y37920D01*
X657376Y37960D01*
X657371Y38000D01*
X657356Y38045D01*
X657346Y38085D01*
X657331Y38125D01*
X657311Y38165D01*
X657296Y38200D01*
X657276Y38240D01*
X657176Y38380D01*
X657146Y38410D01*
Y41840D01*
X657136Y41965D01*
X657096Y42090D01*
X657036Y42200D01*
X656956Y42300D01*
X656856Y42380D01*
X656746Y42440D01*
X656621Y42480D01*
X656496Y42490D01*
X656371Y42480D01*
X656246Y42440D01*
X656136Y42380D01*
X656036Y42300D01*
X655956Y42200D01*
X655896Y42090D01*
X655856Y41965D01*
X655846Y41840D01*
Y38410D01*
X655816Y38380D01*
X655716Y38240D01*
X655696Y38200D01*
X655681Y38165D01*
X655661Y38125D01*
X655646Y38085D01*
X655636Y38045D01*
X655621Y38000D01*
X655616Y37960D01*
X655606Y37920D01*
X655601Y37875D01*
Y37835D01*
X655596Y37790D01*
X655601Y37745D01*
Y37705D01*
X655606Y37660D01*
X655616Y37620D01*
X655621Y37580D01*
X655636Y37535D01*
X655646Y37495D01*
X655661Y37455D01*
X655681Y37415D01*
X655696Y37380D01*
X655716Y37340D01*
X655816Y37200D01*
X655846Y37170D01*
Y36040D01*
X655856Y35915D01*
X655896Y35790D01*
X655956Y35680D01*
X656036Y35580D01*
X656136Y35500D01*
X656246Y35440D01*
X656371Y35400D01*
X656496Y35390D01*
G37*
G36*
G01X651771D02*
X651896Y35400D01*
X652021Y35440D01*
X652131Y35500D01*
X652231Y35580D01*
X652311Y35680D01*
X652371Y35790D01*
X652411Y35915D01*
X652421Y36040D01*
Y37170D01*
X652451Y37200D01*
X652551Y37340D01*
X652571Y37380D01*
X652586Y37415D01*
X652606Y37455D01*
X652621Y37495D01*
X652631Y37535D01*
X652646Y37580D01*
X652651Y37620D01*
X652661Y37660D01*
X652666Y37705D01*
Y37745D01*
X652671Y37790D01*
X652666Y37835D01*
Y37875D01*
X652661Y37920D01*
X652651Y37960D01*
X652646Y38000D01*
X652631Y38045D01*
X652621Y38085D01*
X652606Y38125D01*
X652586Y38165D01*
X652571Y38200D01*
X652551Y38240D01*
X652451Y38380D01*
X652421Y38410D01*
Y41840D01*
X652411Y41965D01*
X652371Y42090D01*
X652311Y42200D01*
X652231Y42300D01*
X652131Y42380D01*
X652021Y42440D01*
X651896Y42480D01*
X651771Y42490D01*
X651646Y42480D01*
X651521Y42440D01*
X651411Y42380D01*
X651311Y42300D01*
X651231Y42200D01*
X651171Y42090D01*
X651131Y41965D01*
X651121Y41840D01*
Y38410D01*
X651091Y38380D01*
X650991Y38240D01*
X650971Y38200D01*
X650956Y38165D01*
X650936Y38125D01*
X650921Y38085D01*
X650911Y38045D01*
X650896Y38000D01*
X650891Y37960D01*
X650881Y37920D01*
X650876Y37875D01*
Y37835D01*
X650871Y37790D01*
X650876Y37745D01*
Y37705D01*
X650881Y37660D01*
X650891Y37620D01*
X650896Y37580D01*
X650911Y37535D01*
X650921Y37495D01*
X650936Y37455D01*
X650956Y37415D01*
X650971Y37380D01*
X650991Y37340D01*
X651091Y37200D01*
X651121Y37170D01*
Y36040D01*
X651131Y35915D01*
X651171Y35790D01*
X651231Y35680D01*
X651311Y35580D01*
X651411Y35500D01*
X651521Y35440D01*
X651646Y35400D01*
X651771Y35390D01*
G37*
G36*
G01X680118D02*
X680243Y35400D01*
X680368Y35440D01*
X680478Y35500D01*
X680578Y35580D01*
X680658Y35680D01*
X680718Y35790D01*
X680758Y35915D01*
X680768Y36040D01*
Y37170D01*
X680798Y37200D01*
X680898Y37340D01*
X680918Y37380D01*
X680933Y37415D01*
X680953Y37455D01*
X680968Y37495D01*
X680978Y37535D01*
X680993Y37580D01*
X680998Y37620D01*
X681008Y37660D01*
X681013Y37705D01*
Y37745D01*
X681018Y37790D01*
X681013Y37835D01*
Y37875D01*
X681008Y37920D01*
X680998Y37960D01*
X680993Y38000D01*
X680978Y38045D01*
X680968Y38085D01*
X680953Y38125D01*
X680933Y38165D01*
X680918Y38200D01*
X680898Y38240D01*
X680798Y38380D01*
X680768Y38410D01*
Y41840D01*
X680758Y41965D01*
X680718Y42090D01*
X680658Y42200D01*
X680578Y42300D01*
X680478Y42380D01*
X680368Y42440D01*
X680243Y42480D01*
X680118Y42490D01*
X679993Y42480D01*
X679868Y42440D01*
X679758Y42380D01*
X679658Y42300D01*
X679578Y42200D01*
X679518Y42090D01*
X679478Y41965D01*
X679468Y41840D01*
Y38410D01*
X679438Y38380D01*
X679338Y38240D01*
X679318Y38200D01*
X679303Y38165D01*
X679283Y38125D01*
X679268Y38085D01*
X679258Y38045D01*
X679243Y38000D01*
X679238Y37960D01*
X679228Y37920D01*
X679223Y37875D01*
Y37835D01*
X679218Y37790D01*
X679223Y37745D01*
Y37705D01*
X679228Y37660D01*
X679238Y37620D01*
X679243Y37580D01*
X679258Y37535D01*
X679268Y37495D01*
X679283Y37455D01*
X679303Y37415D01*
X679318Y37380D01*
X679338Y37340D01*
X679438Y37200D01*
X679468Y37170D01*
Y36040D01*
X679478Y35915D01*
X679518Y35790D01*
X679578Y35680D01*
X679658Y35580D01*
X679758Y35500D01*
X679868Y35440D01*
X679993Y35400D01*
X680118Y35390D01*
G37*
G36*
G01X675393D02*
X675518Y35400D01*
X675643Y35440D01*
X675753Y35500D01*
X675853Y35580D01*
X675933Y35680D01*
X675993Y35790D01*
X676033Y35915D01*
X676043Y36040D01*
Y37170D01*
X676073Y37200D01*
X676173Y37340D01*
X676193Y37380D01*
X676208Y37415D01*
X676228Y37455D01*
X676243Y37495D01*
X676253Y37535D01*
X676268Y37580D01*
X676273Y37620D01*
X676283Y37660D01*
X676288Y37705D01*
Y37745D01*
X676293Y37790D01*
X676288Y37835D01*
Y37875D01*
X676283Y37920D01*
X676273Y37960D01*
X676268Y38000D01*
X676253Y38045D01*
X676243Y38085D01*
X676228Y38125D01*
X676208Y38165D01*
X676193Y38200D01*
X676173Y38240D01*
X676073Y38380D01*
X676043Y38410D01*
Y41840D01*
X676033Y41965D01*
X675993Y42090D01*
X675933Y42200D01*
X675853Y42300D01*
X675753Y42380D01*
X675643Y42440D01*
X675518Y42480D01*
X675393Y42490D01*
X675268Y42480D01*
X675143Y42440D01*
X675033Y42380D01*
X674933Y42300D01*
X674853Y42200D01*
X674793Y42090D01*
X674753Y41965D01*
X674743Y41840D01*
Y38410D01*
X674713Y38380D01*
X674613Y38240D01*
X674593Y38200D01*
X674578Y38165D01*
X674558Y38125D01*
X674543Y38085D01*
X674533Y38045D01*
X674518Y38000D01*
X674513Y37960D01*
X674503Y37920D01*
X674498Y37875D01*
Y37835D01*
X674493Y37790D01*
X674498Y37745D01*
Y37705D01*
X674503Y37660D01*
X674513Y37620D01*
X674518Y37580D01*
X674533Y37535D01*
X674543Y37495D01*
X674558Y37455D01*
X674578Y37415D01*
X674593Y37380D01*
X674613Y37340D01*
X674713Y37200D01*
X674743Y37170D01*
Y36040D01*
X674753Y35915D01*
X674793Y35790D01*
X674853Y35680D01*
X674933Y35580D01*
X675033Y35500D01*
X675143Y35440D01*
X675268Y35400D01*
X675393Y35390D01*
G37*
G36*
G01X670669D02*
X670794Y35400D01*
X670919Y35440D01*
X671029Y35500D01*
X671129Y35580D01*
X671209Y35680D01*
X671269Y35790D01*
X671309Y35915D01*
X671319Y36040D01*
Y37170D01*
X671349Y37200D01*
X671449Y37340D01*
X671469Y37380D01*
X671484Y37415D01*
X671504Y37455D01*
X671519Y37495D01*
X671529Y37535D01*
X671544Y37580D01*
X671549Y37620D01*
X671559Y37660D01*
X671564Y37705D01*
Y37745D01*
X671569Y37790D01*
X671564Y37835D01*
Y37875D01*
X671559Y37920D01*
X671549Y37960D01*
X671544Y38000D01*
X671529Y38045D01*
X671519Y38085D01*
X671504Y38125D01*
X671484Y38165D01*
X671469Y38200D01*
X671449Y38240D01*
X671349Y38380D01*
X671319Y38410D01*
Y41840D01*
X671309Y41965D01*
X671269Y42090D01*
X671209Y42200D01*
X671129Y42300D01*
X671029Y42380D01*
X670919Y42440D01*
X670794Y42480D01*
X670669Y42490D01*
X670544Y42480D01*
X670419Y42440D01*
X670309Y42380D01*
X670209Y42300D01*
X670129Y42200D01*
X670069Y42090D01*
X670029Y41965D01*
X670019Y41840D01*
Y38410D01*
X669989Y38380D01*
X669889Y38240D01*
X669869Y38200D01*
X669854Y38165D01*
X669834Y38125D01*
X669819Y38085D01*
X669809Y38045D01*
X669794Y38000D01*
X669789Y37960D01*
X669779Y37920D01*
X669774Y37875D01*
Y37835D01*
X669769Y37790D01*
X669774Y37745D01*
Y37705D01*
X669779Y37660D01*
X669789Y37620D01*
X669794Y37580D01*
X669809Y37535D01*
X669819Y37495D01*
X669834Y37455D01*
X669854Y37415D01*
X669869Y37380D01*
X669889Y37340D01*
X669989Y37200D01*
X670019Y37170D01*
Y36040D01*
X670029Y35915D01*
X670069Y35790D01*
X670129Y35680D01*
X670209Y35580D01*
X670309Y35500D01*
X670419Y35440D01*
X670544Y35400D01*
X670669Y35390D01*
G37*
G36*
G01X665945D02*
X666070Y35400D01*
X666195Y35440D01*
X666305Y35500D01*
X666405Y35580D01*
X666485Y35680D01*
X666545Y35790D01*
X666585Y35915D01*
X666595Y36040D01*
Y37170D01*
X666625Y37200D01*
X666725Y37340D01*
X666745Y37380D01*
X666760Y37415D01*
X666780Y37455D01*
X666795Y37495D01*
X666805Y37535D01*
X666820Y37580D01*
X666825Y37620D01*
X666835Y37660D01*
X666840Y37705D01*
Y37745D01*
X666845Y37790D01*
X666840Y37835D01*
Y37875D01*
X666835Y37920D01*
X666825Y37960D01*
X666820Y38000D01*
X666805Y38045D01*
X666795Y38085D01*
X666780Y38125D01*
X666760Y38165D01*
X666745Y38200D01*
X666725Y38240D01*
X666625Y38380D01*
X666595Y38410D01*
Y41840D01*
X666585Y41965D01*
X666545Y42090D01*
X666485Y42200D01*
X666405Y42300D01*
X666305Y42380D01*
X666195Y42440D01*
X666070Y42480D01*
X665945Y42490D01*
X665820Y42480D01*
X665695Y42440D01*
X665585Y42380D01*
X665485Y42300D01*
X665405Y42200D01*
X665345Y42090D01*
X665305Y41965D01*
X665295Y41840D01*
Y38410D01*
X665265Y38380D01*
X665165Y38240D01*
X665145Y38200D01*
X665130Y38165D01*
X665110Y38125D01*
X665095Y38085D01*
X665085Y38045D01*
X665070Y38000D01*
X665065Y37960D01*
X665055Y37920D01*
X665050Y37875D01*
Y37835D01*
X665045Y37790D01*
X665050Y37745D01*
Y37705D01*
X665055Y37660D01*
X665065Y37620D01*
X665070Y37580D01*
X665085Y37535D01*
X665095Y37495D01*
X665110Y37455D01*
X665130Y37415D01*
X665145Y37380D01*
X665165Y37340D01*
X665265Y37200D01*
X665295Y37170D01*
Y36040D01*
X665305Y35915D01*
X665345Y35790D01*
X665405Y35680D01*
X665485Y35580D01*
X665585Y35500D01*
X665695Y35440D01*
X665820Y35400D01*
X665945Y35390D01*
G37*
G36*
G01X694291D02*
X694416Y35400D01*
X694541Y35440D01*
X694651Y35500D01*
X694751Y35580D01*
X694831Y35680D01*
X694891Y35790D01*
X694931Y35915D01*
X694941Y36040D01*
Y37170D01*
X694971Y37200D01*
X695071Y37340D01*
X695091Y37380D01*
X695106Y37415D01*
X695126Y37455D01*
X695141Y37495D01*
X695151Y37535D01*
X695166Y37580D01*
X695171Y37620D01*
X695181Y37660D01*
X695186Y37705D01*
Y37745D01*
X695191Y37790D01*
X695186Y37835D01*
Y37875D01*
X695181Y37920D01*
X695171Y37960D01*
X695166Y38000D01*
X695151Y38045D01*
X695141Y38085D01*
X695126Y38125D01*
X695106Y38165D01*
X695091Y38200D01*
X695071Y38240D01*
X694971Y38380D01*
X694941Y38410D01*
Y41840D01*
X694931Y41965D01*
X694891Y42090D01*
X694831Y42200D01*
X694751Y42300D01*
X694651Y42380D01*
X694541Y42440D01*
X694416Y42480D01*
X694291Y42490D01*
X694166Y42480D01*
X694041Y42440D01*
X693931Y42380D01*
X693831Y42300D01*
X693751Y42200D01*
X693691Y42090D01*
X693651Y41965D01*
X693641Y41840D01*
Y38410D01*
X693611Y38380D01*
X693511Y38240D01*
X693491Y38200D01*
X693476Y38165D01*
X693456Y38125D01*
X693441Y38085D01*
X693431Y38045D01*
X693416Y38000D01*
X693411Y37960D01*
X693401Y37920D01*
X693396Y37875D01*
Y37835D01*
X693391Y37790D01*
X693396Y37745D01*
Y37705D01*
X693401Y37660D01*
X693411Y37620D01*
X693416Y37580D01*
X693431Y37535D01*
X693441Y37495D01*
X693456Y37455D01*
X693476Y37415D01*
X693491Y37380D01*
X693511Y37340D01*
X693611Y37200D01*
X693641Y37170D01*
Y36040D01*
X693651Y35915D01*
X693691Y35790D01*
X693751Y35680D01*
X693831Y35580D01*
X693931Y35500D01*
X694041Y35440D01*
X694166Y35400D01*
X694291Y35390D01*
G37*
G36*
G01X689567D02*
X689692Y35400D01*
X689817Y35440D01*
X689927Y35500D01*
X690027Y35580D01*
X690107Y35680D01*
X690167Y35790D01*
X690207Y35915D01*
X690217Y36040D01*
Y37170D01*
X690247Y37200D01*
X690347Y37340D01*
X690367Y37380D01*
X690382Y37415D01*
X690402Y37455D01*
X690417Y37495D01*
X690427Y37535D01*
X690442Y37580D01*
X690447Y37620D01*
X690457Y37660D01*
X690462Y37705D01*
Y37745D01*
X690467Y37790D01*
X690462Y37835D01*
Y37875D01*
X690457Y37920D01*
X690447Y37960D01*
X690442Y38000D01*
X690427Y38045D01*
X690417Y38085D01*
X690402Y38125D01*
X690382Y38165D01*
X690367Y38200D01*
X690347Y38240D01*
X690247Y38380D01*
X690217Y38410D01*
Y41840D01*
X690207Y41965D01*
X690167Y42090D01*
X690107Y42200D01*
X690027Y42300D01*
X689927Y42380D01*
X689817Y42440D01*
X689692Y42480D01*
X689567Y42490D01*
X689442Y42480D01*
X689317Y42440D01*
X689207Y42380D01*
X689107Y42300D01*
X689027Y42200D01*
X688967Y42090D01*
X688927Y41965D01*
X688917Y41840D01*
Y38410D01*
X688887Y38380D01*
X688787Y38240D01*
X688767Y38200D01*
X688752Y38165D01*
X688732Y38125D01*
X688717Y38085D01*
X688707Y38045D01*
X688692Y38000D01*
X688687Y37960D01*
X688677Y37920D01*
X688672Y37875D01*
Y37835D01*
X688667Y37790D01*
X688672Y37745D01*
Y37705D01*
X688677Y37660D01*
X688687Y37620D01*
X688692Y37580D01*
X688707Y37535D01*
X688717Y37495D01*
X688732Y37455D01*
X688752Y37415D01*
X688767Y37380D01*
X688787Y37340D01*
X688887Y37200D01*
X688917Y37170D01*
Y36040D01*
X688927Y35915D01*
X688967Y35790D01*
X689027Y35680D01*
X689107Y35580D01*
X689207Y35500D01*
X689317Y35440D01*
X689442Y35400D01*
X689567Y35390D01*
G37*
G36*
G01X684842D02*
X684967Y35400D01*
X685092Y35440D01*
X685202Y35500D01*
X685302Y35580D01*
X685382Y35680D01*
X685442Y35790D01*
X685482Y35915D01*
X685492Y36040D01*
Y37170D01*
X685522Y37200D01*
X685622Y37340D01*
X685642Y37380D01*
X685657Y37415D01*
X685677Y37455D01*
X685692Y37495D01*
X685702Y37535D01*
X685717Y37580D01*
X685722Y37620D01*
X685732Y37660D01*
X685737Y37705D01*
Y37745D01*
X685742Y37790D01*
X685737Y37835D01*
Y37875D01*
X685732Y37920D01*
X685722Y37960D01*
X685717Y38000D01*
X685702Y38045D01*
X685692Y38085D01*
X685677Y38125D01*
X685657Y38165D01*
X685642Y38200D01*
X685622Y38240D01*
X685522Y38380D01*
X685492Y38410D01*
Y41840D01*
X685482Y41965D01*
X685442Y42090D01*
X685382Y42200D01*
X685302Y42300D01*
X685202Y42380D01*
X685092Y42440D01*
X684967Y42480D01*
X684842Y42490D01*
X684717Y42480D01*
X684592Y42440D01*
X684482Y42380D01*
X684382Y42300D01*
X684302Y42200D01*
X684242Y42090D01*
X684202Y41965D01*
X684192Y41840D01*
Y38410D01*
X684162Y38380D01*
X684062Y38240D01*
X684042Y38200D01*
X684027Y38165D01*
X684007Y38125D01*
X683992Y38085D01*
X683982Y38045D01*
X683967Y38000D01*
X683962Y37960D01*
X683952Y37920D01*
X683947Y37875D01*
Y37835D01*
X683942Y37790D01*
X683947Y37745D01*
Y37705D01*
X683952Y37660D01*
X683962Y37620D01*
X683967Y37580D01*
X683982Y37535D01*
X683992Y37495D01*
X684007Y37455D01*
X684027Y37415D01*
X684042Y37380D01*
X684062Y37340D01*
X684162Y37200D01*
X684192Y37170D01*
Y36040D01*
X684202Y35915D01*
X684242Y35790D01*
X684302Y35680D01*
X684382Y35580D01*
X684482Y35500D01*
X684592Y35440D01*
X684717Y35400D01*
X684842Y35390D01*
G37*
G36*
G01X708464D02*
X708589Y35400D01*
X708714Y35440D01*
X708824Y35500D01*
X708924Y35580D01*
X709004Y35680D01*
X709064Y35790D01*
X709104Y35915D01*
X709114Y36040D01*
Y37170D01*
X709144Y37200D01*
X709244Y37340D01*
X709264Y37380D01*
X709279Y37415D01*
X709299Y37455D01*
X709314Y37495D01*
X709324Y37535D01*
X709339Y37580D01*
X709344Y37620D01*
X709354Y37660D01*
X709359Y37705D01*
Y37745D01*
X709364Y37790D01*
X709359Y37835D01*
Y37875D01*
X709354Y37920D01*
X709344Y37960D01*
X709339Y38000D01*
X709324Y38045D01*
X709314Y38085D01*
X709299Y38125D01*
X709279Y38165D01*
X709264Y38200D01*
X709244Y38240D01*
X709144Y38380D01*
X709114Y38410D01*
Y41840D01*
X709104Y41965D01*
X709064Y42090D01*
X709004Y42200D01*
X708924Y42300D01*
X708824Y42380D01*
X708714Y42440D01*
X708589Y42480D01*
X708464Y42490D01*
X708339Y42480D01*
X708214Y42440D01*
X708104Y42380D01*
X708004Y42300D01*
X707924Y42200D01*
X707864Y42090D01*
X707824Y41965D01*
X707814Y41840D01*
Y38410D01*
X707784Y38380D01*
X707684Y38240D01*
X707664Y38200D01*
X707649Y38165D01*
X707629Y38125D01*
X707614Y38085D01*
X707604Y38045D01*
X707589Y38000D01*
X707584Y37960D01*
X707574Y37920D01*
X707569Y37875D01*
Y37835D01*
X707564Y37790D01*
X707569Y37745D01*
Y37705D01*
X707574Y37660D01*
X707584Y37620D01*
X707589Y37580D01*
X707604Y37535D01*
X707614Y37495D01*
X707629Y37455D01*
X707649Y37415D01*
X707664Y37380D01*
X707684Y37340D01*
X707784Y37200D01*
X707814Y37170D01*
Y36040D01*
X707824Y35915D01*
X707864Y35790D01*
X707924Y35680D01*
X708004Y35580D01*
X708104Y35500D01*
X708214Y35440D01*
X708339Y35400D01*
X708464Y35390D01*
G37*
G36*
G01X703740D02*
X703865Y35400D01*
X703990Y35440D01*
X704100Y35500D01*
X704200Y35580D01*
X704280Y35680D01*
X704340Y35790D01*
X704380Y35915D01*
X704390Y36040D01*
Y37170D01*
X704420Y37200D01*
X704520Y37340D01*
X704540Y37380D01*
X704555Y37415D01*
X704575Y37455D01*
X704590Y37495D01*
X704600Y37535D01*
X704615Y37580D01*
X704620Y37620D01*
X704630Y37660D01*
X704635Y37705D01*
Y37745D01*
X704640Y37790D01*
X704635Y37835D01*
Y37875D01*
X704630Y37920D01*
X704620Y37960D01*
X704615Y38000D01*
X704600Y38045D01*
X704590Y38085D01*
X704575Y38125D01*
X704555Y38165D01*
X704540Y38200D01*
X704520Y38240D01*
X704420Y38380D01*
X704390Y38410D01*
Y41840D01*
X704380Y41965D01*
X704340Y42090D01*
X704280Y42200D01*
X704200Y42300D01*
X704100Y42380D01*
X703990Y42440D01*
X703865Y42480D01*
X703740Y42490D01*
X703615Y42480D01*
X703490Y42440D01*
X703380Y42380D01*
X703280Y42300D01*
X703200Y42200D01*
X703140Y42090D01*
X703100Y41965D01*
X703090Y41840D01*
Y38410D01*
X703060Y38380D01*
X702960Y38240D01*
X702940Y38200D01*
X702925Y38165D01*
X702905Y38125D01*
X702890Y38085D01*
X702880Y38045D01*
X702865Y38000D01*
X702860Y37960D01*
X702850Y37920D01*
X702845Y37875D01*
Y37835D01*
X702840Y37790D01*
X702845Y37745D01*
Y37705D01*
X702850Y37660D01*
X702860Y37620D01*
X702865Y37580D01*
X702880Y37535D01*
X702890Y37495D01*
X702905Y37455D01*
X702925Y37415D01*
X702940Y37380D01*
X702960Y37340D01*
X703060Y37200D01*
X703090Y37170D01*
Y36040D01*
X703100Y35915D01*
X703140Y35790D01*
X703200Y35680D01*
X703280Y35580D01*
X703380Y35500D01*
X703490Y35440D01*
X703615Y35400D01*
X703740Y35390D01*
G37*
G36*
G01X699015D02*
X699140Y35400D01*
X699265Y35440D01*
X699375Y35500D01*
X699475Y35580D01*
X699555Y35680D01*
X699615Y35790D01*
X699655Y35915D01*
X699665Y36040D01*
Y37170D01*
X699695Y37200D01*
X699795Y37340D01*
X699815Y37380D01*
X699830Y37415D01*
X699850Y37455D01*
X699865Y37495D01*
X699875Y37535D01*
X699890Y37580D01*
X699895Y37620D01*
X699905Y37660D01*
X699910Y37705D01*
Y37745D01*
X699915Y37790D01*
X699910Y37835D01*
Y37875D01*
X699905Y37920D01*
X699895Y37960D01*
X699890Y38000D01*
X699875Y38045D01*
X699865Y38085D01*
X699850Y38125D01*
X699830Y38165D01*
X699815Y38200D01*
X699795Y38240D01*
X699695Y38380D01*
X699665Y38410D01*
Y41840D01*
X699655Y41965D01*
X699615Y42090D01*
X699555Y42200D01*
X699475Y42300D01*
X699375Y42380D01*
X699265Y42440D01*
X699140Y42480D01*
X699015Y42490D01*
X698890Y42480D01*
X698765Y42440D01*
X698655Y42380D01*
X698555Y42300D01*
X698475Y42200D01*
X698415Y42090D01*
X698375Y41965D01*
X698365Y41840D01*
Y38410D01*
X698335Y38380D01*
X698235Y38240D01*
X698215Y38200D01*
X698200Y38165D01*
X698180Y38125D01*
X698165Y38085D01*
X698155Y38045D01*
X698140Y38000D01*
X698135Y37960D01*
X698125Y37920D01*
X698120Y37875D01*
Y37835D01*
X698115Y37790D01*
X698120Y37745D01*
Y37705D01*
X698125Y37660D01*
X698135Y37620D01*
X698140Y37580D01*
X698155Y37535D01*
X698165Y37495D01*
X698180Y37455D01*
X698200Y37415D01*
X698215Y37380D01*
X698235Y37340D01*
X698335Y37200D01*
X698365Y37170D01*
Y36040D01*
X698375Y35915D01*
X698415Y35790D01*
X698475Y35680D01*
X698555Y35580D01*
X698655Y35500D01*
X698765Y35440D01*
X698890Y35400D01*
X699015Y35390D01*
G37*
G36*
G01X722638D02*
X722763Y35400D01*
X722888Y35440D01*
X722998Y35500D01*
X723098Y35580D01*
X723178Y35680D01*
X723238Y35790D01*
X723278Y35915D01*
X723288Y36040D01*
Y37170D01*
X723318Y37200D01*
X723418Y37340D01*
X723438Y37380D01*
X723453Y37415D01*
X723473Y37455D01*
X723488Y37495D01*
X723498Y37535D01*
X723513Y37580D01*
X723518Y37620D01*
X723528Y37660D01*
X723533Y37705D01*
Y37745D01*
X723538Y37790D01*
X723533Y37835D01*
Y37875D01*
X723528Y37920D01*
X723518Y37960D01*
X723513Y38000D01*
X723498Y38045D01*
X723488Y38085D01*
X723473Y38125D01*
X723453Y38165D01*
X723438Y38200D01*
X723418Y38240D01*
X723318Y38380D01*
X723288Y38410D01*
Y41840D01*
X723278Y41965D01*
X723238Y42090D01*
X723178Y42200D01*
X723098Y42300D01*
X722998Y42380D01*
X722888Y42440D01*
X722763Y42480D01*
X722638Y42490D01*
X722513Y42480D01*
X722388Y42440D01*
X722278Y42380D01*
X722178Y42300D01*
X722098Y42200D01*
X722038Y42090D01*
X721998Y41965D01*
X721988Y41840D01*
Y38410D01*
X721958Y38380D01*
X721858Y38240D01*
X721838Y38200D01*
X721823Y38165D01*
X721803Y38125D01*
X721788Y38085D01*
X721778Y38045D01*
X721763Y38000D01*
X721758Y37960D01*
X721748Y37920D01*
X721743Y37875D01*
Y37835D01*
X721738Y37790D01*
X721743Y37745D01*
Y37705D01*
X721748Y37660D01*
X721758Y37620D01*
X721763Y37580D01*
X721778Y37535D01*
X721788Y37495D01*
X721803Y37455D01*
X721823Y37415D01*
X721838Y37380D01*
X721858Y37340D01*
X721958Y37200D01*
X721988Y37170D01*
Y36040D01*
X721998Y35915D01*
X722038Y35790D01*
X722098Y35680D01*
X722178Y35580D01*
X722278Y35500D01*
X722388Y35440D01*
X722513Y35400D01*
X722638Y35390D01*
G37*
G36*
G01X717913D02*
X718038Y35400D01*
X718163Y35440D01*
X718273Y35500D01*
X718373Y35580D01*
X718453Y35680D01*
X718513Y35790D01*
X718553Y35915D01*
X718563Y36040D01*
Y37170D01*
X718593Y37200D01*
X718693Y37340D01*
X718713Y37380D01*
X718728Y37415D01*
X718748Y37455D01*
X718763Y37495D01*
X718773Y37535D01*
X718788Y37580D01*
X718793Y37620D01*
X718803Y37660D01*
X718808Y37705D01*
Y37745D01*
X718813Y37790D01*
X718808Y37835D01*
Y37875D01*
X718803Y37920D01*
X718793Y37960D01*
X718788Y38000D01*
X718773Y38045D01*
X718763Y38085D01*
X718748Y38125D01*
X718728Y38165D01*
X718713Y38200D01*
X718693Y38240D01*
X718593Y38380D01*
X718563Y38410D01*
Y41840D01*
X718553Y41965D01*
X718513Y42090D01*
X718453Y42200D01*
X718373Y42300D01*
X718273Y42380D01*
X718163Y42440D01*
X718038Y42480D01*
X717913Y42490D01*
X717788Y42480D01*
X717663Y42440D01*
X717553Y42380D01*
X717453Y42300D01*
X717373Y42200D01*
X717313Y42090D01*
X717273Y41965D01*
X717263Y41840D01*
Y38410D01*
X717233Y38380D01*
X717133Y38240D01*
X717113Y38200D01*
X717098Y38165D01*
X717078Y38125D01*
X717063Y38085D01*
X717053Y38045D01*
X717038Y38000D01*
X717033Y37960D01*
X717023Y37920D01*
X717018Y37875D01*
Y37835D01*
X717013Y37790D01*
X717018Y37745D01*
Y37705D01*
X717023Y37660D01*
X717033Y37620D01*
X717038Y37580D01*
X717053Y37535D01*
X717063Y37495D01*
X717078Y37455D01*
X717098Y37415D01*
X717113Y37380D01*
X717133Y37340D01*
X717233Y37200D01*
X717263Y37170D01*
Y36040D01*
X717273Y35915D01*
X717313Y35790D01*
X717373Y35680D01*
X717453Y35580D01*
X717553Y35500D01*
X717663Y35440D01*
X717788Y35400D01*
X717913Y35390D01*
G37*
G36*
G01X713189D02*
X713314Y35400D01*
X713439Y35440D01*
X713549Y35500D01*
X713649Y35580D01*
X713729Y35680D01*
X713789Y35790D01*
X713829Y35915D01*
X713839Y36040D01*
Y37170D01*
X713869Y37200D01*
X713969Y37340D01*
X713989Y37380D01*
X714004Y37415D01*
X714024Y37455D01*
X714039Y37495D01*
X714049Y37535D01*
X714064Y37580D01*
X714069Y37620D01*
X714079Y37660D01*
X714084Y37705D01*
Y37745D01*
X714089Y37790D01*
X714084Y37835D01*
Y37875D01*
X714079Y37920D01*
X714069Y37960D01*
X714064Y38000D01*
X714049Y38045D01*
X714039Y38085D01*
X714024Y38125D01*
X714004Y38165D01*
X713989Y38200D01*
X713969Y38240D01*
X713869Y38380D01*
X713839Y38410D01*
Y41840D01*
X713829Y41965D01*
X713789Y42090D01*
X713729Y42200D01*
X713649Y42300D01*
X713549Y42380D01*
X713439Y42440D01*
X713314Y42480D01*
X713189Y42490D01*
X713064Y42480D01*
X712939Y42440D01*
X712829Y42380D01*
X712729Y42300D01*
X712649Y42200D01*
X712589Y42090D01*
X712549Y41965D01*
X712539Y41840D01*
Y38410D01*
X712509Y38380D01*
X712409Y38240D01*
X712389Y38200D01*
X712374Y38165D01*
X712354Y38125D01*
X712339Y38085D01*
X712329Y38045D01*
X712314Y38000D01*
X712309Y37960D01*
X712299Y37920D01*
X712294Y37875D01*
Y37835D01*
X712289Y37790D01*
X712294Y37745D01*
Y37705D01*
X712299Y37660D01*
X712309Y37620D01*
X712314Y37580D01*
X712329Y37535D01*
X712339Y37495D01*
X712354Y37455D01*
X712374Y37415D01*
X712389Y37380D01*
X712409Y37340D01*
X712509Y37200D01*
X712539Y37170D01*
Y36040D01*
X712549Y35915D01*
X712589Y35790D01*
X712649Y35680D01*
X712729Y35580D01*
X712829Y35500D01*
X712939Y35440D01*
X713064Y35400D01*
X713189Y35390D01*
G37*
G36*
G01X741535D02*
X741660Y35400D01*
X741785Y35440D01*
X741895Y35500D01*
X741995Y35580D01*
X742075Y35680D01*
X742135Y35790D01*
X742175Y35915D01*
X742185Y36040D01*
Y37170D01*
X742215Y37200D01*
X742315Y37340D01*
X742335Y37380D01*
X742350Y37415D01*
X742370Y37455D01*
X742385Y37495D01*
X742395Y37535D01*
X742410Y37580D01*
X742415Y37620D01*
X742425Y37660D01*
X742430Y37705D01*
Y37745D01*
X742435Y37790D01*
X742430Y37835D01*
Y37875D01*
X742425Y37920D01*
X742415Y37960D01*
X742410Y38000D01*
X742395Y38045D01*
X742385Y38085D01*
X742370Y38125D01*
X742350Y38165D01*
X742335Y38200D01*
X742315Y38240D01*
X742215Y38380D01*
X742185Y38410D01*
Y41840D01*
X742175Y41965D01*
X742135Y42090D01*
X742075Y42200D01*
X741995Y42300D01*
X741895Y42380D01*
X741785Y42440D01*
X741660Y42480D01*
X741535Y42490D01*
X741410Y42480D01*
X741285Y42440D01*
X741175Y42380D01*
X741075Y42300D01*
X740995Y42200D01*
X740935Y42090D01*
X740895Y41965D01*
X740885Y41840D01*
Y38410D01*
X740855Y38380D01*
X740755Y38240D01*
X740735Y38200D01*
X740720Y38165D01*
X740700Y38125D01*
X740685Y38085D01*
X740675Y38045D01*
X740660Y38000D01*
X740655Y37960D01*
X740645Y37920D01*
X740640Y37875D01*
Y37835D01*
X740635Y37790D01*
X740640Y37745D01*
Y37705D01*
X740645Y37660D01*
X740655Y37620D01*
X740660Y37580D01*
X740675Y37535D01*
X740685Y37495D01*
X740700Y37455D01*
X740720Y37415D01*
X740735Y37380D01*
X740755Y37340D01*
X740855Y37200D01*
X740885Y37170D01*
Y36040D01*
X740895Y35915D01*
X740935Y35790D01*
X740995Y35680D01*
X741075Y35580D01*
X741175Y35500D01*
X741285Y35440D01*
X741410Y35400D01*
X741535Y35390D01*
G37*
G36*
G01X736811D02*
X736936Y35400D01*
X737061Y35440D01*
X737171Y35500D01*
X737271Y35580D01*
X737351Y35680D01*
X737411Y35790D01*
X737451Y35915D01*
X737461Y36040D01*
Y37170D01*
X737491Y37200D01*
X737591Y37340D01*
X737611Y37380D01*
X737626Y37415D01*
X737646Y37455D01*
X737661Y37495D01*
X737671Y37535D01*
X737686Y37580D01*
X737691Y37620D01*
X737701Y37660D01*
X737706Y37705D01*
Y37745D01*
X737711Y37790D01*
X737706Y37835D01*
Y37875D01*
X737701Y37920D01*
X737691Y37960D01*
X737686Y38000D01*
X737671Y38045D01*
X737661Y38085D01*
X737646Y38125D01*
X737626Y38165D01*
X737611Y38200D01*
X737591Y38240D01*
X737491Y38380D01*
X737461Y38410D01*
Y41840D01*
X737451Y41965D01*
X737411Y42090D01*
X737351Y42200D01*
X737271Y42300D01*
X737171Y42380D01*
X737061Y42440D01*
X736936Y42480D01*
X736811Y42490D01*
X736686Y42480D01*
X736561Y42440D01*
X736451Y42380D01*
X736351Y42300D01*
X736271Y42200D01*
X736211Y42090D01*
X736171Y41965D01*
X736161Y41840D01*
Y38410D01*
X736131Y38380D01*
X736031Y38240D01*
X736011Y38200D01*
X735996Y38165D01*
X735976Y38125D01*
X735961Y38085D01*
X735951Y38045D01*
X735936Y38000D01*
X735931Y37960D01*
X735921Y37920D01*
X735916Y37875D01*
Y37835D01*
X735911Y37790D01*
X735916Y37745D01*
Y37705D01*
X735921Y37660D01*
X735931Y37620D01*
X735936Y37580D01*
X735951Y37535D01*
X735961Y37495D01*
X735976Y37455D01*
X735996Y37415D01*
X736011Y37380D01*
X736031Y37340D01*
X736131Y37200D01*
X736161Y37170D01*
Y36040D01*
X736171Y35915D01*
X736211Y35790D01*
X736271Y35680D01*
X736351Y35580D01*
X736451Y35500D01*
X736561Y35440D01*
X736686Y35400D01*
X736811Y35390D01*
G37*
G36*
G01X732086D02*
X732211Y35400D01*
X732336Y35440D01*
X732446Y35500D01*
X732546Y35580D01*
X732626Y35680D01*
X732686Y35790D01*
X732726Y35915D01*
X732736Y36040D01*
Y37170D01*
X732766Y37200D01*
X732866Y37340D01*
X732886Y37380D01*
X732901Y37415D01*
X732921Y37455D01*
X732936Y37495D01*
X732946Y37535D01*
X732961Y37580D01*
X732966Y37620D01*
X732976Y37660D01*
X732981Y37705D01*
Y37745D01*
X732986Y37790D01*
X732981Y37835D01*
Y37875D01*
X732976Y37920D01*
X732966Y37960D01*
X732961Y38000D01*
X732946Y38045D01*
X732936Y38085D01*
X732921Y38125D01*
X732901Y38165D01*
X732886Y38200D01*
X732866Y38240D01*
X732766Y38380D01*
X732736Y38410D01*
Y41840D01*
X732726Y41965D01*
X732686Y42090D01*
X732626Y42200D01*
X732546Y42300D01*
X732446Y42380D01*
X732336Y42440D01*
X732211Y42480D01*
X732086Y42490D01*
X731961Y42480D01*
X731836Y42440D01*
X731726Y42380D01*
X731626Y42300D01*
X731546Y42200D01*
X731486Y42090D01*
X731446Y41965D01*
X731436Y41840D01*
Y38410D01*
X731406Y38380D01*
X731306Y38240D01*
X731286Y38200D01*
X731271Y38165D01*
X731251Y38125D01*
X731236Y38085D01*
X731226Y38045D01*
X731211Y38000D01*
X731206Y37960D01*
X731196Y37920D01*
X731191Y37875D01*
Y37835D01*
X731186Y37790D01*
X731191Y37745D01*
Y37705D01*
X731196Y37660D01*
X731206Y37620D01*
X731211Y37580D01*
X731226Y37535D01*
X731236Y37495D01*
X731251Y37455D01*
X731271Y37415D01*
X731286Y37380D01*
X731306Y37340D01*
X731406Y37200D01*
X731436Y37170D01*
Y36040D01*
X731446Y35915D01*
X731486Y35790D01*
X731546Y35680D01*
X731626Y35580D01*
X731726Y35500D01*
X731836Y35440D01*
X731961Y35400D01*
X732086Y35390D01*
G37*
G36*
G01X727362D02*
X727487Y35400D01*
X727612Y35440D01*
X727722Y35500D01*
X727822Y35580D01*
X727902Y35680D01*
X727962Y35790D01*
X728002Y35915D01*
X728012Y36040D01*
Y37170D01*
X728042Y37200D01*
X728142Y37340D01*
X728162Y37380D01*
X728177Y37415D01*
X728197Y37455D01*
X728212Y37495D01*
X728222Y37535D01*
X728237Y37580D01*
X728242Y37620D01*
X728252Y37660D01*
X728257Y37705D01*
Y37745D01*
X728262Y37790D01*
X728257Y37835D01*
Y37875D01*
X728252Y37920D01*
X728242Y37960D01*
X728237Y38000D01*
X728222Y38045D01*
X728212Y38085D01*
X728197Y38125D01*
X728177Y38165D01*
X728162Y38200D01*
X728142Y38240D01*
X728042Y38380D01*
X728012Y38410D01*
Y41840D01*
X728002Y41965D01*
X727962Y42090D01*
X727902Y42200D01*
X727822Y42300D01*
X727722Y42380D01*
X727612Y42440D01*
X727487Y42480D01*
X727362Y42490D01*
X727237Y42480D01*
X727112Y42440D01*
X727002Y42380D01*
X726902Y42300D01*
X726822Y42200D01*
X726762Y42090D01*
X726722Y41965D01*
X726712Y41840D01*
Y38410D01*
X726682Y38380D01*
X726582Y38240D01*
X726562Y38200D01*
X726547Y38165D01*
X726527Y38125D01*
X726512Y38085D01*
X726502Y38045D01*
X726487Y38000D01*
X726482Y37960D01*
X726472Y37920D01*
X726467Y37875D01*
Y37835D01*
X726462Y37790D01*
X726467Y37745D01*
Y37705D01*
X726472Y37660D01*
X726482Y37620D01*
X726487Y37580D01*
X726502Y37535D01*
X726512Y37495D01*
X726527Y37455D01*
X726547Y37415D01*
X726562Y37380D01*
X726582Y37340D01*
X726682Y37200D01*
X726712Y37170D01*
Y36040D01*
X726722Y35915D01*
X726762Y35790D01*
X726822Y35680D01*
X726902Y35580D01*
X727002Y35500D01*
X727112Y35440D01*
X727237Y35400D01*
X727362Y35390D01*
G37*
G36*
G01X750984D02*
X751109Y35400D01*
X751234Y35440D01*
X751344Y35500D01*
X751444Y35580D01*
X751524Y35680D01*
X751584Y35790D01*
X751624Y35915D01*
X751634Y36040D01*
Y37170D01*
X751664Y37200D01*
X751764Y37340D01*
X751784Y37380D01*
X751799Y37415D01*
X751819Y37455D01*
X751834Y37495D01*
X751844Y37535D01*
X751859Y37580D01*
X751864Y37620D01*
X751874Y37660D01*
X751879Y37705D01*
Y37745D01*
X751884Y37790D01*
X751879Y37835D01*
Y37875D01*
X751874Y37920D01*
X751864Y37960D01*
X751859Y38000D01*
X751844Y38045D01*
X751834Y38085D01*
X751819Y38125D01*
X751799Y38165D01*
X751784Y38200D01*
X751764Y38240D01*
X751664Y38380D01*
X751634Y38410D01*
Y41840D01*
X751624Y41965D01*
X751584Y42090D01*
X751524Y42200D01*
X751444Y42300D01*
X751344Y42380D01*
X751234Y42440D01*
X751109Y42480D01*
X750984Y42490D01*
X750859Y42480D01*
X750734Y42440D01*
X750624Y42380D01*
X750524Y42300D01*
X750444Y42200D01*
X750384Y42090D01*
X750344Y41965D01*
X750334Y41840D01*
Y38410D01*
X750304Y38380D01*
X750204Y38240D01*
X750184Y38200D01*
X750169Y38165D01*
X750149Y38125D01*
X750134Y38085D01*
X750124Y38045D01*
X750109Y38000D01*
X750104Y37960D01*
X750094Y37920D01*
X750089Y37875D01*
Y37835D01*
X750084Y37790D01*
X750089Y37745D01*
Y37705D01*
X750094Y37660D01*
X750104Y37620D01*
X750109Y37580D01*
X750124Y37535D01*
X750134Y37495D01*
X750149Y37455D01*
X750169Y37415D01*
X750184Y37380D01*
X750204Y37340D01*
X750304Y37200D01*
X750334Y37170D01*
Y36040D01*
X750344Y35915D01*
X750384Y35790D01*
X750444Y35680D01*
X750524Y35580D01*
X750624Y35500D01*
X750734Y35440D01*
X750859Y35400D01*
X750984Y35390D01*
G37*
G36*
G01X746260D02*
X746385Y35400D01*
X746510Y35440D01*
X746620Y35500D01*
X746720Y35580D01*
X746800Y35680D01*
X746860Y35790D01*
X746900Y35915D01*
X746910Y36040D01*
Y37170D01*
X746940Y37200D01*
X747040Y37340D01*
X747060Y37380D01*
X747075Y37415D01*
X747095Y37455D01*
X747110Y37495D01*
X747120Y37535D01*
X747135Y37580D01*
X747140Y37620D01*
X747150Y37660D01*
X747155Y37705D01*
Y37745D01*
X747160Y37790D01*
X747155Y37835D01*
Y37875D01*
X747150Y37920D01*
X747140Y37960D01*
X747135Y38000D01*
X747120Y38045D01*
X747110Y38085D01*
X747095Y38125D01*
X747075Y38165D01*
X747060Y38200D01*
X747040Y38240D01*
X746940Y38380D01*
X746910Y38410D01*
Y41840D01*
X746900Y41965D01*
X746860Y42090D01*
X746800Y42200D01*
X746720Y42300D01*
X746620Y42380D01*
X746510Y42440D01*
X746385Y42480D01*
X746260Y42490D01*
X746135Y42480D01*
X746010Y42440D01*
X745900Y42380D01*
X745800Y42300D01*
X745720Y42200D01*
X745660Y42090D01*
X745620Y41965D01*
X745610Y41840D01*
Y38410D01*
X745580Y38380D01*
X745480Y38240D01*
X745460Y38200D01*
X745445Y38165D01*
X745425Y38125D01*
X745410Y38085D01*
X745400Y38045D01*
X745385Y38000D01*
X745380Y37960D01*
X745370Y37920D01*
X745365Y37875D01*
Y37835D01*
X745360Y37790D01*
X745365Y37745D01*
Y37705D01*
X745370Y37660D01*
X745380Y37620D01*
X745385Y37580D01*
X745400Y37535D01*
X745410Y37495D01*
X745425Y37455D01*
X745445Y37415D01*
X745460Y37380D01*
X745480Y37340D01*
X745580Y37200D01*
X745610Y37170D01*
Y36040D01*
X745620Y35915D01*
X745660Y35790D01*
X745720Y35680D01*
X745800Y35580D01*
X745900Y35500D01*
X746010Y35440D01*
X746135Y35400D01*
X746260Y35390D01*
G37*
G54D27*
X64370Y26342D03*
G54D73*
X429500Y255413D03*
Y269587D03*
G54D28*
X60500Y120200D03*
Y126800D03*
X109500Y166200D03*
Y172800D03*
X117000Y166200D03*
Y172800D03*
X292700Y75100D03*
Y81700D03*
X339500Y56200D03*
Y62800D03*
X347000Y56200D03*
Y62800D03*
X357000Y271300D03*
Y264700D03*
X369500Y52200D03*
Y58800D03*
X377000Y52200D03*
Y58800D03*
X439900Y175700D03*
Y182300D03*
X447000Y175700D03*
Y182300D03*
X449500Y269800D03*
Y263200D03*
X589500Y230200D03*
X582000D03*
X589500Y236800D03*
X582000D03*
X615900Y47207D03*
Y53807D03*
X608800Y47207D03*
Y53807D03*
X634500Y230200D03*
Y236800D03*
X642000Y230200D03*
Y236800D03*
X676700Y47407D03*
Y54007D03*
X669600Y47407D03*
Y54007D03*
X767500Y122200D03*
Y128800D03*
X803200Y179500D03*
Y172900D03*
G36*
G01X500591Y250006D02*
X500466Y249996D01*
X500341Y249956D01*
X500231Y249896D01*
X500131Y249816D01*
X500051Y249716D01*
X499991Y249606D01*
X499951Y249481D01*
X499941Y249356D01*
Y247231D01*
X499911Y247201D01*
X499886Y247166D01*
X499856Y247131D01*
X499836Y247096D01*
X499811Y247061D01*
X499771Y246981D01*
X499726Y246861D01*
X499716Y246821D01*
X499706Y246776D01*
X499701Y246736D01*
X499691Y246691D01*
Y246521D01*
X499701Y246476D01*
X499706Y246436D01*
X499716Y246391D01*
X499726Y246351D01*
X499771Y246231D01*
X499811Y246151D01*
X499836Y246116D01*
X499856Y246081D01*
X499886Y246046D01*
X499911Y246011D01*
X499941Y245981D01*
Y243556D01*
X499951Y243431D01*
X499991Y243306D01*
X500051Y243196D01*
X500131Y243096D01*
X500231Y243016D01*
X500341Y242956D01*
X500466Y242916D01*
X500591Y242906D01*
X500716Y242916D01*
X500841Y242956D01*
X500951Y243016D01*
X501051Y243096D01*
X501131Y243196D01*
X501191Y243306D01*
X501231Y243431D01*
X501241Y243556D01*
Y245986D01*
X501271Y246016D01*
X501371Y246156D01*
X501391Y246196D01*
X501406Y246231D01*
X501426Y246271D01*
X501441Y246311D01*
X501451Y246351D01*
X501466Y246396D01*
X501471Y246436D01*
X501481Y246476D01*
X501486Y246521D01*
Y246561D01*
X501491Y246606D01*
X501486Y246651D01*
Y246691D01*
X501481Y246736D01*
X501471Y246776D01*
X501466Y246816D01*
X501451Y246861D01*
X501441Y246901D01*
X501426Y246941D01*
X501406Y246981D01*
X501391Y247016D01*
X501371Y247056D01*
X501271Y247196D01*
X501241Y247226D01*
Y249356D01*
X501231Y249481D01*
X501191Y249606D01*
X501131Y249716D01*
X501051Y249816D01*
X500951Y249896D01*
X500841Y249956D01*
X500716Y249996D01*
X500591Y250006D01*
G37*
G36*
G01X505315D02*
X505190Y249996D01*
X505065Y249956D01*
X504955Y249896D01*
X504855Y249816D01*
X504775Y249716D01*
X504715Y249606D01*
X504675Y249481D01*
X504665Y249356D01*
Y247231D01*
X504635Y247201D01*
X504610Y247166D01*
X504580Y247131D01*
X504560Y247096D01*
X504535Y247061D01*
X504495Y246981D01*
X504450Y246861D01*
X504440Y246821D01*
X504430Y246776D01*
X504425Y246736D01*
X504415Y246691D01*
Y246521D01*
X504425Y246476D01*
X504430Y246436D01*
X504440Y246391D01*
X504450Y246351D01*
X504495Y246231D01*
X504535Y246151D01*
X504560Y246116D01*
X504580Y246081D01*
X504610Y246046D01*
X504635Y246011D01*
X504665Y245981D01*
Y243556D01*
X504675Y243431D01*
X504715Y243306D01*
X504775Y243196D01*
X504855Y243096D01*
X504955Y243016D01*
X505065Y242956D01*
X505190Y242916D01*
X505315Y242906D01*
X505440Y242916D01*
X505565Y242956D01*
X505675Y243016D01*
X505775Y243096D01*
X505855Y243196D01*
X505915Y243306D01*
X505955Y243431D01*
X505965Y243556D01*
Y245986D01*
X505995Y246016D01*
X506095Y246156D01*
X506115Y246196D01*
X506130Y246231D01*
X506150Y246271D01*
X506165Y246311D01*
X506175Y246351D01*
X506190Y246396D01*
X506195Y246436D01*
X506205Y246476D01*
X506210Y246521D01*
Y246561D01*
X506215Y246606D01*
X506210Y246651D01*
Y246691D01*
X506205Y246736D01*
X506195Y246776D01*
X506190Y246816D01*
X506175Y246861D01*
X506165Y246901D01*
X506150Y246941D01*
X506130Y246981D01*
X506115Y247016D01*
X506095Y247056D01*
X505995Y247196D01*
X505965Y247226D01*
Y249356D01*
X505955Y249481D01*
X505915Y249606D01*
X505855Y249716D01*
X505775Y249816D01*
X505675Y249896D01*
X505565Y249956D01*
X505440Y249996D01*
X505315Y250006D01*
G37*
G36*
G01X510040D02*
X509915Y249996D01*
X509790Y249956D01*
X509680Y249896D01*
X509580Y249816D01*
X509500Y249716D01*
X509440Y249606D01*
X509400Y249481D01*
X509390Y249356D01*
Y247231D01*
X509360Y247201D01*
X509335Y247166D01*
X509305Y247131D01*
X509285Y247096D01*
X509260Y247061D01*
X509220Y246981D01*
X509175Y246861D01*
X509165Y246821D01*
X509155Y246776D01*
X509150Y246736D01*
X509140Y246691D01*
Y246521D01*
X509150Y246476D01*
X509155Y246436D01*
X509165Y246391D01*
X509175Y246351D01*
X509220Y246231D01*
X509260Y246151D01*
X509285Y246116D01*
X509305Y246081D01*
X509335Y246046D01*
X509360Y246011D01*
X509390Y245981D01*
Y243556D01*
X509400Y243431D01*
X509440Y243306D01*
X509500Y243196D01*
X509580Y243096D01*
X509680Y243016D01*
X509790Y242956D01*
X509915Y242916D01*
X510040Y242906D01*
X510165Y242916D01*
X510290Y242956D01*
X510400Y243016D01*
X510500Y243096D01*
X510580Y243196D01*
X510640Y243306D01*
X510680Y243431D01*
X510690Y243556D01*
Y245986D01*
X510720Y246016D01*
X510820Y246156D01*
X510840Y246196D01*
X510855Y246231D01*
X510875Y246271D01*
X510890Y246311D01*
X510900Y246351D01*
X510915Y246396D01*
X510920Y246436D01*
X510930Y246476D01*
X510935Y246521D01*
Y246561D01*
X510940Y246606D01*
X510935Y246651D01*
Y246691D01*
X510930Y246736D01*
X510920Y246776D01*
X510915Y246816D01*
X510900Y246861D01*
X510890Y246901D01*
X510875Y246941D01*
X510855Y246981D01*
X510840Y247016D01*
X510820Y247056D01*
X510720Y247196D01*
X510690Y247226D01*
Y249356D01*
X510680Y249481D01*
X510640Y249606D01*
X510580Y249716D01*
X510500Y249816D01*
X510400Y249896D01*
X510290Y249956D01*
X510165Y249996D01*
X510040Y250006D01*
G37*
G36*
G01X514764D02*
X514639Y249996D01*
X514514Y249956D01*
X514404Y249896D01*
X514304Y249816D01*
X514224Y249716D01*
X514164Y249606D01*
X514124Y249481D01*
X514114Y249356D01*
Y247231D01*
X514084Y247201D01*
X514059Y247166D01*
X514029Y247131D01*
X514009Y247096D01*
X513984Y247061D01*
X513944Y246981D01*
X513899Y246861D01*
X513889Y246821D01*
X513879Y246776D01*
X513874Y246736D01*
X513864Y246691D01*
Y246521D01*
X513874Y246476D01*
X513879Y246436D01*
X513889Y246391D01*
X513899Y246351D01*
X513944Y246231D01*
X513984Y246151D01*
X514009Y246116D01*
X514029Y246081D01*
X514059Y246046D01*
X514084Y246011D01*
X514114Y245981D01*
Y243556D01*
X514124Y243431D01*
X514164Y243306D01*
X514224Y243196D01*
X514304Y243096D01*
X514404Y243016D01*
X514514Y242956D01*
X514639Y242916D01*
X514764Y242906D01*
X514889Y242916D01*
X515014Y242956D01*
X515124Y243016D01*
X515224Y243096D01*
X515304Y243196D01*
X515364Y243306D01*
X515404Y243431D01*
X515414Y243556D01*
Y245986D01*
X515444Y246016D01*
X515544Y246156D01*
X515564Y246196D01*
X515579Y246231D01*
X515599Y246271D01*
X515614Y246311D01*
X515624Y246351D01*
X515639Y246396D01*
X515644Y246436D01*
X515654Y246476D01*
X515659Y246521D01*
Y246561D01*
X515664Y246606D01*
X515659Y246651D01*
Y246691D01*
X515654Y246736D01*
X515644Y246776D01*
X515639Y246816D01*
X515624Y246861D01*
X515614Y246901D01*
X515599Y246941D01*
X515579Y246981D01*
X515564Y247016D01*
X515544Y247056D01*
X515444Y247196D01*
X515414Y247226D01*
Y249356D01*
X515404Y249481D01*
X515364Y249606D01*
X515304Y249716D01*
X515224Y249816D01*
X515124Y249896D01*
X515014Y249956D01*
X514889Y249996D01*
X514764Y250006D01*
G37*
G36*
G01X519488D02*
X519363Y249996D01*
X519238Y249956D01*
X519128Y249896D01*
X519028Y249816D01*
X518948Y249716D01*
X518888Y249606D01*
X518848Y249481D01*
X518838Y249356D01*
Y247231D01*
X518808Y247201D01*
X518783Y247166D01*
X518753Y247131D01*
X518733Y247096D01*
X518708Y247061D01*
X518668Y246981D01*
X518623Y246861D01*
X518613Y246821D01*
X518603Y246776D01*
X518598Y246736D01*
X518588Y246691D01*
Y246521D01*
X518598Y246476D01*
X518603Y246436D01*
X518613Y246391D01*
X518623Y246351D01*
X518668Y246231D01*
X518708Y246151D01*
X518733Y246116D01*
X518753Y246081D01*
X518783Y246046D01*
X518808Y246011D01*
X518838Y245981D01*
Y243556D01*
X518848Y243431D01*
X518888Y243306D01*
X518948Y243196D01*
X519028Y243096D01*
X519128Y243016D01*
X519238Y242956D01*
X519363Y242916D01*
X519488Y242906D01*
X519613Y242916D01*
X519738Y242956D01*
X519848Y243016D01*
X519948Y243096D01*
X520028Y243196D01*
X520088Y243306D01*
X520128Y243431D01*
X520138Y243556D01*
Y245986D01*
X520168Y246016D01*
X520268Y246156D01*
X520288Y246196D01*
X520303Y246231D01*
X520323Y246271D01*
X520338Y246311D01*
X520348Y246351D01*
X520363Y246396D01*
X520368Y246436D01*
X520378Y246476D01*
X520383Y246521D01*
Y246561D01*
X520388Y246606D01*
X520383Y246651D01*
Y246691D01*
X520378Y246736D01*
X520368Y246776D01*
X520363Y246816D01*
X520348Y246861D01*
X520338Y246901D01*
X520323Y246941D01*
X520303Y246981D01*
X520288Y247016D01*
X520268Y247056D01*
X520168Y247196D01*
X520138Y247226D01*
Y249356D01*
X520128Y249481D01*
X520088Y249606D01*
X520028Y249716D01*
X519948Y249816D01*
X519848Y249896D01*
X519738Y249956D01*
X519613Y249996D01*
X519488Y250006D01*
G37*
G36*
G01X524213D02*
X524088Y249996D01*
X523963Y249956D01*
X523853Y249896D01*
X523753Y249816D01*
X523673Y249716D01*
X523613Y249606D01*
X523573Y249481D01*
X523563Y249356D01*
Y247231D01*
X523533Y247201D01*
X523508Y247166D01*
X523478Y247131D01*
X523458Y247096D01*
X523433Y247061D01*
X523393Y246981D01*
X523348Y246861D01*
X523338Y246821D01*
X523328Y246776D01*
X523323Y246736D01*
X523313Y246691D01*
Y246521D01*
X523323Y246476D01*
X523328Y246436D01*
X523338Y246391D01*
X523348Y246351D01*
X523393Y246231D01*
X523433Y246151D01*
X523458Y246116D01*
X523478Y246081D01*
X523508Y246046D01*
X523533Y246011D01*
X523563Y245981D01*
Y243556D01*
X523573Y243431D01*
X523613Y243306D01*
X523673Y243196D01*
X523753Y243096D01*
X523853Y243016D01*
X523963Y242956D01*
X524088Y242916D01*
X524213Y242906D01*
X524338Y242916D01*
X524463Y242956D01*
X524573Y243016D01*
X524673Y243096D01*
X524753Y243196D01*
X524813Y243306D01*
X524853Y243431D01*
X524863Y243556D01*
Y245986D01*
X524893Y246016D01*
X524993Y246156D01*
X525013Y246196D01*
X525028Y246231D01*
X525048Y246271D01*
X525063Y246311D01*
X525073Y246351D01*
X525088Y246396D01*
X525093Y246436D01*
X525103Y246476D01*
X525108Y246521D01*
Y246561D01*
X525113Y246606D01*
X525108Y246651D01*
Y246691D01*
X525103Y246736D01*
X525093Y246776D01*
X525088Y246816D01*
X525073Y246861D01*
X525063Y246901D01*
X525048Y246941D01*
X525028Y246981D01*
X525013Y247016D01*
X524993Y247056D01*
X524893Y247196D01*
X524863Y247226D01*
Y249356D01*
X524853Y249481D01*
X524813Y249606D01*
X524753Y249716D01*
X524673Y249816D01*
X524573Y249896D01*
X524463Y249956D01*
X524338Y249996D01*
X524213Y250006D01*
G37*
G36*
G01X528937D02*
X528812Y249996D01*
X528687Y249956D01*
X528577Y249896D01*
X528477Y249816D01*
X528397Y249716D01*
X528337Y249606D01*
X528297Y249481D01*
X528287Y249356D01*
Y247231D01*
X528257Y247201D01*
X528232Y247166D01*
X528202Y247131D01*
X528182Y247096D01*
X528157Y247061D01*
X528117Y246981D01*
X528072Y246861D01*
X528062Y246821D01*
X528052Y246776D01*
X528047Y246736D01*
X528037Y246691D01*
Y246521D01*
X528047Y246476D01*
X528052Y246436D01*
X528062Y246391D01*
X528072Y246351D01*
X528117Y246231D01*
X528157Y246151D01*
X528182Y246116D01*
X528202Y246081D01*
X528232Y246046D01*
X528257Y246011D01*
X528287Y245981D01*
Y243556D01*
X528297Y243431D01*
X528337Y243306D01*
X528397Y243196D01*
X528477Y243096D01*
X528577Y243016D01*
X528687Y242956D01*
X528812Y242916D01*
X528937Y242906D01*
X529062Y242916D01*
X529187Y242956D01*
X529297Y243016D01*
X529397Y243096D01*
X529477Y243196D01*
X529537Y243306D01*
X529577Y243431D01*
X529587Y243556D01*
Y245986D01*
X529617Y246016D01*
X529717Y246156D01*
X529737Y246196D01*
X529752Y246231D01*
X529772Y246271D01*
X529787Y246311D01*
X529797Y246351D01*
X529812Y246396D01*
X529817Y246436D01*
X529827Y246476D01*
X529832Y246521D01*
Y246561D01*
X529837Y246606D01*
X529832Y246651D01*
Y246691D01*
X529827Y246736D01*
X529817Y246776D01*
X529812Y246816D01*
X529797Y246861D01*
X529787Y246901D01*
X529772Y246941D01*
X529752Y246981D01*
X529737Y247016D01*
X529717Y247056D01*
X529617Y247196D01*
X529587Y247226D01*
Y249356D01*
X529577Y249481D01*
X529537Y249606D01*
X529477Y249716D01*
X529397Y249816D01*
X529297Y249896D01*
X529187Y249956D01*
X529062Y249996D01*
X528937Y250006D01*
G37*
G36*
G01X533662D02*
X533537Y249996D01*
X533412Y249956D01*
X533302Y249896D01*
X533202Y249816D01*
X533122Y249716D01*
X533062Y249606D01*
X533022Y249481D01*
X533012Y249356D01*
Y247231D01*
X532982Y247201D01*
X532957Y247166D01*
X532927Y247131D01*
X532907Y247096D01*
X532882Y247061D01*
X532842Y246981D01*
X532797Y246861D01*
X532787Y246821D01*
X532777Y246776D01*
X532772Y246736D01*
X532762Y246691D01*
Y246521D01*
X532772Y246476D01*
X532777Y246436D01*
X532787Y246391D01*
X532797Y246351D01*
X532842Y246231D01*
X532882Y246151D01*
X532907Y246116D01*
X532927Y246081D01*
X532957Y246046D01*
X532982Y246011D01*
X533012Y245981D01*
Y243556D01*
X533022Y243431D01*
X533062Y243306D01*
X533122Y243196D01*
X533202Y243096D01*
X533302Y243016D01*
X533412Y242956D01*
X533537Y242916D01*
X533662Y242906D01*
X533787Y242916D01*
X533912Y242956D01*
X534022Y243016D01*
X534122Y243096D01*
X534202Y243196D01*
X534262Y243306D01*
X534302Y243431D01*
X534312Y243556D01*
Y245986D01*
X534342Y246016D01*
X534442Y246156D01*
X534462Y246196D01*
X534477Y246231D01*
X534497Y246271D01*
X534512Y246311D01*
X534522Y246351D01*
X534537Y246396D01*
X534542Y246436D01*
X534552Y246476D01*
X534557Y246521D01*
Y246561D01*
X534562Y246606D01*
X534557Y246651D01*
Y246691D01*
X534552Y246736D01*
X534542Y246776D01*
X534537Y246816D01*
X534522Y246861D01*
X534512Y246901D01*
X534497Y246941D01*
X534477Y246981D01*
X534462Y247016D01*
X534442Y247056D01*
X534342Y247196D01*
X534312Y247226D01*
Y249356D01*
X534302Y249481D01*
X534262Y249606D01*
X534202Y249716D01*
X534122Y249816D01*
X534022Y249896D01*
X533912Y249956D01*
X533787Y249996D01*
X533662Y250006D01*
G37*
G36*
G01X538386D02*
X538261Y249996D01*
X538136Y249956D01*
X538026Y249896D01*
X537926Y249816D01*
X537846Y249716D01*
X537786Y249606D01*
X537746Y249481D01*
X537736Y249356D01*
Y247231D01*
X537706Y247201D01*
X537681Y247166D01*
X537651Y247131D01*
X537631Y247096D01*
X537606Y247061D01*
X537566Y246981D01*
X537521Y246861D01*
X537511Y246821D01*
X537501Y246776D01*
X537496Y246736D01*
X537486Y246691D01*
Y246521D01*
X537496Y246476D01*
X537501Y246436D01*
X537511Y246391D01*
X537521Y246351D01*
X537566Y246231D01*
X537606Y246151D01*
X537631Y246116D01*
X537651Y246081D01*
X537681Y246046D01*
X537706Y246011D01*
X537736Y245981D01*
Y243556D01*
X537746Y243431D01*
X537786Y243306D01*
X537846Y243196D01*
X537926Y243096D01*
X538026Y243016D01*
X538136Y242956D01*
X538261Y242916D01*
X538386Y242906D01*
X538511Y242916D01*
X538636Y242956D01*
X538746Y243016D01*
X538846Y243096D01*
X538926Y243196D01*
X538986Y243306D01*
X539026Y243431D01*
X539036Y243556D01*
Y245986D01*
X539066Y246016D01*
X539166Y246156D01*
X539186Y246196D01*
X539201Y246231D01*
X539221Y246271D01*
X539236Y246311D01*
X539246Y246351D01*
X539261Y246396D01*
X539266Y246436D01*
X539276Y246476D01*
X539281Y246521D01*
Y246561D01*
X539286Y246606D01*
X539281Y246651D01*
Y246691D01*
X539276Y246736D01*
X539266Y246776D01*
X539261Y246816D01*
X539246Y246861D01*
X539236Y246901D01*
X539221Y246941D01*
X539201Y246981D01*
X539186Y247016D01*
X539166Y247056D01*
X539066Y247196D01*
X539036Y247226D01*
Y249356D01*
X539026Y249481D01*
X538986Y249606D01*
X538926Y249716D01*
X538846Y249816D01*
X538746Y249896D01*
X538636Y249956D01*
X538511Y249996D01*
X538386Y250006D01*
G37*
G36*
G01X543110D02*
X542985Y249996D01*
X542860Y249956D01*
X542750Y249896D01*
X542650Y249816D01*
X542570Y249716D01*
X542510Y249606D01*
X542470Y249481D01*
X542460Y249356D01*
Y247231D01*
X542430Y247201D01*
X542405Y247166D01*
X542375Y247131D01*
X542355Y247096D01*
X542330Y247061D01*
X542290Y246981D01*
X542245Y246861D01*
X542235Y246821D01*
X542225Y246776D01*
X542220Y246736D01*
X542210Y246691D01*
Y246521D01*
X542220Y246476D01*
X542225Y246436D01*
X542235Y246391D01*
X542245Y246351D01*
X542290Y246231D01*
X542330Y246151D01*
X542355Y246116D01*
X542375Y246081D01*
X542405Y246046D01*
X542430Y246011D01*
X542460Y245981D01*
Y243556D01*
X542470Y243431D01*
X542510Y243306D01*
X542570Y243196D01*
X542650Y243096D01*
X542750Y243016D01*
X542860Y242956D01*
X542985Y242916D01*
X543110Y242906D01*
X543235Y242916D01*
X543360Y242956D01*
X543470Y243016D01*
X543570Y243096D01*
X543650Y243196D01*
X543710Y243306D01*
X543750Y243431D01*
X543760Y243556D01*
Y245986D01*
X543790Y246016D01*
X543890Y246156D01*
X543910Y246196D01*
X543925Y246231D01*
X543945Y246271D01*
X543960Y246311D01*
X543970Y246351D01*
X543985Y246396D01*
X543990Y246436D01*
X544000Y246476D01*
X544005Y246521D01*
Y246561D01*
X544010Y246606D01*
X544005Y246651D01*
Y246691D01*
X544000Y246736D01*
X543990Y246776D01*
X543985Y246816D01*
X543970Y246861D01*
X543960Y246901D01*
X543945Y246941D01*
X543925Y246981D01*
X543910Y247016D01*
X543890Y247056D01*
X543790Y247196D01*
X543760Y247226D01*
Y249356D01*
X543750Y249481D01*
X543710Y249606D01*
X543650Y249716D01*
X543570Y249816D01*
X543470Y249896D01*
X543360Y249956D01*
X543235Y249996D01*
X543110Y250006D01*
G37*
G36*
G01X547835D02*
X547710Y249996D01*
X547585Y249956D01*
X547475Y249896D01*
X547375Y249816D01*
X547295Y249716D01*
X547235Y249606D01*
X547195Y249481D01*
X547185Y249356D01*
Y247231D01*
X547155Y247201D01*
X547130Y247166D01*
X547100Y247131D01*
X547080Y247096D01*
X547055Y247061D01*
X547015Y246981D01*
X546970Y246861D01*
X546960Y246821D01*
X546950Y246776D01*
X546945Y246736D01*
X546935Y246691D01*
Y246521D01*
X546945Y246476D01*
X546950Y246436D01*
X546960Y246391D01*
X546970Y246351D01*
X547015Y246231D01*
X547055Y246151D01*
X547080Y246116D01*
X547100Y246081D01*
X547130Y246046D01*
X547155Y246011D01*
X547185Y245981D01*
Y243556D01*
X547195Y243431D01*
X547235Y243306D01*
X547295Y243196D01*
X547375Y243096D01*
X547475Y243016D01*
X547585Y242956D01*
X547710Y242916D01*
X547835Y242906D01*
X547960Y242916D01*
X548085Y242956D01*
X548195Y243016D01*
X548295Y243096D01*
X548375Y243196D01*
X548435Y243306D01*
X548475Y243431D01*
X548485Y243556D01*
Y245986D01*
X548515Y246016D01*
X548615Y246156D01*
X548635Y246196D01*
X548650Y246231D01*
X548670Y246271D01*
X548685Y246311D01*
X548695Y246351D01*
X548710Y246396D01*
X548715Y246436D01*
X548725Y246476D01*
X548730Y246521D01*
Y246561D01*
X548735Y246606D01*
X548730Y246651D01*
Y246691D01*
X548725Y246736D01*
X548715Y246776D01*
X548710Y246816D01*
X548695Y246861D01*
X548685Y246901D01*
X548670Y246941D01*
X548650Y246981D01*
X548635Y247016D01*
X548615Y247056D01*
X548515Y247196D01*
X548485Y247226D01*
Y249356D01*
X548475Y249481D01*
X548435Y249606D01*
X548375Y249716D01*
X548295Y249816D01*
X548195Y249896D01*
X548085Y249956D01*
X547960Y249996D01*
X547835Y250006D01*
G37*
G36*
G01X552559D02*
X552434Y249996D01*
X552309Y249956D01*
X552199Y249896D01*
X552099Y249816D01*
X552019Y249716D01*
X551959Y249606D01*
X551919Y249481D01*
X551909Y249356D01*
Y247231D01*
X551879Y247201D01*
X551854Y247166D01*
X551824Y247131D01*
X551804Y247096D01*
X551779Y247061D01*
X551739Y246981D01*
X551694Y246861D01*
X551684Y246821D01*
X551674Y246776D01*
X551669Y246736D01*
X551659Y246691D01*
Y246521D01*
X551669Y246476D01*
X551674Y246436D01*
X551684Y246391D01*
X551694Y246351D01*
X551739Y246231D01*
X551779Y246151D01*
X551804Y246116D01*
X551824Y246081D01*
X551854Y246046D01*
X551879Y246011D01*
X551909Y245981D01*
Y243556D01*
X551919Y243431D01*
X551959Y243306D01*
X552019Y243196D01*
X552099Y243096D01*
X552199Y243016D01*
X552309Y242956D01*
X552434Y242916D01*
X552559Y242906D01*
X552684Y242916D01*
X552809Y242956D01*
X552919Y243016D01*
X553019Y243096D01*
X553099Y243196D01*
X553159Y243306D01*
X553199Y243431D01*
X553209Y243556D01*
Y245986D01*
X553239Y246016D01*
X553339Y246156D01*
X553359Y246196D01*
X553374Y246231D01*
X553394Y246271D01*
X553409Y246311D01*
X553419Y246351D01*
X553434Y246396D01*
X553439Y246436D01*
X553449Y246476D01*
X553454Y246521D01*
Y246561D01*
X553459Y246606D01*
X553454Y246651D01*
Y246691D01*
X553449Y246736D01*
X553439Y246776D01*
X553434Y246816D01*
X553419Y246861D01*
X553409Y246901D01*
X553394Y246941D01*
X553374Y246981D01*
X553359Y247016D01*
X553339Y247056D01*
X553239Y247196D01*
X553209Y247226D01*
Y249356D01*
X553199Y249481D01*
X553159Y249606D01*
X553099Y249716D01*
X553019Y249816D01*
X552919Y249896D01*
X552809Y249956D01*
X552684Y249996D01*
X552559Y250006D01*
G37*
G36*
G01X557284D02*
X557159Y249996D01*
X557034Y249956D01*
X556924Y249896D01*
X556824Y249816D01*
X556744Y249716D01*
X556684Y249606D01*
X556644Y249481D01*
X556634Y249356D01*
Y247231D01*
X556604Y247201D01*
X556579Y247166D01*
X556549Y247131D01*
X556529Y247096D01*
X556504Y247061D01*
X556464Y246981D01*
X556419Y246861D01*
X556409Y246821D01*
X556399Y246776D01*
X556394Y246736D01*
X556384Y246691D01*
Y246521D01*
X556394Y246476D01*
X556399Y246436D01*
X556409Y246391D01*
X556419Y246351D01*
X556464Y246231D01*
X556504Y246151D01*
X556529Y246116D01*
X556549Y246081D01*
X556579Y246046D01*
X556604Y246011D01*
X556634Y245981D01*
Y243556D01*
X556644Y243431D01*
X556684Y243306D01*
X556744Y243196D01*
X556824Y243096D01*
X556924Y243016D01*
X557034Y242956D01*
X557159Y242916D01*
X557284Y242906D01*
X557409Y242916D01*
X557534Y242956D01*
X557644Y243016D01*
X557744Y243096D01*
X557824Y243196D01*
X557884Y243306D01*
X557924Y243431D01*
X557934Y243556D01*
Y245986D01*
X557964Y246016D01*
X558064Y246156D01*
X558084Y246196D01*
X558099Y246231D01*
X558119Y246271D01*
X558134Y246311D01*
X558144Y246351D01*
X558159Y246396D01*
X558164Y246436D01*
X558174Y246476D01*
X558179Y246521D01*
Y246561D01*
X558184Y246606D01*
X558179Y246651D01*
Y246691D01*
X558174Y246736D01*
X558164Y246776D01*
X558159Y246816D01*
X558144Y246861D01*
X558134Y246901D01*
X558119Y246941D01*
X558099Y246981D01*
X558084Y247016D01*
X558064Y247056D01*
X557964Y247196D01*
X557934Y247226D01*
Y249356D01*
X557924Y249481D01*
X557884Y249606D01*
X557824Y249716D01*
X557744Y249816D01*
X557644Y249896D01*
X557534Y249956D01*
X557409Y249996D01*
X557284Y250006D01*
G37*
G36*
G01X562008D02*
X561883Y249996D01*
X561758Y249956D01*
X561648Y249896D01*
X561548Y249816D01*
X561468Y249716D01*
X561408Y249606D01*
X561368Y249481D01*
X561358Y249356D01*
Y247231D01*
X561328Y247201D01*
X561303Y247166D01*
X561273Y247131D01*
X561253Y247096D01*
X561228Y247061D01*
X561188Y246981D01*
X561143Y246861D01*
X561133Y246821D01*
X561123Y246776D01*
X561118Y246736D01*
X561108Y246691D01*
Y246521D01*
X561118Y246476D01*
X561123Y246436D01*
X561133Y246391D01*
X561143Y246351D01*
X561188Y246231D01*
X561228Y246151D01*
X561253Y246116D01*
X561273Y246081D01*
X561303Y246046D01*
X561328Y246011D01*
X561358Y245981D01*
Y243556D01*
X561368Y243431D01*
X561408Y243306D01*
X561468Y243196D01*
X561548Y243096D01*
X561648Y243016D01*
X561758Y242956D01*
X561883Y242916D01*
X562008Y242906D01*
X562133Y242916D01*
X562258Y242956D01*
X562368Y243016D01*
X562468Y243096D01*
X562548Y243196D01*
X562608Y243306D01*
X562648Y243431D01*
X562658Y243556D01*
Y245986D01*
X562688Y246016D01*
X562788Y246156D01*
X562808Y246196D01*
X562823Y246231D01*
X562843Y246271D01*
X562858Y246311D01*
X562868Y246351D01*
X562883Y246396D01*
X562888Y246436D01*
X562898Y246476D01*
X562903Y246521D01*
Y246561D01*
X562908Y246606D01*
X562903Y246651D01*
Y246691D01*
X562898Y246736D01*
X562888Y246776D01*
X562883Y246816D01*
X562868Y246861D01*
X562858Y246901D01*
X562843Y246941D01*
X562823Y246981D01*
X562808Y247016D01*
X562788Y247056D01*
X562688Y247196D01*
X562658Y247226D01*
Y249356D01*
X562648Y249481D01*
X562608Y249606D01*
X562548Y249716D01*
X562468Y249816D01*
X562368Y249896D01*
X562258Y249956D01*
X562133Y249996D01*
X562008Y250006D01*
G37*
G36*
G01X566733D02*
X566608Y249996D01*
X566483Y249956D01*
X566373Y249896D01*
X566273Y249816D01*
X566193Y249716D01*
X566133Y249606D01*
X566093Y249481D01*
X566083Y249356D01*
Y247231D01*
X566053Y247201D01*
X566028Y247166D01*
X565998Y247131D01*
X565978Y247096D01*
X565953Y247061D01*
X565913Y246981D01*
X565868Y246861D01*
X565858Y246821D01*
X565848Y246776D01*
X565843Y246736D01*
X565833Y246691D01*
Y246521D01*
X565843Y246476D01*
X565848Y246436D01*
X565858Y246391D01*
X565868Y246351D01*
X565913Y246231D01*
X565953Y246151D01*
X565978Y246116D01*
X565998Y246081D01*
X566028Y246046D01*
X566053Y246011D01*
X566083Y245981D01*
Y243556D01*
X566093Y243431D01*
X566133Y243306D01*
X566193Y243196D01*
X566273Y243096D01*
X566373Y243016D01*
X566483Y242956D01*
X566608Y242916D01*
X566733Y242906D01*
X566858Y242916D01*
X566983Y242956D01*
X567093Y243016D01*
X567193Y243096D01*
X567273Y243196D01*
X567333Y243306D01*
X567373Y243431D01*
X567383Y243556D01*
Y245986D01*
X567413Y246016D01*
X567513Y246156D01*
X567533Y246196D01*
X567548Y246231D01*
X567568Y246271D01*
X567583Y246311D01*
X567593Y246351D01*
X567608Y246396D01*
X567613Y246436D01*
X567623Y246476D01*
X567628Y246521D01*
Y246561D01*
X567633Y246606D01*
X567628Y246651D01*
Y246691D01*
X567623Y246736D01*
X567613Y246776D01*
X567608Y246816D01*
X567593Y246861D01*
X567583Y246901D01*
X567568Y246941D01*
X567548Y246981D01*
X567533Y247016D01*
X567513Y247056D01*
X567413Y247196D01*
X567383Y247226D01*
Y249356D01*
X567373Y249481D01*
X567333Y249606D01*
X567273Y249716D01*
X567193Y249816D01*
X567093Y249896D01*
X566983Y249956D01*
X566858Y249996D01*
X566733Y250006D01*
G37*
G36*
G01X571457D02*
X571332Y249996D01*
X571207Y249956D01*
X571097Y249896D01*
X570997Y249816D01*
X570917Y249716D01*
X570857Y249606D01*
X570817Y249481D01*
X570807Y249356D01*
Y247231D01*
X570777Y247201D01*
X570752Y247166D01*
X570722Y247131D01*
X570702Y247096D01*
X570677Y247061D01*
X570637Y246981D01*
X570592Y246861D01*
X570582Y246821D01*
X570572Y246776D01*
X570567Y246736D01*
X570557Y246691D01*
Y246521D01*
X570567Y246476D01*
X570572Y246436D01*
X570582Y246391D01*
X570592Y246351D01*
X570637Y246231D01*
X570677Y246151D01*
X570702Y246116D01*
X570722Y246081D01*
X570752Y246046D01*
X570777Y246011D01*
X570807Y245981D01*
Y243556D01*
X570817Y243431D01*
X570857Y243306D01*
X570917Y243196D01*
X570997Y243096D01*
X571097Y243016D01*
X571207Y242956D01*
X571332Y242916D01*
X571457Y242906D01*
X571582Y242916D01*
X571707Y242956D01*
X571817Y243016D01*
X571917Y243096D01*
X571997Y243196D01*
X572057Y243306D01*
X572097Y243431D01*
X572107Y243556D01*
Y245986D01*
X572137Y246016D01*
X572237Y246156D01*
X572257Y246196D01*
X572272Y246231D01*
X572292Y246271D01*
X572307Y246311D01*
X572317Y246351D01*
X572332Y246396D01*
X572337Y246436D01*
X572347Y246476D01*
X572352Y246521D01*
Y246561D01*
X572357Y246606D01*
X572352Y246651D01*
Y246691D01*
X572347Y246736D01*
X572337Y246776D01*
X572332Y246816D01*
X572317Y246861D01*
X572307Y246901D01*
X572292Y246941D01*
X572272Y246981D01*
X572257Y247016D01*
X572237Y247056D01*
X572137Y247196D01*
X572107Y247226D01*
Y249356D01*
X572097Y249481D01*
X572057Y249606D01*
X571997Y249716D01*
X571917Y249816D01*
X571817Y249896D01*
X571707Y249956D01*
X571582Y249996D01*
X571457Y250006D01*
G37*
G36*
G01X576181D02*
X576056Y249996D01*
X575931Y249956D01*
X575821Y249896D01*
X575721Y249816D01*
X575641Y249716D01*
X575581Y249606D01*
X575541Y249481D01*
X575531Y249356D01*
Y247231D01*
X575501Y247201D01*
X575476Y247166D01*
X575446Y247131D01*
X575426Y247096D01*
X575401Y247061D01*
X575361Y246981D01*
X575316Y246861D01*
X575306Y246821D01*
X575296Y246776D01*
X575291Y246736D01*
X575281Y246691D01*
Y246521D01*
X575291Y246476D01*
X575296Y246436D01*
X575306Y246391D01*
X575316Y246351D01*
X575361Y246231D01*
X575401Y246151D01*
X575426Y246116D01*
X575446Y246081D01*
X575476Y246046D01*
X575501Y246011D01*
X575531Y245981D01*
Y243556D01*
X575541Y243431D01*
X575581Y243306D01*
X575641Y243196D01*
X575721Y243096D01*
X575821Y243016D01*
X575931Y242956D01*
X576056Y242916D01*
X576181Y242906D01*
X576306Y242916D01*
X576431Y242956D01*
X576541Y243016D01*
X576641Y243096D01*
X576721Y243196D01*
X576781Y243306D01*
X576821Y243431D01*
X576831Y243556D01*
Y245986D01*
X576861Y246016D01*
X576961Y246156D01*
X576981Y246196D01*
X576996Y246231D01*
X577016Y246271D01*
X577031Y246311D01*
X577041Y246351D01*
X577056Y246396D01*
X577061Y246436D01*
X577071Y246476D01*
X577076Y246521D01*
Y246561D01*
X577081Y246606D01*
X577076Y246651D01*
Y246691D01*
X577071Y246736D01*
X577061Y246776D01*
X577056Y246816D01*
X577041Y246861D01*
X577031Y246901D01*
X577016Y246941D01*
X576996Y246981D01*
X576981Y247016D01*
X576961Y247056D01*
X576861Y247196D01*
X576831Y247226D01*
Y249356D01*
X576821Y249481D01*
X576781Y249606D01*
X576721Y249716D01*
X576641Y249816D01*
X576541Y249896D01*
X576431Y249956D01*
X576306Y249996D01*
X576181Y250006D01*
G37*
G36*
G01X580906D02*
X580781Y249996D01*
X580656Y249956D01*
X580546Y249896D01*
X580446Y249816D01*
X580366Y249716D01*
X580306Y249606D01*
X580266Y249481D01*
X580256Y249356D01*
Y247231D01*
X580226Y247201D01*
X580201Y247166D01*
X580171Y247131D01*
X580151Y247096D01*
X580126Y247061D01*
X580086Y246981D01*
X580041Y246861D01*
X580031Y246821D01*
X580021Y246776D01*
X580016Y246736D01*
X580006Y246691D01*
Y246521D01*
X580016Y246476D01*
X580021Y246436D01*
X580031Y246391D01*
X580041Y246351D01*
X580086Y246231D01*
X580126Y246151D01*
X580151Y246116D01*
X580171Y246081D01*
X580201Y246046D01*
X580226Y246011D01*
X580256Y245981D01*
Y243556D01*
X580266Y243431D01*
X580306Y243306D01*
X580366Y243196D01*
X580446Y243096D01*
X580546Y243016D01*
X580656Y242956D01*
X580781Y242916D01*
X580906Y242906D01*
X581031Y242916D01*
X581156Y242956D01*
X581266Y243016D01*
X581366Y243096D01*
X581446Y243196D01*
X581506Y243306D01*
X581546Y243431D01*
X581556Y243556D01*
Y245986D01*
X581586Y246016D01*
X581686Y246156D01*
X581706Y246196D01*
X581721Y246231D01*
X581741Y246271D01*
X581756Y246311D01*
X581766Y246351D01*
X581781Y246396D01*
X581786Y246436D01*
X581796Y246476D01*
X581801Y246521D01*
Y246561D01*
X581806Y246606D01*
X581801Y246651D01*
Y246691D01*
X581796Y246736D01*
X581786Y246776D01*
X581781Y246816D01*
X581766Y246861D01*
X581756Y246901D01*
X581741Y246941D01*
X581721Y246981D01*
X581706Y247016D01*
X581686Y247056D01*
X581586Y247196D01*
X581556Y247226D01*
Y249356D01*
X581546Y249481D01*
X581506Y249606D01*
X581446Y249716D01*
X581366Y249816D01*
X581266Y249896D01*
X581156Y249956D01*
X581031Y249996D01*
X580906Y250006D01*
G37*
G36*
G01X585630D02*
X585505Y249996D01*
X585380Y249956D01*
X585270Y249896D01*
X585170Y249816D01*
X585090Y249716D01*
X585030Y249606D01*
X584990Y249481D01*
X584980Y249356D01*
Y247231D01*
X584950Y247201D01*
X584925Y247166D01*
X584895Y247131D01*
X584875Y247096D01*
X584850Y247061D01*
X584810Y246981D01*
X584765Y246861D01*
X584755Y246821D01*
X584745Y246776D01*
X584740Y246736D01*
X584730Y246691D01*
Y246521D01*
X584740Y246476D01*
X584745Y246436D01*
X584755Y246391D01*
X584765Y246351D01*
X584810Y246231D01*
X584850Y246151D01*
X584875Y246116D01*
X584895Y246081D01*
X584925Y246046D01*
X584950Y246011D01*
X584980Y245981D01*
Y243556D01*
X584990Y243431D01*
X585030Y243306D01*
X585090Y243196D01*
X585170Y243096D01*
X585270Y243016D01*
X585380Y242956D01*
X585505Y242916D01*
X585630Y242906D01*
X585755Y242916D01*
X585880Y242956D01*
X585990Y243016D01*
X586090Y243096D01*
X586170Y243196D01*
X586230Y243306D01*
X586270Y243431D01*
X586280Y243556D01*
Y245986D01*
X586310Y246016D01*
X586410Y246156D01*
X586430Y246196D01*
X586445Y246231D01*
X586465Y246271D01*
X586480Y246311D01*
X586490Y246351D01*
X586505Y246396D01*
X586510Y246436D01*
X586520Y246476D01*
X586525Y246521D01*
Y246561D01*
X586530Y246606D01*
X586525Y246651D01*
Y246691D01*
X586520Y246736D01*
X586510Y246776D01*
X586505Y246816D01*
X586490Y246861D01*
X586480Y246901D01*
X586465Y246941D01*
X586445Y246981D01*
X586430Y247016D01*
X586410Y247056D01*
X586310Y247196D01*
X586280Y247226D01*
Y249356D01*
X586270Y249481D01*
X586230Y249606D01*
X586170Y249716D01*
X586090Y249816D01*
X585990Y249896D01*
X585880Y249956D01*
X585755Y249996D01*
X585630Y250006D01*
G37*
G36*
G01X590355D02*
X590230Y249996D01*
X590105Y249956D01*
X589995Y249896D01*
X589895Y249816D01*
X589815Y249716D01*
X589755Y249606D01*
X589715Y249481D01*
X589705Y249356D01*
Y247231D01*
X589675Y247201D01*
X589650Y247166D01*
X589620Y247131D01*
X589600Y247096D01*
X589575Y247061D01*
X589535Y246981D01*
X589490Y246861D01*
X589480Y246821D01*
X589470Y246776D01*
X589465Y246736D01*
X589455Y246691D01*
Y246521D01*
X589465Y246476D01*
X589470Y246436D01*
X589480Y246391D01*
X589490Y246351D01*
X589535Y246231D01*
X589575Y246151D01*
X589600Y246116D01*
X589620Y246081D01*
X589650Y246046D01*
X589675Y246011D01*
X589705Y245981D01*
Y243556D01*
X589715Y243431D01*
X589755Y243306D01*
X589815Y243196D01*
X589895Y243096D01*
X589995Y243016D01*
X590105Y242956D01*
X590230Y242916D01*
X590355Y242906D01*
X590480Y242916D01*
X590605Y242956D01*
X590715Y243016D01*
X590815Y243096D01*
X590895Y243196D01*
X590955Y243306D01*
X590995Y243431D01*
X591005Y243556D01*
Y245986D01*
X591035Y246016D01*
X591135Y246156D01*
X591155Y246196D01*
X591170Y246231D01*
X591190Y246271D01*
X591205Y246311D01*
X591215Y246351D01*
X591230Y246396D01*
X591235Y246436D01*
X591245Y246476D01*
X591250Y246521D01*
Y246561D01*
X591255Y246606D01*
X591250Y246651D01*
Y246691D01*
X591245Y246736D01*
X591235Y246776D01*
X591230Y246816D01*
X591215Y246861D01*
X591205Y246901D01*
X591190Y246941D01*
X591170Y246981D01*
X591155Y247016D01*
X591135Y247056D01*
X591035Y247196D01*
X591005Y247226D01*
Y249356D01*
X590995Y249481D01*
X590955Y249606D01*
X590895Y249716D01*
X590815Y249816D01*
X590715Y249896D01*
X590605Y249956D01*
X590480Y249996D01*
X590355Y250006D01*
G37*
G36*
G01X595079D02*
X594954Y249996D01*
X594829Y249956D01*
X594719Y249896D01*
X594619Y249816D01*
X594539Y249716D01*
X594479Y249606D01*
X594439Y249481D01*
X594429Y249356D01*
Y247231D01*
X594399Y247201D01*
X594374Y247166D01*
X594344Y247131D01*
X594324Y247096D01*
X594299Y247061D01*
X594259Y246981D01*
X594214Y246861D01*
X594204Y246821D01*
X594194Y246776D01*
X594189Y246736D01*
X594179Y246691D01*
Y246521D01*
X594189Y246476D01*
X594194Y246436D01*
X594204Y246391D01*
X594214Y246351D01*
X594259Y246231D01*
X594299Y246151D01*
X594324Y246116D01*
X594344Y246081D01*
X594374Y246046D01*
X594399Y246011D01*
X594429Y245981D01*
Y243556D01*
X594439Y243431D01*
X594479Y243306D01*
X594539Y243196D01*
X594619Y243096D01*
X594719Y243016D01*
X594829Y242956D01*
X594954Y242916D01*
X595079Y242906D01*
X595204Y242916D01*
X595329Y242956D01*
X595439Y243016D01*
X595539Y243096D01*
X595619Y243196D01*
X595679Y243306D01*
X595719Y243431D01*
X595729Y243556D01*
Y245986D01*
X595759Y246016D01*
X595859Y246156D01*
X595879Y246196D01*
X595894Y246231D01*
X595914Y246271D01*
X595929Y246311D01*
X595939Y246351D01*
X595954Y246396D01*
X595959Y246436D01*
X595969Y246476D01*
X595974Y246521D01*
Y246561D01*
X595979Y246606D01*
X595974Y246651D01*
Y246691D01*
X595969Y246736D01*
X595959Y246776D01*
X595954Y246816D01*
X595939Y246861D01*
X595929Y246901D01*
X595914Y246941D01*
X595894Y246981D01*
X595879Y247016D01*
X595859Y247056D01*
X595759Y247196D01*
X595729Y247226D01*
Y249356D01*
X595719Y249481D01*
X595679Y249606D01*
X595619Y249716D01*
X595539Y249816D01*
X595439Y249896D01*
X595329Y249956D01*
X595204Y249996D01*
X595079Y250006D01*
G37*
G36*
G01X599803D02*
X599678Y249996D01*
X599553Y249956D01*
X599443Y249896D01*
X599343Y249816D01*
X599263Y249716D01*
X599203Y249606D01*
X599163Y249481D01*
X599153Y249356D01*
Y247231D01*
X599123Y247201D01*
X599098Y247166D01*
X599068Y247131D01*
X599048Y247096D01*
X599023Y247061D01*
X598983Y246981D01*
X598938Y246861D01*
X598928Y246821D01*
X598918Y246776D01*
X598913Y246736D01*
X598903Y246691D01*
Y246521D01*
X598913Y246476D01*
X598918Y246436D01*
X598928Y246391D01*
X598938Y246351D01*
X598983Y246231D01*
X599023Y246151D01*
X599048Y246116D01*
X599068Y246081D01*
X599098Y246046D01*
X599123Y246011D01*
X599153Y245981D01*
Y243556D01*
X599163Y243431D01*
X599203Y243306D01*
X599263Y243196D01*
X599343Y243096D01*
X599443Y243016D01*
X599553Y242956D01*
X599678Y242916D01*
X599803Y242906D01*
X599928Y242916D01*
X600053Y242956D01*
X600163Y243016D01*
X600263Y243096D01*
X600343Y243196D01*
X600403Y243306D01*
X600443Y243431D01*
X600453Y243556D01*
Y245986D01*
X600483Y246016D01*
X600583Y246156D01*
X600603Y246196D01*
X600618Y246231D01*
X600638Y246271D01*
X600653Y246311D01*
X600663Y246351D01*
X600678Y246396D01*
X600683Y246436D01*
X600693Y246476D01*
X600698Y246521D01*
Y246561D01*
X600703Y246606D01*
X600698Y246651D01*
Y246691D01*
X600693Y246736D01*
X600683Y246776D01*
X600678Y246816D01*
X600663Y246861D01*
X600653Y246901D01*
X600638Y246941D01*
X600618Y246981D01*
X600603Y247016D01*
X600583Y247056D01*
X600483Y247196D01*
X600453Y247226D01*
Y249356D01*
X600443Y249481D01*
X600403Y249606D01*
X600343Y249716D01*
X600263Y249816D01*
X600163Y249896D01*
X600053Y249956D01*
X599928Y249996D01*
X599803Y250006D01*
G37*
G36*
G01X604528D02*
X604403Y249996D01*
X604278Y249956D01*
X604168Y249896D01*
X604068Y249816D01*
X603988Y249716D01*
X603928Y249606D01*
X603888Y249481D01*
X603878Y249356D01*
Y247231D01*
X603848Y247201D01*
X603823Y247166D01*
X603793Y247131D01*
X603773Y247096D01*
X603748Y247061D01*
X603708Y246981D01*
X603663Y246861D01*
X603653Y246821D01*
X603643Y246776D01*
X603638Y246736D01*
X603628Y246691D01*
Y246521D01*
X603638Y246476D01*
X603643Y246436D01*
X603653Y246391D01*
X603663Y246351D01*
X603708Y246231D01*
X603748Y246151D01*
X603773Y246116D01*
X603793Y246081D01*
X603823Y246046D01*
X603848Y246011D01*
X603878Y245981D01*
Y243556D01*
X603888Y243431D01*
X603928Y243306D01*
X603988Y243196D01*
X604068Y243096D01*
X604168Y243016D01*
X604278Y242956D01*
X604403Y242916D01*
X604528Y242906D01*
X604653Y242916D01*
X604778Y242956D01*
X604888Y243016D01*
X604988Y243096D01*
X605068Y243196D01*
X605128Y243306D01*
X605168Y243431D01*
X605178Y243556D01*
Y245986D01*
X605208Y246016D01*
X605308Y246156D01*
X605328Y246196D01*
X605343Y246231D01*
X605363Y246271D01*
X605378Y246311D01*
X605388Y246351D01*
X605403Y246396D01*
X605408Y246436D01*
X605418Y246476D01*
X605423Y246521D01*
Y246561D01*
X605428Y246606D01*
X605423Y246651D01*
Y246691D01*
X605418Y246736D01*
X605408Y246776D01*
X605403Y246816D01*
X605388Y246861D01*
X605378Y246901D01*
X605363Y246941D01*
X605343Y246981D01*
X605328Y247016D01*
X605308Y247056D01*
X605208Y247196D01*
X605178Y247226D01*
Y249356D01*
X605168Y249481D01*
X605128Y249606D01*
X605068Y249716D01*
X604988Y249816D01*
X604888Y249896D01*
X604778Y249956D01*
X604653Y249996D01*
X604528Y250006D01*
G37*
G36*
G01X609252D02*
X609127Y249996D01*
X609002Y249956D01*
X608892Y249896D01*
X608792Y249816D01*
X608712Y249716D01*
X608652Y249606D01*
X608612Y249481D01*
X608602Y249356D01*
Y247231D01*
X608572Y247201D01*
X608547Y247166D01*
X608517Y247131D01*
X608497Y247096D01*
X608472Y247061D01*
X608432Y246981D01*
X608387Y246861D01*
X608377Y246821D01*
X608367Y246776D01*
X608362Y246736D01*
X608352Y246691D01*
Y246521D01*
X608362Y246476D01*
X608367Y246436D01*
X608377Y246391D01*
X608387Y246351D01*
X608432Y246231D01*
X608472Y246151D01*
X608497Y246116D01*
X608517Y246081D01*
X608547Y246046D01*
X608572Y246011D01*
X608602Y245981D01*
Y243556D01*
X608612Y243431D01*
X608652Y243306D01*
X608712Y243196D01*
X608792Y243096D01*
X608892Y243016D01*
X609002Y242956D01*
X609127Y242916D01*
X609252Y242906D01*
X609377Y242916D01*
X609502Y242956D01*
X609612Y243016D01*
X609712Y243096D01*
X609792Y243196D01*
X609852Y243306D01*
X609892Y243431D01*
X609902Y243556D01*
Y245986D01*
X609932Y246016D01*
X610032Y246156D01*
X610052Y246196D01*
X610067Y246231D01*
X610087Y246271D01*
X610102Y246311D01*
X610112Y246351D01*
X610127Y246396D01*
X610132Y246436D01*
X610142Y246476D01*
X610147Y246521D01*
Y246561D01*
X610152Y246606D01*
X610147Y246651D01*
Y246691D01*
X610142Y246736D01*
X610132Y246776D01*
X610127Y246816D01*
X610112Y246861D01*
X610102Y246901D01*
X610087Y246941D01*
X610067Y246981D01*
X610052Y247016D01*
X610032Y247056D01*
X609932Y247196D01*
X609902Y247226D01*
Y249356D01*
X609892Y249481D01*
X609852Y249606D01*
X609792Y249716D01*
X609712Y249816D01*
X609612Y249896D01*
X609502Y249956D01*
X609377Y249996D01*
X609252Y250006D01*
G37*
G36*
G01X613977D02*
X613852Y249996D01*
X613727Y249956D01*
X613617Y249896D01*
X613517Y249816D01*
X613437Y249716D01*
X613377Y249606D01*
X613337Y249481D01*
X613327Y249356D01*
Y247231D01*
X613297Y247201D01*
X613272Y247166D01*
X613242Y247131D01*
X613222Y247096D01*
X613197Y247061D01*
X613157Y246981D01*
X613112Y246861D01*
X613102Y246821D01*
X613092Y246776D01*
X613087Y246736D01*
X613077Y246691D01*
Y246521D01*
X613087Y246476D01*
X613092Y246436D01*
X613102Y246391D01*
X613112Y246351D01*
X613157Y246231D01*
X613197Y246151D01*
X613222Y246116D01*
X613242Y246081D01*
X613272Y246046D01*
X613297Y246011D01*
X613327Y245981D01*
Y243556D01*
X613337Y243431D01*
X613377Y243306D01*
X613437Y243196D01*
X613517Y243096D01*
X613617Y243016D01*
X613727Y242956D01*
X613852Y242916D01*
X613977Y242906D01*
X614102Y242916D01*
X614227Y242956D01*
X614337Y243016D01*
X614437Y243096D01*
X614517Y243196D01*
X614577Y243306D01*
X614617Y243431D01*
X614627Y243556D01*
Y245986D01*
X614657Y246016D01*
X614757Y246156D01*
X614777Y246196D01*
X614792Y246231D01*
X614812Y246271D01*
X614827Y246311D01*
X614837Y246351D01*
X614852Y246396D01*
X614857Y246436D01*
X614867Y246476D01*
X614872Y246521D01*
Y246561D01*
X614877Y246606D01*
X614872Y246651D01*
Y246691D01*
X614867Y246736D01*
X614857Y246776D01*
X614852Y246816D01*
X614837Y246861D01*
X614827Y246901D01*
X614812Y246941D01*
X614792Y246981D01*
X614777Y247016D01*
X614757Y247056D01*
X614657Y247196D01*
X614627Y247226D01*
Y249356D01*
X614617Y249481D01*
X614577Y249606D01*
X614517Y249716D01*
X614437Y249816D01*
X614337Y249896D01*
X614227Y249956D01*
X614102Y249996D01*
X613977Y250006D01*
G37*
G36*
G01X618701D02*
X618576Y249996D01*
X618451Y249956D01*
X618341Y249896D01*
X618241Y249816D01*
X618161Y249716D01*
X618101Y249606D01*
X618061Y249481D01*
X618051Y249356D01*
Y247231D01*
X618021Y247201D01*
X617996Y247166D01*
X617966Y247131D01*
X617946Y247096D01*
X617921Y247061D01*
X617881Y246981D01*
X617836Y246861D01*
X617826Y246821D01*
X617816Y246776D01*
X617811Y246736D01*
X617801Y246691D01*
Y246521D01*
X617811Y246476D01*
X617816Y246436D01*
X617826Y246391D01*
X617836Y246351D01*
X617881Y246231D01*
X617921Y246151D01*
X617946Y246116D01*
X617966Y246081D01*
X617996Y246046D01*
X618021Y246011D01*
X618051Y245981D01*
Y243556D01*
X618061Y243431D01*
X618101Y243306D01*
X618161Y243196D01*
X618241Y243096D01*
X618341Y243016D01*
X618451Y242956D01*
X618576Y242916D01*
X618701Y242906D01*
X618826Y242916D01*
X618951Y242956D01*
X619061Y243016D01*
X619161Y243096D01*
X619241Y243196D01*
X619301Y243306D01*
X619341Y243431D01*
X619351Y243556D01*
Y245986D01*
X619381Y246016D01*
X619481Y246156D01*
X619501Y246196D01*
X619516Y246231D01*
X619536Y246271D01*
X619551Y246311D01*
X619561Y246351D01*
X619576Y246396D01*
X619581Y246436D01*
X619591Y246476D01*
X619596Y246521D01*
Y246561D01*
X619601Y246606D01*
X619596Y246651D01*
Y246691D01*
X619591Y246736D01*
X619581Y246776D01*
X619576Y246816D01*
X619561Y246861D01*
X619551Y246901D01*
X619536Y246941D01*
X619516Y246981D01*
X619501Y247016D01*
X619481Y247056D01*
X619381Y247196D01*
X619351Y247226D01*
Y249356D01*
X619341Y249481D01*
X619301Y249606D01*
X619241Y249716D01*
X619161Y249816D01*
X619061Y249896D01*
X618951Y249956D01*
X618826Y249996D01*
X618701Y250006D01*
G37*
G36*
G01X623425D02*
X623300Y249996D01*
X623175Y249956D01*
X623065Y249896D01*
X622965Y249816D01*
X622885Y249716D01*
X622825Y249606D01*
X622785Y249481D01*
X622775Y249356D01*
Y247231D01*
X622745Y247201D01*
X622720Y247166D01*
X622690Y247131D01*
X622670Y247096D01*
X622645Y247061D01*
X622605Y246981D01*
X622560Y246861D01*
X622550Y246821D01*
X622540Y246776D01*
X622535Y246736D01*
X622525Y246691D01*
Y246521D01*
X622535Y246476D01*
X622540Y246436D01*
X622550Y246391D01*
X622560Y246351D01*
X622605Y246231D01*
X622645Y246151D01*
X622670Y246116D01*
X622690Y246081D01*
X622720Y246046D01*
X622745Y246011D01*
X622775Y245981D01*
Y243556D01*
X622785Y243431D01*
X622825Y243306D01*
X622885Y243196D01*
X622965Y243096D01*
X623065Y243016D01*
X623175Y242956D01*
X623300Y242916D01*
X623425Y242906D01*
X623550Y242916D01*
X623675Y242956D01*
X623785Y243016D01*
X623885Y243096D01*
X623965Y243196D01*
X624025Y243306D01*
X624065Y243431D01*
X624075Y243556D01*
Y245986D01*
X624105Y246016D01*
X624205Y246156D01*
X624225Y246196D01*
X624240Y246231D01*
X624260Y246271D01*
X624275Y246311D01*
X624285Y246351D01*
X624300Y246396D01*
X624305Y246436D01*
X624315Y246476D01*
X624320Y246521D01*
Y246561D01*
X624325Y246606D01*
X624320Y246651D01*
Y246691D01*
X624315Y246736D01*
X624305Y246776D01*
X624300Y246816D01*
X624285Y246861D01*
X624275Y246901D01*
X624260Y246941D01*
X624240Y246981D01*
X624225Y247016D01*
X624205Y247056D01*
X624105Y247196D01*
X624075Y247226D01*
Y249356D01*
X624065Y249481D01*
X624025Y249606D01*
X623965Y249716D01*
X623885Y249816D01*
X623785Y249896D01*
X623675Y249956D01*
X623550Y249996D01*
X623425Y250006D01*
G37*
G36*
G01X628150D02*
X628025Y249996D01*
X627900Y249956D01*
X627790Y249896D01*
X627690Y249816D01*
X627610Y249716D01*
X627550Y249606D01*
X627510Y249481D01*
X627500Y249356D01*
Y247231D01*
X627470Y247201D01*
X627445Y247166D01*
X627415Y247131D01*
X627395Y247096D01*
X627370Y247061D01*
X627330Y246981D01*
X627285Y246861D01*
X627275Y246821D01*
X627265Y246776D01*
X627260Y246736D01*
X627250Y246691D01*
Y246521D01*
X627260Y246476D01*
X627265Y246436D01*
X627275Y246391D01*
X627285Y246351D01*
X627330Y246231D01*
X627370Y246151D01*
X627395Y246116D01*
X627415Y246081D01*
X627445Y246046D01*
X627470Y246011D01*
X627500Y245981D01*
Y243556D01*
X627510Y243431D01*
X627550Y243306D01*
X627610Y243196D01*
X627690Y243096D01*
X627790Y243016D01*
X627900Y242956D01*
X628025Y242916D01*
X628150Y242906D01*
X628275Y242916D01*
X628400Y242956D01*
X628510Y243016D01*
X628610Y243096D01*
X628690Y243196D01*
X628750Y243306D01*
X628790Y243431D01*
X628800Y243556D01*
Y245986D01*
X628830Y246016D01*
X628930Y246156D01*
X628950Y246196D01*
X628965Y246231D01*
X628985Y246271D01*
X629000Y246311D01*
X629010Y246351D01*
X629025Y246396D01*
X629030Y246436D01*
X629040Y246476D01*
X629045Y246521D01*
Y246561D01*
X629050Y246606D01*
X629045Y246651D01*
Y246691D01*
X629040Y246736D01*
X629030Y246776D01*
X629025Y246816D01*
X629010Y246861D01*
X629000Y246901D01*
X628985Y246941D01*
X628965Y246981D01*
X628950Y247016D01*
X628930Y247056D01*
X628830Y247196D01*
X628800Y247226D01*
Y249356D01*
X628790Y249481D01*
X628750Y249606D01*
X628690Y249716D01*
X628610Y249816D01*
X628510Y249896D01*
X628400Y249956D01*
X628275Y249996D01*
X628150Y250006D01*
G37*
G36*
G01X632874D02*
X632749Y249996D01*
X632624Y249956D01*
X632514Y249896D01*
X632414Y249816D01*
X632334Y249716D01*
X632274Y249606D01*
X632234Y249481D01*
X632224Y249356D01*
Y247231D01*
X632194Y247201D01*
X632169Y247166D01*
X632139Y247131D01*
X632119Y247096D01*
X632094Y247061D01*
X632054Y246981D01*
X632009Y246861D01*
X631999Y246821D01*
X631989Y246776D01*
X631984Y246736D01*
X631974Y246691D01*
Y246521D01*
X631984Y246476D01*
X631989Y246436D01*
X631999Y246391D01*
X632009Y246351D01*
X632054Y246231D01*
X632094Y246151D01*
X632119Y246116D01*
X632139Y246081D01*
X632169Y246046D01*
X632194Y246011D01*
X632224Y245981D01*
Y243556D01*
X632234Y243431D01*
X632274Y243306D01*
X632334Y243196D01*
X632414Y243096D01*
X632514Y243016D01*
X632624Y242956D01*
X632749Y242916D01*
X632874Y242906D01*
X632999Y242916D01*
X633124Y242956D01*
X633234Y243016D01*
X633334Y243096D01*
X633414Y243196D01*
X633474Y243306D01*
X633514Y243431D01*
X633524Y243556D01*
Y245986D01*
X633554Y246016D01*
X633654Y246156D01*
X633674Y246196D01*
X633689Y246231D01*
X633709Y246271D01*
X633724Y246311D01*
X633734Y246351D01*
X633749Y246396D01*
X633754Y246436D01*
X633764Y246476D01*
X633769Y246521D01*
Y246561D01*
X633774Y246606D01*
X633769Y246651D01*
Y246691D01*
X633764Y246736D01*
X633754Y246776D01*
X633749Y246816D01*
X633734Y246861D01*
X633724Y246901D01*
X633709Y246941D01*
X633689Y246981D01*
X633674Y247016D01*
X633654Y247056D01*
X633554Y247196D01*
X633524Y247226D01*
Y249356D01*
X633514Y249481D01*
X633474Y249606D01*
X633414Y249716D01*
X633334Y249816D01*
X633234Y249896D01*
X633124Y249956D01*
X632999Y249996D01*
X632874Y250006D01*
G37*
G36*
G01X637599D02*
X637474Y249996D01*
X637349Y249956D01*
X637239Y249896D01*
X637139Y249816D01*
X637059Y249716D01*
X636999Y249606D01*
X636959Y249481D01*
X636949Y249356D01*
Y247231D01*
X636919Y247201D01*
X636894Y247166D01*
X636864Y247131D01*
X636844Y247096D01*
X636819Y247061D01*
X636779Y246981D01*
X636734Y246861D01*
X636724Y246821D01*
X636714Y246776D01*
X636709Y246736D01*
X636699Y246691D01*
Y246521D01*
X636709Y246476D01*
X636714Y246436D01*
X636724Y246391D01*
X636734Y246351D01*
X636779Y246231D01*
X636819Y246151D01*
X636844Y246116D01*
X636864Y246081D01*
X636894Y246046D01*
X636919Y246011D01*
X636949Y245981D01*
Y243556D01*
X636959Y243431D01*
X636999Y243306D01*
X637059Y243196D01*
X637139Y243096D01*
X637239Y243016D01*
X637349Y242956D01*
X637474Y242916D01*
X637599Y242906D01*
X637724Y242916D01*
X637849Y242956D01*
X637959Y243016D01*
X638059Y243096D01*
X638139Y243196D01*
X638199Y243306D01*
X638239Y243431D01*
X638249Y243556D01*
Y245986D01*
X638279Y246016D01*
X638379Y246156D01*
X638399Y246196D01*
X638414Y246231D01*
X638434Y246271D01*
X638449Y246311D01*
X638459Y246351D01*
X638474Y246396D01*
X638479Y246436D01*
X638489Y246476D01*
X638494Y246521D01*
Y246561D01*
X638499Y246606D01*
X638494Y246651D01*
Y246691D01*
X638489Y246736D01*
X638479Y246776D01*
X638474Y246816D01*
X638459Y246861D01*
X638449Y246901D01*
X638434Y246941D01*
X638414Y246981D01*
X638399Y247016D01*
X638379Y247056D01*
X638279Y247196D01*
X638249Y247226D01*
Y249356D01*
X638239Y249481D01*
X638199Y249606D01*
X638139Y249716D01*
X638059Y249816D01*
X637959Y249896D01*
X637849Y249956D01*
X637724Y249996D01*
X637599Y250006D01*
G37*
G36*
G01X642323D02*
X642198Y249996D01*
X642073Y249956D01*
X641963Y249896D01*
X641863Y249816D01*
X641783Y249716D01*
X641723Y249606D01*
X641683Y249481D01*
X641673Y249356D01*
Y247231D01*
X641643Y247201D01*
X641618Y247166D01*
X641588Y247131D01*
X641568Y247096D01*
X641543Y247061D01*
X641503Y246981D01*
X641458Y246861D01*
X641448Y246821D01*
X641438Y246776D01*
X641433Y246736D01*
X641423Y246691D01*
Y246521D01*
X641433Y246476D01*
X641438Y246436D01*
X641448Y246391D01*
X641458Y246351D01*
X641503Y246231D01*
X641543Y246151D01*
X641568Y246116D01*
X641588Y246081D01*
X641618Y246046D01*
X641643Y246011D01*
X641673Y245981D01*
Y243556D01*
X641683Y243431D01*
X641723Y243306D01*
X641783Y243196D01*
X641863Y243096D01*
X641963Y243016D01*
X642073Y242956D01*
X642198Y242916D01*
X642323Y242906D01*
X642448Y242916D01*
X642573Y242956D01*
X642683Y243016D01*
X642783Y243096D01*
X642863Y243196D01*
X642923Y243306D01*
X642963Y243431D01*
X642973Y243556D01*
Y245986D01*
X643003Y246016D01*
X643103Y246156D01*
X643123Y246196D01*
X643138Y246231D01*
X643158Y246271D01*
X643173Y246311D01*
X643183Y246351D01*
X643198Y246396D01*
X643203Y246436D01*
X643213Y246476D01*
X643218Y246521D01*
Y246561D01*
X643223Y246606D01*
X643218Y246651D01*
Y246691D01*
X643213Y246736D01*
X643203Y246776D01*
X643198Y246816D01*
X643183Y246861D01*
X643173Y246901D01*
X643158Y246941D01*
X643138Y246981D01*
X643123Y247016D01*
X643103Y247056D01*
X643003Y247196D01*
X642973Y247226D01*
Y249356D01*
X642963Y249481D01*
X642923Y249606D01*
X642863Y249716D01*
X642783Y249816D01*
X642683Y249896D01*
X642573Y249956D01*
X642448Y249996D01*
X642323Y250006D01*
G37*
G36*
G01X647047D02*
X646922Y249996D01*
X646797Y249956D01*
X646687Y249896D01*
X646587Y249816D01*
X646507Y249716D01*
X646447Y249606D01*
X646407Y249481D01*
X646397Y249356D01*
Y247231D01*
X646367Y247201D01*
X646342Y247166D01*
X646312Y247131D01*
X646292Y247096D01*
X646267Y247061D01*
X646227Y246981D01*
X646182Y246861D01*
X646172Y246821D01*
X646162Y246776D01*
X646157Y246736D01*
X646147Y246691D01*
Y246521D01*
X646157Y246476D01*
X646162Y246436D01*
X646172Y246391D01*
X646182Y246351D01*
X646227Y246231D01*
X646267Y246151D01*
X646292Y246116D01*
X646312Y246081D01*
X646342Y246046D01*
X646367Y246011D01*
X646397Y245981D01*
Y243556D01*
X646407Y243431D01*
X646447Y243306D01*
X646507Y243196D01*
X646587Y243096D01*
X646687Y243016D01*
X646797Y242956D01*
X646922Y242916D01*
X647047Y242906D01*
X647172Y242916D01*
X647297Y242956D01*
X647407Y243016D01*
X647507Y243096D01*
X647587Y243196D01*
X647647Y243306D01*
X647687Y243431D01*
X647697Y243556D01*
Y245986D01*
X647727Y246016D01*
X647827Y246156D01*
X647847Y246196D01*
X647862Y246231D01*
X647882Y246271D01*
X647897Y246311D01*
X647907Y246351D01*
X647922Y246396D01*
X647927Y246436D01*
X647937Y246476D01*
X647942Y246521D01*
Y246561D01*
X647947Y246606D01*
X647942Y246651D01*
Y246691D01*
X647937Y246736D01*
X647927Y246776D01*
X647922Y246816D01*
X647907Y246861D01*
X647897Y246901D01*
X647882Y246941D01*
X647862Y246981D01*
X647847Y247016D01*
X647827Y247056D01*
X647727Y247196D01*
X647697Y247226D01*
Y249356D01*
X647687Y249481D01*
X647647Y249606D01*
X647587Y249716D01*
X647507Y249816D01*
X647407Y249896D01*
X647297Y249956D01*
X647172Y249996D01*
X647047Y250006D01*
G37*
G36*
G01X651772D02*
X651647Y249996D01*
X651522Y249956D01*
X651412Y249896D01*
X651312Y249816D01*
X651232Y249716D01*
X651172Y249606D01*
X651132Y249481D01*
X651122Y249356D01*
Y247231D01*
X651092Y247201D01*
X651067Y247166D01*
X651037Y247131D01*
X651017Y247096D01*
X650992Y247061D01*
X650952Y246981D01*
X650907Y246861D01*
X650897Y246821D01*
X650887Y246776D01*
X650882Y246736D01*
X650872Y246691D01*
Y246521D01*
X650882Y246476D01*
X650887Y246436D01*
X650897Y246391D01*
X650907Y246351D01*
X650952Y246231D01*
X650992Y246151D01*
X651017Y246116D01*
X651037Y246081D01*
X651067Y246046D01*
X651092Y246011D01*
X651122Y245981D01*
Y243556D01*
X651132Y243431D01*
X651172Y243306D01*
X651232Y243196D01*
X651312Y243096D01*
X651412Y243016D01*
X651522Y242956D01*
X651647Y242916D01*
X651772Y242906D01*
X651897Y242916D01*
X652022Y242956D01*
X652132Y243016D01*
X652232Y243096D01*
X652312Y243196D01*
X652372Y243306D01*
X652412Y243431D01*
X652422Y243556D01*
Y245986D01*
X652452Y246016D01*
X652552Y246156D01*
X652572Y246196D01*
X652587Y246231D01*
X652607Y246271D01*
X652622Y246311D01*
X652632Y246351D01*
X652647Y246396D01*
X652652Y246436D01*
X652662Y246476D01*
X652667Y246521D01*
Y246561D01*
X652672Y246606D01*
X652667Y246651D01*
Y246691D01*
X652662Y246736D01*
X652652Y246776D01*
X652647Y246816D01*
X652632Y246861D01*
X652622Y246901D01*
X652607Y246941D01*
X652587Y246981D01*
X652572Y247016D01*
X652552Y247056D01*
X652452Y247196D01*
X652422Y247226D01*
Y249356D01*
X652412Y249481D01*
X652372Y249606D01*
X652312Y249716D01*
X652232Y249816D01*
X652132Y249896D01*
X652022Y249956D01*
X651897Y249996D01*
X651772Y250006D01*
G37*
G36*
G01X665945D02*
X665820Y249996D01*
X665695Y249956D01*
X665585Y249896D01*
X665485Y249816D01*
X665405Y249716D01*
X665345Y249606D01*
X665305Y249481D01*
X665295Y249356D01*
Y247231D01*
X665265Y247201D01*
X665240Y247166D01*
X665210Y247131D01*
X665190Y247096D01*
X665165Y247061D01*
X665125Y246981D01*
X665080Y246861D01*
X665070Y246821D01*
X665060Y246776D01*
X665055Y246736D01*
X665045Y246691D01*
Y246521D01*
X665055Y246476D01*
X665060Y246436D01*
X665070Y246391D01*
X665080Y246351D01*
X665125Y246231D01*
X665165Y246151D01*
X665190Y246116D01*
X665210Y246081D01*
X665240Y246046D01*
X665265Y246011D01*
X665295Y245981D01*
Y243556D01*
X665305Y243431D01*
X665345Y243306D01*
X665405Y243196D01*
X665485Y243096D01*
X665585Y243016D01*
X665695Y242956D01*
X665820Y242916D01*
X665945Y242906D01*
X666070Y242916D01*
X666195Y242956D01*
X666305Y243016D01*
X666405Y243096D01*
X666485Y243196D01*
X666545Y243306D01*
X666585Y243431D01*
X666595Y243556D01*
Y245986D01*
X666625Y246016D01*
X666725Y246156D01*
X666745Y246196D01*
X666760Y246231D01*
X666780Y246271D01*
X666795Y246311D01*
X666805Y246351D01*
X666820Y246396D01*
X666825Y246436D01*
X666835Y246476D01*
X666840Y246521D01*
Y246561D01*
X666845Y246606D01*
X666840Y246651D01*
Y246691D01*
X666835Y246736D01*
X666825Y246776D01*
X666820Y246816D01*
X666805Y246861D01*
X666795Y246901D01*
X666780Y246941D01*
X666760Y246981D01*
X666745Y247016D01*
X666725Y247056D01*
X666625Y247196D01*
X666595Y247226D01*
Y249356D01*
X666585Y249481D01*
X666545Y249606D01*
X666485Y249716D01*
X666405Y249816D01*
X666305Y249896D01*
X666195Y249956D01*
X666070Y249996D01*
X665945Y250006D01*
G37*
G36*
G01X670670D02*
X670545Y249996D01*
X670420Y249956D01*
X670310Y249896D01*
X670210Y249816D01*
X670130Y249716D01*
X670070Y249606D01*
X670030Y249481D01*
X670020Y249356D01*
Y247231D01*
X669990Y247201D01*
X669965Y247166D01*
X669935Y247131D01*
X669915Y247096D01*
X669890Y247061D01*
X669850Y246981D01*
X669805Y246861D01*
X669795Y246821D01*
X669785Y246776D01*
X669780Y246736D01*
X669770Y246691D01*
Y246521D01*
X669780Y246476D01*
X669785Y246436D01*
X669795Y246391D01*
X669805Y246351D01*
X669850Y246231D01*
X669890Y246151D01*
X669915Y246116D01*
X669935Y246081D01*
X669965Y246046D01*
X669990Y246011D01*
X670020Y245981D01*
Y243556D01*
X670030Y243431D01*
X670070Y243306D01*
X670130Y243196D01*
X670210Y243096D01*
X670310Y243016D01*
X670420Y242956D01*
X670545Y242916D01*
X670670Y242906D01*
X670795Y242916D01*
X670920Y242956D01*
X671030Y243016D01*
X671130Y243096D01*
X671210Y243196D01*
X671270Y243306D01*
X671310Y243431D01*
X671320Y243556D01*
Y245986D01*
X671350Y246016D01*
X671450Y246156D01*
X671470Y246196D01*
X671485Y246231D01*
X671505Y246271D01*
X671520Y246311D01*
X671530Y246351D01*
X671545Y246396D01*
X671550Y246436D01*
X671560Y246476D01*
X671565Y246521D01*
Y246561D01*
X671570Y246606D01*
X671565Y246651D01*
Y246691D01*
X671560Y246736D01*
X671550Y246776D01*
X671545Y246816D01*
X671530Y246861D01*
X671520Y246901D01*
X671505Y246941D01*
X671485Y246981D01*
X671470Y247016D01*
X671450Y247056D01*
X671350Y247196D01*
X671320Y247226D01*
Y249356D01*
X671310Y249481D01*
X671270Y249606D01*
X671210Y249716D01*
X671130Y249816D01*
X671030Y249896D01*
X670920Y249956D01*
X670795Y249996D01*
X670670Y250006D01*
G37*
G36*
G01X675394D02*
X675269Y249996D01*
X675144Y249956D01*
X675034Y249896D01*
X674934Y249816D01*
X674854Y249716D01*
X674794Y249606D01*
X674754Y249481D01*
X674744Y249356D01*
Y247231D01*
X674714Y247201D01*
X674689Y247166D01*
X674659Y247131D01*
X674639Y247096D01*
X674614Y247061D01*
X674574Y246981D01*
X674529Y246861D01*
X674519Y246821D01*
X674509Y246776D01*
X674504Y246736D01*
X674494Y246691D01*
Y246521D01*
X674504Y246476D01*
X674509Y246436D01*
X674519Y246391D01*
X674529Y246351D01*
X674574Y246231D01*
X674614Y246151D01*
X674639Y246116D01*
X674659Y246081D01*
X674689Y246046D01*
X674714Y246011D01*
X674744Y245981D01*
Y243556D01*
X674754Y243431D01*
X674794Y243306D01*
X674854Y243196D01*
X674934Y243096D01*
X675034Y243016D01*
X675144Y242956D01*
X675269Y242916D01*
X675394Y242906D01*
X675519Y242916D01*
X675644Y242956D01*
X675754Y243016D01*
X675854Y243096D01*
X675934Y243196D01*
X675994Y243306D01*
X676034Y243431D01*
X676044Y243556D01*
Y245986D01*
X676074Y246016D01*
X676174Y246156D01*
X676194Y246196D01*
X676209Y246231D01*
X676229Y246271D01*
X676244Y246311D01*
X676254Y246351D01*
X676269Y246396D01*
X676274Y246436D01*
X676284Y246476D01*
X676289Y246521D01*
Y246561D01*
X676294Y246606D01*
X676289Y246651D01*
Y246691D01*
X676284Y246736D01*
X676274Y246776D01*
X676269Y246816D01*
X676254Y246861D01*
X676244Y246901D01*
X676229Y246941D01*
X676209Y246981D01*
X676194Y247016D01*
X676174Y247056D01*
X676074Y247196D01*
X676044Y247226D01*
Y249356D01*
X676034Y249481D01*
X675994Y249606D01*
X675934Y249716D01*
X675854Y249816D01*
X675754Y249896D01*
X675644Y249956D01*
X675519Y249996D01*
X675394Y250006D01*
G37*
G36*
G01X680118D02*
X679993Y249996D01*
X679868Y249956D01*
X679758Y249896D01*
X679658Y249816D01*
X679578Y249716D01*
X679518Y249606D01*
X679478Y249481D01*
X679468Y249356D01*
Y247231D01*
X679438Y247201D01*
X679413Y247166D01*
X679383Y247131D01*
X679363Y247096D01*
X679338Y247061D01*
X679298Y246981D01*
X679253Y246861D01*
X679243Y246821D01*
X679233Y246776D01*
X679228Y246736D01*
X679218Y246691D01*
Y246521D01*
X679228Y246476D01*
X679233Y246436D01*
X679243Y246391D01*
X679253Y246351D01*
X679298Y246231D01*
X679338Y246151D01*
X679363Y246116D01*
X679383Y246081D01*
X679413Y246046D01*
X679438Y246011D01*
X679468Y245981D01*
Y243556D01*
X679478Y243431D01*
X679518Y243306D01*
X679578Y243196D01*
X679658Y243096D01*
X679758Y243016D01*
X679868Y242956D01*
X679993Y242916D01*
X680118Y242906D01*
X680243Y242916D01*
X680368Y242956D01*
X680478Y243016D01*
X680578Y243096D01*
X680658Y243196D01*
X680718Y243306D01*
X680758Y243431D01*
X680768Y243556D01*
Y245986D01*
X680798Y246016D01*
X680898Y246156D01*
X680918Y246196D01*
X680933Y246231D01*
X680953Y246271D01*
X680968Y246311D01*
X680978Y246351D01*
X680993Y246396D01*
X680998Y246436D01*
X681008Y246476D01*
X681013Y246521D01*
Y246561D01*
X681018Y246606D01*
X681013Y246651D01*
Y246691D01*
X681008Y246736D01*
X680998Y246776D01*
X680993Y246816D01*
X680978Y246861D01*
X680968Y246901D01*
X680953Y246941D01*
X680933Y246981D01*
X680918Y247016D01*
X680898Y247056D01*
X680798Y247196D01*
X680768Y247226D01*
Y249356D01*
X680758Y249481D01*
X680718Y249606D01*
X680658Y249716D01*
X680578Y249816D01*
X680478Y249896D01*
X680368Y249956D01*
X680243Y249996D01*
X680118Y250006D01*
G37*
G36*
G01X684843D02*
X684718Y249996D01*
X684593Y249956D01*
X684483Y249896D01*
X684383Y249816D01*
X684303Y249716D01*
X684243Y249606D01*
X684203Y249481D01*
X684193Y249356D01*
Y247231D01*
X684163Y247201D01*
X684138Y247166D01*
X684108Y247131D01*
X684088Y247096D01*
X684063Y247061D01*
X684023Y246981D01*
X683978Y246861D01*
X683968Y246821D01*
X683958Y246776D01*
X683953Y246736D01*
X683943Y246691D01*
Y246521D01*
X683953Y246476D01*
X683958Y246436D01*
X683968Y246391D01*
X683978Y246351D01*
X684023Y246231D01*
X684063Y246151D01*
X684088Y246116D01*
X684108Y246081D01*
X684138Y246046D01*
X684163Y246011D01*
X684193Y245981D01*
Y243556D01*
X684203Y243431D01*
X684243Y243306D01*
X684303Y243196D01*
X684383Y243096D01*
X684483Y243016D01*
X684593Y242956D01*
X684718Y242916D01*
X684843Y242906D01*
X684968Y242916D01*
X685093Y242956D01*
X685203Y243016D01*
X685303Y243096D01*
X685383Y243196D01*
X685443Y243306D01*
X685483Y243431D01*
X685493Y243556D01*
Y245986D01*
X685523Y246016D01*
X685623Y246156D01*
X685643Y246196D01*
X685658Y246231D01*
X685678Y246271D01*
X685693Y246311D01*
X685703Y246351D01*
X685718Y246396D01*
X685723Y246436D01*
X685733Y246476D01*
X685738Y246521D01*
Y246561D01*
X685743Y246606D01*
X685738Y246651D01*
Y246691D01*
X685733Y246736D01*
X685723Y246776D01*
X685718Y246816D01*
X685703Y246861D01*
X685693Y246901D01*
X685678Y246941D01*
X685658Y246981D01*
X685643Y247016D01*
X685623Y247056D01*
X685523Y247196D01*
X685493Y247226D01*
Y249356D01*
X685483Y249481D01*
X685443Y249606D01*
X685383Y249716D01*
X685303Y249816D01*
X685203Y249896D01*
X685093Y249956D01*
X684968Y249996D01*
X684843Y250006D01*
G37*
G36*
G01X689567D02*
X689442Y249996D01*
X689317Y249956D01*
X689207Y249896D01*
X689107Y249816D01*
X689027Y249716D01*
X688967Y249606D01*
X688927Y249481D01*
X688917Y249356D01*
Y247231D01*
X688887Y247201D01*
X688862Y247166D01*
X688832Y247131D01*
X688812Y247096D01*
X688787Y247061D01*
X688747Y246981D01*
X688702Y246861D01*
X688692Y246821D01*
X688682Y246776D01*
X688677Y246736D01*
X688667Y246691D01*
Y246521D01*
X688677Y246476D01*
X688682Y246436D01*
X688692Y246391D01*
X688702Y246351D01*
X688747Y246231D01*
X688787Y246151D01*
X688812Y246116D01*
X688832Y246081D01*
X688862Y246046D01*
X688887Y246011D01*
X688917Y245981D01*
Y243556D01*
X688927Y243431D01*
X688967Y243306D01*
X689027Y243196D01*
X689107Y243096D01*
X689207Y243016D01*
X689317Y242956D01*
X689442Y242916D01*
X689567Y242906D01*
X689692Y242916D01*
X689817Y242956D01*
X689927Y243016D01*
X690027Y243096D01*
X690107Y243196D01*
X690167Y243306D01*
X690207Y243431D01*
X690217Y243556D01*
Y245986D01*
X690247Y246016D01*
X690347Y246156D01*
X690367Y246196D01*
X690382Y246231D01*
X690402Y246271D01*
X690417Y246311D01*
X690427Y246351D01*
X690442Y246396D01*
X690447Y246436D01*
X690457Y246476D01*
X690462Y246521D01*
Y246561D01*
X690467Y246606D01*
X690462Y246651D01*
Y246691D01*
X690457Y246736D01*
X690447Y246776D01*
X690442Y246816D01*
X690427Y246861D01*
X690417Y246901D01*
X690402Y246941D01*
X690382Y246981D01*
X690367Y247016D01*
X690347Y247056D01*
X690247Y247196D01*
X690217Y247226D01*
Y249356D01*
X690207Y249481D01*
X690167Y249606D01*
X690107Y249716D01*
X690027Y249816D01*
X689927Y249896D01*
X689817Y249956D01*
X689692Y249996D01*
X689567Y250006D01*
G37*
G36*
G01X694292D02*
X694167Y249996D01*
X694042Y249956D01*
X693932Y249896D01*
X693832Y249816D01*
X693752Y249716D01*
X693692Y249606D01*
X693652Y249481D01*
X693642Y249356D01*
Y247231D01*
X693612Y247201D01*
X693587Y247166D01*
X693557Y247131D01*
X693537Y247096D01*
X693512Y247061D01*
X693472Y246981D01*
X693427Y246861D01*
X693417Y246821D01*
X693407Y246776D01*
X693402Y246736D01*
X693392Y246691D01*
Y246521D01*
X693402Y246476D01*
X693407Y246436D01*
X693417Y246391D01*
X693427Y246351D01*
X693472Y246231D01*
X693512Y246151D01*
X693537Y246116D01*
X693557Y246081D01*
X693587Y246046D01*
X693612Y246011D01*
X693642Y245981D01*
Y243556D01*
X693652Y243431D01*
X693692Y243306D01*
X693752Y243196D01*
X693832Y243096D01*
X693932Y243016D01*
X694042Y242956D01*
X694167Y242916D01*
X694292Y242906D01*
X694417Y242916D01*
X694542Y242956D01*
X694652Y243016D01*
X694752Y243096D01*
X694832Y243196D01*
X694892Y243306D01*
X694932Y243431D01*
X694942Y243556D01*
Y245986D01*
X694972Y246016D01*
X695072Y246156D01*
X695092Y246196D01*
X695107Y246231D01*
X695127Y246271D01*
X695142Y246311D01*
X695152Y246351D01*
X695167Y246396D01*
X695172Y246436D01*
X695182Y246476D01*
X695187Y246521D01*
Y246561D01*
X695192Y246606D01*
X695187Y246651D01*
Y246691D01*
X695182Y246736D01*
X695172Y246776D01*
X695167Y246816D01*
X695152Y246861D01*
X695142Y246901D01*
X695127Y246941D01*
X695107Y246981D01*
X695092Y247016D01*
X695072Y247056D01*
X694972Y247196D01*
X694942Y247226D01*
Y249356D01*
X694932Y249481D01*
X694892Y249606D01*
X694832Y249716D01*
X694752Y249816D01*
X694652Y249896D01*
X694542Y249956D01*
X694417Y249996D01*
X694292Y250006D01*
G37*
G36*
G01X699016D02*
X698891Y249996D01*
X698766Y249956D01*
X698656Y249896D01*
X698556Y249816D01*
X698476Y249716D01*
X698416Y249606D01*
X698376Y249481D01*
X698366Y249356D01*
Y247231D01*
X698336Y247201D01*
X698311Y247166D01*
X698281Y247131D01*
X698261Y247096D01*
X698236Y247061D01*
X698196Y246981D01*
X698151Y246861D01*
X698141Y246821D01*
X698131Y246776D01*
X698126Y246736D01*
X698116Y246691D01*
Y246521D01*
X698126Y246476D01*
X698131Y246436D01*
X698141Y246391D01*
X698151Y246351D01*
X698196Y246231D01*
X698236Y246151D01*
X698261Y246116D01*
X698281Y246081D01*
X698311Y246046D01*
X698336Y246011D01*
X698366Y245981D01*
Y243556D01*
X698376Y243431D01*
X698416Y243306D01*
X698476Y243196D01*
X698556Y243096D01*
X698656Y243016D01*
X698766Y242956D01*
X698891Y242916D01*
X699016Y242906D01*
X699141Y242916D01*
X699266Y242956D01*
X699376Y243016D01*
X699476Y243096D01*
X699556Y243196D01*
X699616Y243306D01*
X699656Y243431D01*
X699666Y243556D01*
Y245986D01*
X699696Y246016D01*
X699796Y246156D01*
X699816Y246196D01*
X699831Y246231D01*
X699851Y246271D01*
X699866Y246311D01*
X699876Y246351D01*
X699891Y246396D01*
X699896Y246436D01*
X699906Y246476D01*
X699911Y246521D01*
Y246561D01*
X699916Y246606D01*
X699911Y246651D01*
Y246691D01*
X699906Y246736D01*
X699896Y246776D01*
X699891Y246816D01*
X699876Y246861D01*
X699866Y246901D01*
X699851Y246941D01*
X699831Y246981D01*
X699816Y247016D01*
X699796Y247056D01*
X699696Y247196D01*
X699666Y247226D01*
Y249356D01*
X699656Y249481D01*
X699616Y249606D01*
X699556Y249716D01*
X699476Y249816D01*
X699376Y249896D01*
X699266Y249956D01*
X699141Y249996D01*
X699016Y250006D01*
G37*
G36*
G01X703740D02*
X703615Y249996D01*
X703490Y249956D01*
X703380Y249896D01*
X703280Y249816D01*
X703200Y249716D01*
X703140Y249606D01*
X703100Y249481D01*
X703090Y249356D01*
Y247231D01*
X703060Y247201D01*
X703035Y247166D01*
X703005Y247131D01*
X702985Y247096D01*
X702960Y247061D01*
X702920Y246981D01*
X702875Y246861D01*
X702865Y246821D01*
X702855Y246776D01*
X702850Y246736D01*
X702840Y246691D01*
Y246521D01*
X702850Y246476D01*
X702855Y246436D01*
X702865Y246391D01*
X702875Y246351D01*
X702920Y246231D01*
X702960Y246151D01*
X702985Y246116D01*
X703005Y246081D01*
X703035Y246046D01*
X703060Y246011D01*
X703090Y245981D01*
Y243556D01*
X703100Y243431D01*
X703140Y243306D01*
X703200Y243196D01*
X703280Y243096D01*
X703380Y243016D01*
X703490Y242956D01*
X703615Y242916D01*
X703740Y242906D01*
X703865Y242916D01*
X703990Y242956D01*
X704100Y243016D01*
X704200Y243096D01*
X704280Y243196D01*
X704340Y243306D01*
X704380Y243431D01*
X704390Y243556D01*
Y245986D01*
X704420Y246016D01*
X704520Y246156D01*
X704540Y246196D01*
X704555Y246231D01*
X704575Y246271D01*
X704590Y246311D01*
X704600Y246351D01*
X704615Y246396D01*
X704620Y246436D01*
X704630Y246476D01*
X704635Y246521D01*
Y246561D01*
X704640Y246606D01*
X704635Y246651D01*
Y246691D01*
X704630Y246736D01*
X704620Y246776D01*
X704615Y246816D01*
X704600Y246861D01*
X704590Y246901D01*
X704575Y246941D01*
X704555Y246981D01*
X704540Y247016D01*
X704520Y247056D01*
X704420Y247196D01*
X704390Y247226D01*
Y249356D01*
X704380Y249481D01*
X704340Y249606D01*
X704280Y249716D01*
X704200Y249816D01*
X704100Y249896D01*
X703990Y249956D01*
X703865Y249996D01*
X703740Y250006D01*
G37*
G36*
G01X708465D02*
X708340Y249996D01*
X708215Y249956D01*
X708105Y249896D01*
X708005Y249816D01*
X707925Y249716D01*
X707865Y249606D01*
X707825Y249481D01*
X707815Y249356D01*
Y247231D01*
X707785Y247201D01*
X707760Y247166D01*
X707730Y247131D01*
X707710Y247096D01*
X707685Y247061D01*
X707645Y246981D01*
X707600Y246861D01*
X707590Y246821D01*
X707580Y246776D01*
X707575Y246736D01*
X707565Y246691D01*
Y246521D01*
X707575Y246476D01*
X707580Y246436D01*
X707590Y246391D01*
X707600Y246351D01*
X707645Y246231D01*
X707685Y246151D01*
X707710Y246116D01*
X707730Y246081D01*
X707760Y246046D01*
X707785Y246011D01*
X707815Y245981D01*
Y243556D01*
X707825Y243431D01*
X707865Y243306D01*
X707925Y243196D01*
X708005Y243096D01*
X708105Y243016D01*
X708215Y242956D01*
X708340Y242916D01*
X708465Y242906D01*
X708590Y242916D01*
X708715Y242956D01*
X708825Y243016D01*
X708925Y243096D01*
X709005Y243196D01*
X709065Y243306D01*
X709105Y243431D01*
X709115Y243556D01*
Y245986D01*
X709145Y246016D01*
X709245Y246156D01*
X709265Y246196D01*
X709280Y246231D01*
X709300Y246271D01*
X709315Y246311D01*
X709325Y246351D01*
X709340Y246396D01*
X709345Y246436D01*
X709355Y246476D01*
X709360Y246521D01*
Y246561D01*
X709365Y246606D01*
X709360Y246651D01*
Y246691D01*
X709355Y246736D01*
X709345Y246776D01*
X709340Y246816D01*
X709325Y246861D01*
X709315Y246901D01*
X709300Y246941D01*
X709280Y246981D01*
X709265Y247016D01*
X709245Y247056D01*
X709145Y247196D01*
X709115Y247226D01*
Y249356D01*
X709105Y249481D01*
X709065Y249606D01*
X709005Y249716D01*
X708925Y249816D01*
X708825Y249896D01*
X708715Y249956D01*
X708590Y249996D01*
X708465Y250006D01*
G37*
G36*
G01X713189D02*
X713064Y249996D01*
X712939Y249956D01*
X712829Y249896D01*
X712729Y249816D01*
X712649Y249716D01*
X712589Y249606D01*
X712549Y249481D01*
X712539Y249356D01*
Y247231D01*
X712509Y247201D01*
X712484Y247166D01*
X712454Y247131D01*
X712434Y247096D01*
X712409Y247061D01*
X712369Y246981D01*
X712324Y246861D01*
X712314Y246821D01*
X712304Y246776D01*
X712299Y246736D01*
X712289Y246691D01*
Y246521D01*
X712299Y246476D01*
X712304Y246436D01*
X712314Y246391D01*
X712324Y246351D01*
X712369Y246231D01*
X712409Y246151D01*
X712434Y246116D01*
X712454Y246081D01*
X712484Y246046D01*
X712509Y246011D01*
X712539Y245981D01*
Y243556D01*
X712549Y243431D01*
X712589Y243306D01*
X712649Y243196D01*
X712729Y243096D01*
X712829Y243016D01*
X712939Y242956D01*
X713064Y242916D01*
X713189Y242906D01*
X713314Y242916D01*
X713439Y242956D01*
X713549Y243016D01*
X713649Y243096D01*
X713729Y243196D01*
X713789Y243306D01*
X713829Y243431D01*
X713839Y243556D01*
Y245986D01*
X713869Y246016D01*
X713969Y246156D01*
X713989Y246196D01*
X714004Y246231D01*
X714024Y246271D01*
X714039Y246311D01*
X714049Y246351D01*
X714064Y246396D01*
X714069Y246436D01*
X714079Y246476D01*
X714084Y246521D01*
Y246561D01*
X714089Y246606D01*
X714084Y246651D01*
Y246691D01*
X714079Y246736D01*
X714069Y246776D01*
X714064Y246816D01*
X714049Y246861D01*
X714039Y246901D01*
X714024Y246941D01*
X714004Y246981D01*
X713989Y247016D01*
X713969Y247056D01*
X713869Y247196D01*
X713839Y247226D01*
Y249356D01*
X713829Y249481D01*
X713789Y249606D01*
X713729Y249716D01*
X713649Y249816D01*
X713549Y249896D01*
X713439Y249956D01*
X713314Y249996D01*
X713189Y250006D01*
G37*
G36*
G01X717914D02*
X717789Y249996D01*
X717664Y249956D01*
X717554Y249896D01*
X717454Y249816D01*
X717374Y249716D01*
X717314Y249606D01*
X717274Y249481D01*
X717264Y249356D01*
Y247231D01*
X717234Y247201D01*
X717209Y247166D01*
X717179Y247131D01*
X717159Y247096D01*
X717134Y247061D01*
X717094Y246981D01*
X717049Y246861D01*
X717039Y246821D01*
X717029Y246776D01*
X717024Y246736D01*
X717014Y246691D01*
Y246521D01*
X717024Y246476D01*
X717029Y246436D01*
X717039Y246391D01*
X717049Y246351D01*
X717094Y246231D01*
X717134Y246151D01*
X717159Y246116D01*
X717179Y246081D01*
X717209Y246046D01*
X717234Y246011D01*
X717264Y245981D01*
Y243556D01*
X717274Y243431D01*
X717314Y243306D01*
X717374Y243196D01*
X717454Y243096D01*
X717554Y243016D01*
X717664Y242956D01*
X717789Y242916D01*
X717914Y242906D01*
X718039Y242916D01*
X718164Y242956D01*
X718274Y243016D01*
X718374Y243096D01*
X718454Y243196D01*
X718514Y243306D01*
X718554Y243431D01*
X718564Y243556D01*
Y245986D01*
X718594Y246016D01*
X718694Y246156D01*
X718714Y246196D01*
X718729Y246231D01*
X718749Y246271D01*
X718764Y246311D01*
X718774Y246351D01*
X718789Y246396D01*
X718794Y246436D01*
X718804Y246476D01*
X718809Y246521D01*
Y246561D01*
X718814Y246606D01*
X718809Y246651D01*
Y246691D01*
X718804Y246736D01*
X718794Y246776D01*
X718789Y246816D01*
X718774Y246861D01*
X718764Y246901D01*
X718749Y246941D01*
X718729Y246981D01*
X718714Y247016D01*
X718694Y247056D01*
X718594Y247196D01*
X718564Y247226D01*
Y249356D01*
X718554Y249481D01*
X718514Y249606D01*
X718454Y249716D01*
X718374Y249816D01*
X718274Y249896D01*
X718164Y249956D01*
X718039Y249996D01*
X717914Y250006D01*
G37*
G36*
G01X722638D02*
X722513Y249996D01*
X722388Y249956D01*
X722278Y249896D01*
X722178Y249816D01*
X722098Y249716D01*
X722038Y249606D01*
X721998Y249481D01*
X721988Y249356D01*
Y247231D01*
X721958Y247201D01*
X721933Y247166D01*
X721903Y247131D01*
X721883Y247096D01*
X721858Y247061D01*
X721818Y246981D01*
X721773Y246861D01*
X721763Y246821D01*
X721753Y246776D01*
X721748Y246736D01*
X721738Y246691D01*
Y246521D01*
X721748Y246476D01*
X721753Y246436D01*
X721763Y246391D01*
X721773Y246351D01*
X721818Y246231D01*
X721858Y246151D01*
X721883Y246116D01*
X721903Y246081D01*
X721933Y246046D01*
X721958Y246011D01*
X721988Y245981D01*
Y243556D01*
X721998Y243431D01*
X722038Y243306D01*
X722098Y243196D01*
X722178Y243096D01*
X722278Y243016D01*
X722388Y242956D01*
X722513Y242916D01*
X722638Y242906D01*
X722763Y242916D01*
X722888Y242956D01*
X722998Y243016D01*
X723098Y243096D01*
X723178Y243196D01*
X723238Y243306D01*
X723278Y243431D01*
X723288Y243556D01*
Y245986D01*
X723318Y246016D01*
X723418Y246156D01*
X723438Y246196D01*
X723453Y246231D01*
X723473Y246271D01*
X723488Y246311D01*
X723498Y246351D01*
X723513Y246396D01*
X723518Y246436D01*
X723528Y246476D01*
X723533Y246521D01*
Y246561D01*
X723538Y246606D01*
X723533Y246651D01*
Y246691D01*
X723528Y246736D01*
X723518Y246776D01*
X723513Y246816D01*
X723498Y246861D01*
X723488Y246901D01*
X723473Y246941D01*
X723453Y246981D01*
X723438Y247016D01*
X723418Y247056D01*
X723318Y247196D01*
X723288Y247226D01*
Y249356D01*
X723278Y249481D01*
X723238Y249606D01*
X723178Y249716D01*
X723098Y249816D01*
X722998Y249896D01*
X722888Y249956D01*
X722763Y249996D01*
X722638Y250006D01*
G37*
G36*
G01X727362D02*
X727237Y249996D01*
X727112Y249956D01*
X727002Y249896D01*
X726902Y249816D01*
X726822Y249716D01*
X726762Y249606D01*
X726722Y249481D01*
X726712Y249356D01*
Y247231D01*
X726682Y247201D01*
X726657Y247166D01*
X726627Y247131D01*
X726607Y247096D01*
X726582Y247061D01*
X726542Y246981D01*
X726497Y246861D01*
X726487Y246821D01*
X726477Y246776D01*
X726472Y246736D01*
X726462Y246691D01*
Y246521D01*
X726472Y246476D01*
X726477Y246436D01*
X726487Y246391D01*
X726497Y246351D01*
X726542Y246231D01*
X726582Y246151D01*
X726607Y246116D01*
X726627Y246081D01*
X726657Y246046D01*
X726682Y246011D01*
X726712Y245981D01*
Y243556D01*
X726722Y243431D01*
X726762Y243306D01*
X726822Y243196D01*
X726902Y243096D01*
X727002Y243016D01*
X727112Y242956D01*
X727237Y242916D01*
X727362Y242906D01*
X727487Y242916D01*
X727612Y242956D01*
X727722Y243016D01*
X727822Y243096D01*
X727902Y243196D01*
X727962Y243306D01*
X728002Y243431D01*
X728012Y243556D01*
Y245986D01*
X728042Y246016D01*
X728142Y246156D01*
X728162Y246196D01*
X728177Y246231D01*
X728197Y246271D01*
X728212Y246311D01*
X728222Y246351D01*
X728237Y246396D01*
X728242Y246436D01*
X728252Y246476D01*
X728257Y246521D01*
Y246561D01*
X728262Y246606D01*
X728257Y246651D01*
Y246691D01*
X728252Y246736D01*
X728242Y246776D01*
X728237Y246816D01*
X728222Y246861D01*
X728212Y246901D01*
X728197Y246941D01*
X728177Y246981D01*
X728162Y247016D01*
X728142Y247056D01*
X728042Y247196D01*
X728012Y247226D01*
Y249356D01*
X728002Y249481D01*
X727962Y249606D01*
X727902Y249716D01*
X727822Y249816D01*
X727722Y249896D01*
X727612Y249956D01*
X727487Y249996D01*
X727362Y250006D01*
G37*
G36*
G01X732087D02*
X731962Y249996D01*
X731837Y249956D01*
X731727Y249896D01*
X731627Y249816D01*
X731547Y249716D01*
X731487Y249606D01*
X731447Y249481D01*
X731437Y249356D01*
Y247231D01*
X731407Y247201D01*
X731382Y247166D01*
X731352Y247131D01*
X731332Y247096D01*
X731307Y247061D01*
X731267Y246981D01*
X731222Y246861D01*
X731212Y246821D01*
X731202Y246776D01*
X731197Y246736D01*
X731187Y246691D01*
Y246521D01*
X731197Y246476D01*
X731202Y246436D01*
X731212Y246391D01*
X731222Y246351D01*
X731267Y246231D01*
X731307Y246151D01*
X731332Y246116D01*
X731352Y246081D01*
X731382Y246046D01*
X731407Y246011D01*
X731437Y245981D01*
Y243556D01*
X731447Y243431D01*
X731487Y243306D01*
X731547Y243196D01*
X731627Y243096D01*
X731727Y243016D01*
X731837Y242956D01*
X731962Y242916D01*
X732087Y242906D01*
X732212Y242916D01*
X732337Y242956D01*
X732447Y243016D01*
X732547Y243096D01*
X732627Y243196D01*
X732687Y243306D01*
X732727Y243431D01*
X732737Y243556D01*
Y245986D01*
X732767Y246016D01*
X732867Y246156D01*
X732887Y246196D01*
X732902Y246231D01*
X732922Y246271D01*
X732937Y246311D01*
X732947Y246351D01*
X732962Y246396D01*
X732967Y246436D01*
X732977Y246476D01*
X732982Y246521D01*
Y246561D01*
X732987Y246606D01*
X732982Y246651D01*
Y246691D01*
X732977Y246736D01*
X732967Y246776D01*
X732962Y246816D01*
X732947Y246861D01*
X732937Y246901D01*
X732922Y246941D01*
X732902Y246981D01*
X732887Y247016D01*
X732867Y247056D01*
X732767Y247196D01*
X732737Y247226D01*
Y249356D01*
X732727Y249481D01*
X732687Y249606D01*
X732627Y249716D01*
X732547Y249816D01*
X732447Y249896D01*
X732337Y249956D01*
X732212Y249996D01*
X732087Y250006D01*
G37*
G36*
G01X736811D02*
X736686Y249996D01*
X736561Y249956D01*
X736451Y249896D01*
X736351Y249816D01*
X736271Y249716D01*
X736211Y249606D01*
X736171Y249481D01*
X736161Y249356D01*
Y247231D01*
X736131Y247201D01*
X736106Y247166D01*
X736076Y247131D01*
X736056Y247096D01*
X736031Y247061D01*
X735991Y246981D01*
X735946Y246861D01*
X735936Y246821D01*
X735926Y246776D01*
X735921Y246736D01*
X735911Y246691D01*
Y246521D01*
X735921Y246476D01*
X735926Y246436D01*
X735936Y246391D01*
X735946Y246351D01*
X735991Y246231D01*
X736031Y246151D01*
X736056Y246116D01*
X736076Y246081D01*
X736106Y246046D01*
X736131Y246011D01*
X736161Y245981D01*
Y243556D01*
X736171Y243431D01*
X736211Y243306D01*
X736271Y243196D01*
X736351Y243096D01*
X736451Y243016D01*
X736561Y242956D01*
X736686Y242916D01*
X736811Y242906D01*
X736936Y242916D01*
X737061Y242956D01*
X737171Y243016D01*
X737271Y243096D01*
X737351Y243196D01*
X737411Y243306D01*
X737451Y243431D01*
X737461Y243556D01*
Y245986D01*
X737491Y246016D01*
X737591Y246156D01*
X737611Y246196D01*
X737626Y246231D01*
X737646Y246271D01*
X737661Y246311D01*
X737671Y246351D01*
X737686Y246396D01*
X737691Y246436D01*
X737701Y246476D01*
X737706Y246521D01*
Y246561D01*
X737711Y246606D01*
X737706Y246651D01*
Y246691D01*
X737701Y246736D01*
X737691Y246776D01*
X737686Y246816D01*
X737671Y246861D01*
X737661Y246901D01*
X737646Y246941D01*
X737626Y246981D01*
X737611Y247016D01*
X737591Y247056D01*
X737491Y247196D01*
X737461Y247226D01*
Y249356D01*
X737451Y249481D01*
X737411Y249606D01*
X737351Y249716D01*
X737271Y249816D01*
X737171Y249896D01*
X737061Y249956D01*
X736936Y249996D01*
X736811Y250006D01*
G37*
G36*
G01X741536D02*
X741411Y249996D01*
X741286Y249956D01*
X741176Y249896D01*
X741076Y249816D01*
X740996Y249716D01*
X740936Y249606D01*
X740896Y249481D01*
X740886Y249356D01*
Y247231D01*
X740856Y247201D01*
X740831Y247166D01*
X740801Y247131D01*
X740781Y247096D01*
X740756Y247061D01*
X740716Y246981D01*
X740671Y246861D01*
X740661Y246821D01*
X740651Y246776D01*
X740646Y246736D01*
X740636Y246691D01*
Y246521D01*
X740646Y246476D01*
X740651Y246436D01*
X740661Y246391D01*
X740671Y246351D01*
X740716Y246231D01*
X740756Y246151D01*
X740781Y246116D01*
X740801Y246081D01*
X740831Y246046D01*
X740856Y246011D01*
X740886Y245981D01*
Y243556D01*
X740896Y243431D01*
X740936Y243306D01*
X740996Y243196D01*
X741076Y243096D01*
X741176Y243016D01*
X741286Y242956D01*
X741411Y242916D01*
X741536Y242906D01*
X741661Y242916D01*
X741786Y242956D01*
X741896Y243016D01*
X741996Y243096D01*
X742076Y243196D01*
X742136Y243306D01*
X742176Y243431D01*
X742186Y243556D01*
Y245986D01*
X742216Y246016D01*
X742316Y246156D01*
X742336Y246196D01*
X742351Y246231D01*
X742371Y246271D01*
X742386Y246311D01*
X742396Y246351D01*
X742411Y246396D01*
X742416Y246436D01*
X742426Y246476D01*
X742431Y246521D01*
Y246561D01*
X742436Y246606D01*
X742431Y246651D01*
Y246691D01*
X742426Y246736D01*
X742416Y246776D01*
X742411Y246816D01*
X742396Y246861D01*
X742386Y246901D01*
X742371Y246941D01*
X742351Y246981D01*
X742336Y247016D01*
X742316Y247056D01*
X742216Y247196D01*
X742186Y247226D01*
Y249356D01*
X742176Y249481D01*
X742136Y249606D01*
X742076Y249716D01*
X741996Y249816D01*
X741896Y249896D01*
X741786Y249956D01*
X741661Y249996D01*
X741536Y250006D01*
G37*
G36*
G01X746260D02*
X746135Y249996D01*
X746010Y249956D01*
X745900Y249896D01*
X745800Y249816D01*
X745720Y249716D01*
X745660Y249606D01*
X745620Y249481D01*
X745610Y249356D01*
Y247231D01*
X745580Y247201D01*
X745555Y247166D01*
X745525Y247131D01*
X745505Y247096D01*
X745480Y247061D01*
X745440Y246981D01*
X745395Y246861D01*
X745385Y246821D01*
X745375Y246776D01*
X745370Y246736D01*
X745360Y246691D01*
Y246521D01*
X745370Y246476D01*
X745375Y246436D01*
X745385Y246391D01*
X745395Y246351D01*
X745440Y246231D01*
X745480Y246151D01*
X745505Y246116D01*
X745525Y246081D01*
X745555Y246046D01*
X745580Y246011D01*
X745610Y245981D01*
Y243556D01*
X745620Y243431D01*
X745660Y243306D01*
X745720Y243196D01*
X745800Y243096D01*
X745900Y243016D01*
X746010Y242956D01*
X746135Y242916D01*
X746260Y242906D01*
X746385Y242916D01*
X746510Y242956D01*
X746620Y243016D01*
X746720Y243096D01*
X746800Y243196D01*
X746860Y243306D01*
X746900Y243431D01*
X746910Y243556D01*
Y245986D01*
X746940Y246016D01*
X747040Y246156D01*
X747060Y246196D01*
X747075Y246231D01*
X747095Y246271D01*
X747110Y246311D01*
X747120Y246351D01*
X747135Y246396D01*
X747140Y246436D01*
X747150Y246476D01*
X747155Y246521D01*
Y246561D01*
X747160Y246606D01*
X747155Y246651D01*
Y246691D01*
X747150Y246736D01*
X747140Y246776D01*
X747135Y246816D01*
X747120Y246861D01*
X747110Y246901D01*
X747095Y246941D01*
X747075Y246981D01*
X747060Y247016D01*
X747040Y247056D01*
X746940Y247196D01*
X746910Y247226D01*
Y249356D01*
X746900Y249481D01*
X746860Y249606D01*
X746800Y249716D01*
X746720Y249816D01*
X746620Y249896D01*
X746510Y249956D01*
X746385Y249996D01*
X746260Y250006D01*
G37*
G54D55*
X270000Y97750D03*
G54D91*
X787246Y280709D03*
G54D64*
X331500Y244900D03*
X335500D03*
X333500Y250100D03*
G54D46*
X173459Y181448D03*
X175034D03*
X176609D03*
X178184D03*
X179759D03*
X181333D03*
X182908D03*
X184483D03*
X186058D03*
Y203570D03*
X184483D03*
X182908D03*
X181333D03*
X179759D03*
X178184D03*
X176609D03*
X175034D03*
X173459D03*
X187633Y181448D03*
Y203570D03*
G54D37*
X100000Y61000D03*
X125500Y132600D03*
X221800Y48100D03*
X333270Y141240D03*
X438500Y279000D03*
G54D19*
X25700Y131500D03*
X22300D03*
X64200Y94500D03*
X60800D03*
X64300Y135500D03*
Y138500D03*
X78800Y110000D03*
X67700Y135500D03*
Y138500D03*
X74900Y238700D03*
X71500D03*
X82200Y110000D03*
X138200Y67000D03*
X134800D03*
X138200Y64000D03*
X134800D03*
X132200Y169000D03*
X128800D03*
X138600Y192500D03*
X135200D03*
X147200Y112000D03*
X143800D03*
X155200Y195300D03*
X151800D03*
X155200Y198300D03*
X151800D03*
X147200Y194500D03*
X143800D03*
X155300Y257000D03*
X163700Y57500D03*
X160300D03*
X171400Y113200D03*
X168000D03*
X171300Y213000D03*
X158700Y257000D03*
X177300Y61300D03*
X173900D03*
X174700Y213000D03*
X193200Y57500D03*
X189800D03*
X200300Y195000D03*
X202300Y230500D03*
X203700Y195000D03*
X205700Y230500D03*
X261400Y73100D03*
X258000D03*
X263800Y70000D03*
X262200Y146300D03*
X267200Y70000D03*
X265600Y146300D03*
X274200Y247500D03*
X270800D03*
X291900Y90600D03*
X288500D03*
X285200Y95000D03*
X281800D03*
X292300Y97600D03*
X293200Y113000D03*
X289800D03*
X293200Y116000D03*
X289800D03*
X293200Y110000D03*
X289800D03*
X293200Y119000D03*
X289800D03*
X293200Y128000D03*
X289800D03*
X293200Y122000D03*
X289800D03*
X293200Y125000D03*
X289800D03*
X293200Y131000D03*
X289800D03*
X293200Y144500D03*
X289800D03*
X293200Y147500D03*
X289800D03*
X293700Y160500D03*
X290300D03*
X293700Y164000D03*
X290300D03*
X293700Y174000D03*
X290300D03*
X293700Y168000D03*
X290300D03*
X293700Y177500D03*
X290300D03*
X293700Y171000D03*
X290300D03*
X293700Y181500D03*
X290300D03*
X293300Y196500D03*
Y193500D03*
X295700Y97600D03*
X307800Y151300D03*
X296700Y196500D03*
Y193500D03*
X321700Y106500D03*
X318300D03*
X317700Y129200D03*
X314300D03*
X311200Y151300D03*
X340700Y84500D03*
X337300D03*
X337200Y125000D03*
X333800D03*
X341300Y181000D03*
X333700Y254000D03*
X330300D03*
X346150Y159200D03*
X342750D03*
X344700Y181000D03*
X392200Y81000D03*
X388800D03*
X397200Y227500D03*
X393800D03*
X415950Y175623D03*
X419350D03*
X444200Y127063D03*
X440800D03*
X458700Y252000D03*
X455300D03*
X530700Y191500D03*
X527300D03*
X530700Y188500D03*
X527300D03*
X557200Y179000D03*
X553800D03*
X570300Y187000D03*
X566900D03*
X638200Y285000D03*
X634800D03*
X736200Y105500D03*
X732800D03*
X738000Y134100D03*
X734600D03*
X748100Y50007D03*
X744700D03*
X751600Y46507D03*
X748200D03*
X778700Y139000D03*
X775300D03*
X778200Y260000D03*
X774800D03*
X778200Y266000D03*
X774800D03*
X778200Y263000D03*
X774800D03*
G54D56*
X270000Y100250D03*
G54D47*
X180546Y192509D03*
G54D74*
X449150Y143900D03*
X444350Y162800D03*
X467650D03*
X472450Y143900D03*
X780650Y195800D03*
X803950D03*
G54D29*
X63000Y198900D03*
Y204100D03*
X68000Y198900D03*
Y204100D03*
X88800Y218900D03*
Y224100D03*
X109000Y124900D03*
Y130100D03*
X103500Y124900D03*
Y130100D03*
X123500Y164900D03*
Y170100D03*
X157000Y201900D03*
Y207100D03*
X343000Y115900D03*
Y121100D03*
X380500Y68463D03*
Y73663D03*
X376500Y202900D03*
Y208100D03*
X381500Y202900D03*
Y208100D03*
X512500Y56407D03*
Y61607D03*
X517500Y219400D03*
Y224600D03*
X512500Y219400D03*
Y224600D03*
X522500Y219400D03*
Y224600D03*
X622000Y46907D03*
Y52107D03*
X650500Y46907D03*
Y52107D03*
X645300Y49507D03*
Y54707D03*
X747500Y61900D03*
Y67100D03*
X762000Y144400D03*
Y149600D03*
X797000Y173400D03*
Y178600D03*
G36*
G01X502953Y250006D02*
X502828Y249996D01*
X502703Y249956D01*
X502593Y249896D01*
X502493Y249816D01*
X502413Y249716D01*
X502353Y249606D01*
X502313Y249481D01*
X502303Y249356D01*
Y248226D01*
X502273Y248196D01*
X502173Y248056D01*
X502153Y248016D01*
X502138Y247981D01*
X502118Y247941D01*
X502103Y247901D01*
X502093Y247861D01*
X502078Y247816D01*
X502073Y247776D01*
X502063Y247736D01*
X502058Y247691D01*
Y247651D01*
X502053Y247606D01*
X502058Y247561D01*
Y247521D01*
X502063Y247476D01*
X502073Y247436D01*
X502078Y247396D01*
X502093Y247351D01*
X502103Y247311D01*
X502118Y247271D01*
X502138Y247231D01*
X502153Y247196D01*
X502173Y247156D01*
X502273Y247016D01*
X502303Y246986D01*
Y243556D01*
X502313Y243431D01*
X502353Y243306D01*
X502413Y243196D01*
X502493Y243096D01*
X502593Y243016D01*
X502703Y242956D01*
X502828Y242916D01*
X502953Y242906D01*
X503078Y242916D01*
X503203Y242956D01*
X503313Y243016D01*
X503413Y243096D01*
X503493Y243196D01*
X503553Y243306D01*
X503593Y243431D01*
X503603Y243556D01*
Y246986D01*
X503633Y247016D01*
X503733Y247156D01*
X503753Y247196D01*
X503768Y247231D01*
X503788Y247271D01*
X503803Y247311D01*
X503813Y247351D01*
X503828Y247396D01*
X503833Y247436D01*
X503843Y247476D01*
X503848Y247521D01*
Y247561D01*
X503853Y247606D01*
X503848Y247651D01*
Y247691D01*
X503843Y247736D01*
X503833Y247776D01*
X503828Y247816D01*
X503813Y247861D01*
X503803Y247901D01*
X503788Y247941D01*
X503768Y247981D01*
X503753Y248016D01*
X503733Y248056D01*
X503633Y248196D01*
X503603Y248226D01*
Y249356D01*
X503593Y249481D01*
X503553Y249606D01*
X503493Y249716D01*
X503413Y249816D01*
X503313Y249896D01*
X503203Y249956D01*
X503078Y249996D01*
X502953Y250006D01*
G37*
G36*
G01X507677D02*
X507552Y249996D01*
X507427Y249956D01*
X507317Y249896D01*
X507217Y249816D01*
X507137Y249716D01*
X507077Y249606D01*
X507037Y249481D01*
X507027Y249356D01*
Y248226D01*
X506997Y248196D01*
X506897Y248056D01*
X506877Y248016D01*
X506862Y247981D01*
X506842Y247941D01*
X506827Y247901D01*
X506817Y247861D01*
X506802Y247816D01*
X506797Y247776D01*
X506787Y247736D01*
X506782Y247691D01*
Y247651D01*
X506777Y247606D01*
X506782Y247561D01*
Y247521D01*
X506787Y247476D01*
X506797Y247436D01*
X506802Y247396D01*
X506817Y247351D01*
X506827Y247311D01*
X506842Y247271D01*
X506862Y247231D01*
X506877Y247196D01*
X506897Y247156D01*
X506997Y247016D01*
X507027Y246986D01*
Y243556D01*
X507037Y243431D01*
X507077Y243306D01*
X507137Y243196D01*
X507217Y243096D01*
X507317Y243016D01*
X507427Y242956D01*
X507552Y242916D01*
X507677Y242906D01*
X507802Y242916D01*
X507927Y242956D01*
X508037Y243016D01*
X508137Y243096D01*
X508217Y243196D01*
X508277Y243306D01*
X508317Y243431D01*
X508327Y243556D01*
Y246986D01*
X508357Y247016D01*
X508457Y247156D01*
X508477Y247196D01*
X508492Y247231D01*
X508512Y247271D01*
X508527Y247311D01*
X508537Y247351D01*
X508552Y247396D01*
X508557Y247436D01*
X508567Y247476D01*
X508572Y247521D01*
Y247561D01*
X508577Y247606D01*
X508572Y247651D01*
Y247691D01*
X508567Y247736D01*
X508557Y247776D01*
X508552Y247816D01*
X508537Y247861D01*
X508527Y247901D01*
X508512Y247941D01*
X508492Y247981D01*
X508477Y248016D01*
X508457Y248056D01*
X508357Y248196D01*
X508327Y248226D01*
Y249356D01*
X508317Y249481D01*
X508277Y249606D01*
X508217Y249716D01*
X508137Y249816D01*
X508037Y249896D01*
X507927Y249956D01*
X507802Y249996D01*
X507677Y250006D01*
G37*
G36*
G01X512402D02*
X512277Y249996D01*
X512152Y249956D01*
X512042Y249896D01*
X511942Y249816D01*
X511862Y249716D01*
X511802Y249606D01*
X511762Y249481D01*
X511752Y249356D01*
Y248226D01*
X511722Y248196D01*
X511622Y248056D01*
X511602Y248016D01*
X511587Y247981D01*
X511567Y247941D01*
X511552Y247901D01*
X511542Y247861D01*
X511527Y247816D01*
X511522Y247776D01*
X511512Y247736D01*
X511507Y247691D01*
Y247651D01*
X511502Y247606D01*
X511507Y247561D01*
Y247521D01*
X511512Y247476D01*
X511522Y247436D01*
X511527Y247396D01*
X511542Y247351D01*
X511552Y247311D01*
X511567Y247271D01*
X511587Y247231D01*
X511602Y247196D01*
X511622Y247156D01*
X511722Y247016D01*
X511752Y246986D01*
Y243556D01*
X511762Y243431D01*
X511802Y243306D01*
X511862Y243196D01*
X511942Y243096D01*
X512042Y243016D01*
X512152Y242956D01*
X512277Y242916D01*
X512402Y242906D01*
X512527Y242916D01*
X512652Y242956D01*
X512762Y243016D01*
X512862Y243096D01*
X512942Y243196D01*
X513002Y243306D01*
X513042Y243431D01*
X513052Y243556D01*
Y246986D01*
X513082Y247016D01*
X513182Y247156D01*
X513202Y247196D01*
X513217Y247231D01*
X513237Y247271D01*
X513252Y247311D01*
X513262Y247351D01*
X513277Y247396D01*
X513282Y247436D01*
X513292Y247476D01*
X513297Y247521D01*
Y247561D01*
X513302Y247606D01*
X513297Y247651D01*
Y247691D01*
X513292Y247736D01*
X513282Y247776D01*
X513277Y247816D01*
X513262Y247861D01*
X513252Y247901D01*
X513237Y247941D01*
X513217Y247981D01*
X513202Y248016D01*
X513182Y248056D01*
X513082Y248196D01*
X513052Y248226D01*
Y249356D01*
X513042Y249481D01*
X513002Y249606D01*
X512942Y249716D01*
X512862Y249816D01*
X512762Y249896D01*
X512652Y249956D01*
X512527Y249996D01*
X512402Y250006D01*
G37*
G36*
G01X517126D02*
X517001Y249996D01*
X516876Y249956D01*
X516766Y249896D01*
X516666Y249816D01*
X516586Y249716D01*
X516526Y249606D01*
X516486Y249481D01*
X516476Y249356D01*
Y248226D01*
X516446Y248196D01*
X516346Y248056D01*
X516326Y248016D01*
X516311Y247981D01*
X516291Y247941D01*
X516276Y247901D01*
X516266Y247861D01*
X516251Y247816D01*
X516246Y247776D01*
X516236Y247736D01*
X516231Y247691D01*
Y247651D01*
X516226Y247606D01*
X516231Y247561D01*
Y247521D01*
X516236Y247476D01*
X516246Y247436D01*
X516251Y247396D01*
X516266Y247351D01*
X516276Y247311D01*
X516291Y247271D01*
X516311Y247231D01*
X516326Y247196D01*
X516346Y247156D01*
X516446Y247016D01*
X516476Y246986D01*
Y243556D01*
X516486Y243431D01*
X516526Y243306D01*
X516586Y243196D01*
X516666Y243096D01*
X516766Y243016D01*
X516876Y242956D01*
X517001Y242916D01*
X517126Y242906D01*
X517251Y242916D01*
X517376Y242956D01*
X517486Y243016D01*
X517586Y243096D01*
X517666Y243196D01*
X517726Y243306D01*
X517766Y243431D01*
X517776Y243556D01*
Y246986D01*
X517806Y247016D01*
X517906Y247156D01*
X517926Y247196D01*
X517941Y247231D01*
X517961Y247271D01*
X517976Y247311D01*
X517986Y247351D01*
X518001Y247396D01*
X518006Y247436D01*
X518016Y247476D01*
X518021Y247521D01*
Y247561D01*
X518026Y247606D01*
X518021Y247651D01*
Y247691D01*
X518016Y247736D01*
X518006Y247776D01*
X518001Y247816D01*
X517986Y247861D01*
X517976Y247901D01*
X517961Y247941D01*
X517941Y247981D01*
X517926Y248016D01*
X517906Y248056D01*
X517806Y248196D01*
X517776Y248226D01*
Y249356D01*
X517766Y249481D01*
X517726Y249606D01*
X517666Y249716D01*
X517586Y249816D01*
X517486Y249896D01*
X517376Y249956D01*
X517251Y249996D01*
X517126Y250006D01*
G37*
G36*
G01X521851D02*
X521726Y249996D01*
X521601Y249956D01*
X521491Y249896D01*
X521391Y249816D01*
X521311Y249716D01*
X521251Y249606D01*
X521211Y249481D01*
X521201Y249356D01*
Y248226D01*
X521171Y248196D01*
X521071Y248056D01*
X521051Y248016D01*
X521036Y247981D01*
X521016Y247941D01*
X521001Y247901D01*
X520991Y247861D01*
X520976Y247816D01*
X520971Y247776D01*
X520961Y247736D01*
X520956Y247691D01*
Y247651D01*
X520951Y247606D01*
X520956Y247561D01*
Y247521D01*
X520961Y247476D01*
X520971Y247436D01*
X520976Y247396D01*
X520991Y247351D01*
X521001Y247311D01*
X521016Y247271D01*
X521036Y247231D01*
X521051Y247196D01*
X521071Y247156D01*
X521171Y247016D01*
X521201Y246986D01*
Y243556D01*
X521211Y243431D01*
X521251Y243306D01*
X521311Y243196D01*
X521391Y243096D01*
X521491Y243016D01*
X521601Y242956D01*
X521726Y242916D01*
X521851Y242906D01*
X521976Y242916D01*
X522101Y242956D01*
X522211Y243016D01*
X522311Y243096D01*
X522391Y243196D01*
X522451Y243306D01*
X522491Y243431D01*
X522501Y243556D01*
Y246986D01*
X522531Y247016D01*
X522631Y247156D01*
X522651Y247196D01*
X522666Y247231D01*
X522686Y247271D01*
X522701Y247311D01*
X522711Y247351D01*
X522726Y247396D01*
X522731Y247436D01*
X522741Y247476D01*
X522746Y247521D01*
Y247561D01*
X522751Y247606D01*
X522746Y247651D01*
Y247691D01*
X522741Y247736D01*
X522731Y247776D01*
X522726Y247816D01*
X522711Y247861D01*
X522701Y247901D01*
X522686Y247941D01*
X522666Y247981D01*
X522651Y248016D01*
X522631Y248056D01*
X522531Y248196D01*
X522501Y248226D01*
Y249356D01*
X522491Y249481D01*
X522451Y249606D01*
X522391Y249716D01*
X522311Y249816D01*
X522211Y249896D01*
X522101Y249956D01*
X521976Y249996D01*
X521851Y250006D01*
G37*
G36*
G01X526575D02*
X526450Y249996D01*
X526325Y249956D01*
X526215Y249896D01*
X526115Y249816D01*
X526035Y249716D01*
X525975Y249606D01*
X525935Y249481D01*
X525925Y249356D01*
Y248226D01*
X525895Y248196D01*
X525795Y248056D01*
X525775Y248016D01*
X525760Y247981D01*
X525740Y247941D01*
X525725Y247901D01*
X525715Y247861D01*
X525700Y247816D01*
X525695Y247776D01*
X525685Y247736D01*
X525680Y247691D01*
Y247651D01*
X525675Y247606D01*
X525680Y247561D01*
Y247521D01*
X525685Y247476D01*
X525695Y247436D01*
X525700Y247396D01*
X525715Y247351D01*
X525725Y247311D01*
X525740Y247271D01*
X525760Y247231D01*
X525775Y247196D01*
X525795Y247156D01*
X525895Y247016D01*
X525925Y246986D01*
Y243556D01*
X525935Y243431D01*
X525975Y243306D01*
X526035Y243196D01*
X526115Y243096D01*
X526215Y243016D01*
X526325Y242956D01*
X526450Y242916D01*
X526575Y242906D01*
X526700Y242916D01*
X526825Y242956D01*
X526935Y243016D01*
X527035Y243096D01*
X527115Y243196D01*
X527175Y243306D01*
X527215Y243431D01*
X527225Y243556D01*
Y246986D01*
X527255Y247016D01*
X527355Y247156D01*
X527375Y247196D01*
X527390Y247231D01*
X527410Y247271D01*
X527425Y247311D01*
X527435Y247351D01*
X527450Y247396D01*
X527455Y247436D01*
X527465Y247476D01*
X527470Y247521D01*
Y247561D01*
X527475Y247606D01*
X527470Y247651D01*
Y247691D01*
X527465Y247736D01*
X527455Y247776D01*
X527450Y247816D01*
X527435Y247861D01*
X527425Y247901D01*
X527410Y247941D01*
X527390Y247981D01*
X527375Y248016D01*
X527355Y248056D01*
X527255Y248196D01*
X527225Y248226D01*
Y249356D01*
X527215Y249481D01*
X527175Y249606D01*
X527115Y249716D01*
X527035Y249816D01*
X526935Y249896D01*
X526825Y249956D01*
X526700Y249996D01*
X526575Y250006D01*
G37*
G36*
G01X531299D02*
X531174Y249996D01*
X531049Y249956D01*
X530939Y249896D01*
X530839Y249816D01*
X530759Y249716D01*
X530699Y249606D01*
X530659Y249481D01*
X530649Y249356D01*
Y248226D01*
X530619Y248196D01*
X530519Y248056D01*
X530499Y248016D01*
X530484Y247981D01*
X530464Y247941D01*
X530449Y247901D01*
X530439Y247861D01*
X530424Y247816D01*
X530419Y247776D01*
X530409Y247736D01*
X530404Y247691D01*
Y247651D01*
X530399Y247606D01*
X530404Y247561D01*
Y247521D01*
X530409Y247476D01*
X530419Y247436D01*
X530424Y247396D01*
X530439Y247351D01*
X530449Y247311D01*
X530464Y247271D01*
X530484Y247231D01*
X530499Y247196D01*
X530519Y247156D01*
X530619Y247016D01*
X530649Y246986D01*
Y243556D01*
X530659Y243431D01*
X530699Y243306D01*
X530759Y243196D01*
X530839Y243096D01*
X530939Y243016D01*
X531049Y242956D01*
X531174Y242916D01*
X531299Y242906D01*
X531424Y242916D01*
X531549Y242956D01*
X531659Y243016D01*
X531759Y243096D01*
X531839Y243196D01*
X531899Y243306D01*
X531939Y243431D01*
X531949Y243556D01*
Y246986D01*
X531979Y247016D01*
X532079Y247156D01*
X532099Y247196D01*
X532114Y247231D01*
X532134Y247271D01*
X532149Y247311D01*
X532159Y247351D01*
X532174Y247396D01*
X532179Y247436D01*
X532189Y247476D01*
X532194Y247521D01*
Y247561D01*
X532199Y247606D01*
X532194Y247651D01*
Y247691D01*
X532189Y247736D01*
X532179Y247776D01*
X532174Y247816D01*
X532159Y247861D01*
X532149Y247901D01*
X532134Y247941D01*
X532114Y247981D01*
X532099Y248016D01*
X532079Y248056D01*
X531979Y248196D01*
X531949Y248226D01*
Y249356D01*
X531939Y249481D01*
X531899Y249606D01*
X531839Y249716D01*
X531759Y249816D01*
X531659Y249896D01*
X531549Y249956D01*
X531424Y249996D01*
X531299Y250006D01*
G37*
G36*
G01X536024D02*
X535899Y249996D01*
X535774Y249956D01*
X535664Y249896D01*
X535564Y249816D01*
X535484Y249716D01*
X535424Y249606D01*
X535384Y249481D01*
X535374Y249356D01*
Y248226D01*
X535344Y248196D01*
X535244Y248056D01*
X535224Y248016D01*
X535209Y247981D01*
X535189Y247941D01*
X535174Y247901D01*
X535164Y247861D01*
X535149Y247816D01*
X535144Y247776D01*
X535134Y247736D01*
X535129Y247691D01*
Y247651D01*
X535124Y247606D01*
X535129Y247561D01*
Y247521D01*
X535134Y247476D01*
X535144Y247436D01*
X535149Y247396D01*
X535164Y247351D01*
X535174Y247311D01*
X535189Y247271D01*
X535209Y247231D01*
X535224Y247196D01*
X535244Y247156D01*
X535344Y247016D01*
X535374Y246986D01*
Y243556D01*
X535384Y243431D01*
X535424Y243306D01*
X535484Y243196D01*
X535564Y243096D01*
X535664Y243016D01*
X535774Y242956D01*
X535899Y242916D01*
X536024Y242906D01*
X536149Y242916D01*
X536274Y242956D01*
X536384Y243016D01*
X536484Y243096D01*
X536564Y243196D01*
X536624Y243306D01*
X536664Y243431D01*
X536674Y243556D01*
Y246986D01*
X536704Y247016D01*
X536804Y247156D01*
X536824Y247196D01*
X536839Y247231D01*
X536859Y247271D01*
X536874Y247311D01*
X536884Y247351D01*
X536899Y247396D01*
X536904Y247436D01*
X536914Y247476D01*
X536919Y247521D01*
Y247561D01*
X536924Y247606D01*
X536919Y247651D01*
Y247691D01*
X536914Y247736D01*
X536904Y247776D01*
X536899Y247816D01*
X536884Y247861D01*
X536874Y247901D01*
X536859Y247941D01*
X536839Y247981D01*
X536824Y248016D01*
X536804Y248056D01*
X536704Y248196D01*
X536674Y248226D01*
Y249356D01*
X536664Y249481D01*
X536624Y249606D01*
X536564Y249716D01*
X536484Y249816D01*
X536384Y249896D01*
X536274Y249956D01*
X536149Y249996D01*
X536024Y250006D01*
G37*
G36*
G01X540748D02*
X540623Y249996D01*
X540498Y249956D01*
X540388Y249896D01*
X540288Y249816D01*
X540208Y249716D01*
X540148Y249606D01*
X540108Y249481D01*
X540098Y249356D01*
Y248226D01*
X540068Y248196D01*
X539968Y248056D01*
X539948Y248016D01*
X539933Y247981D01*
X539913Y247941D01*
X539898Y247901D01*
X539888Y247861D01*
X539873Y247816D01*
X539868Y247776D01*
X539858Y247736D01*
X539853Y247691D01*
Y247651D01*
X539848Y247606D01*
X539853Y247561D01*
Y247521D01*
X539858Y247476D01*
X539868Y247436D01*
X539873Y247396D01*
X539888Y247351D01*
X539898Y247311D01*
X539913Y247271D01*
X539933Y247231D01*
X539948Y247196D01*
X539968Y247156D01*
X540068Y247016D01*
X540098Y246986D01*
Y243556D01*
X540108Y243431D01*
X540148Y243306D01*
X540208Y243196D01*
X540288Y243096D01*
X540388Y243016D01*
X540498Y242956D01*
X540623Y242916D01*
X540748Y242906D01*
X540873Y242916D01*
X540998Y242956D01*
X541108Y243016D01*
X541208Y243096D01*
X541288Y243196D01*
X541348Y243306D01*
X541388Y243431D01*
X541398Y243556D01*
Y246986D01*
X541428Y247016D01*
X541528Y247156D01*
X541548Y247196D01*
X541563Y247231D01*
X541583Y247271D01*
X541598Y247311D01*
X541608Y247351D01*
X541623Y247396D01*
X541628Y247436D01*
X541638Y247476D01*
X541643Y247521D01*
Y247561D01*
X541648Y247606D01*
X541643Y247651D01*
Y247691D01*
X541638Y247736D01*
X541628Y247776D01*
X541623Y247816D01*
X541608Y247861D01*
X541598Y247901D01*
X541583Y247941D01*
X541563Y247981D01*
X541548Y248016D01*
X541528Y248056D01*
X541428Y248196D01*
X541398Y248226D01*
Y249356D01*
X541388Y249481D01*
X541348Y249606D01*
X541288Y249716D01*
X541208Y249816D01*
X541108Y249896D01*
X540998Y249956D01*
X540873Y249996D01*
X540748Y250006D01*
G37*
G36*
G01X545473D02*
X545348Y249996D01*
X545223Y249956D01*
X545113Y249896D01*
X545013Y249816D01*
X544933Y249716D01*
X544873Y249606D01*
X544833Y249481D01*
X544823Y249356D01*
Y248226D01*
X544793Y248196D01*
X544693Y248056D01*
X544673Y248016D01*
X544658Y247981D01*
X544638Y247941D01*
X544623Y247901D01*
X544613Y247861D01*
X544598Y247816D01*
X544593Y247776D01*
X544583Y247736D01*
X544578Y247691D01*
Y247651D01*
X544573Y247606D01*
X544578Y247561D01*
Y247521D01*
X544583Y247476D01*
X544593Y247436D01*
X544598Y247396D01*
X544613Y247351D01*
X544623Y247311D01*
X544638Y247271D01*
X544658Y247231D01*
X544673Y247196D01*
X544693Y247156D01*
X544793Y247016D01*
X544823Y246986D01*
Y243556D01*
X544833Y243431D01*
X544873Y243306D01*
X544933Y243196D01*
X545013Y243096D01*
X545113Y243016D01*
X545223Y242956D01*
X545348Y242916D01*
X545473Y242906D01*
X545598Y242916D01*
X545723Y242956D01*
X545833Y243016D01*
X545933Y243096D01*
X546013Y243196D01*
X546073Y243306D01*
X546113Y243431D01*
X546123Y243556D01*
Y246986D01*
X546153Y247016D01*
X546253Y247156D01*
X546273Y247196D01*
X546288Y247231D01*
X546308Y247271D01*
X546323Y247311D01*
X546333Y247351D01*
X546348Y247396D01*
X546353Y247436D01*
X546363Y247476D01*
X546368Y247521D01*
Y247561D01*
X546373Y247606D01*
X546368Y247651D01*
Y247691D01*
X546363Y247736D01*
X546353Y247776D01*
X546348Y247816D01*
X546333Y247861D01*
X546323Y247901D01*
X546308Y247941D01*
X546288Y247981D01*
X546273Y248016D01*
X546253Y248056D01*
X546153Y248196D01*
X546123Y248226D01*
Y249356D01*
X546113Y249481D01*
X546073Y249606D01*
X546013Y249716D01*
X545933Y249816D01*
X545833Y249896D01*
X545723Y249956D01*
X545598Y249996D01*
X545473Y250006D01*
G37*
G36*
G01X550197D02*
X550072Y249996D01*
X549947Y249956D01*
X549837Y249896D01*
X549737Y249816D01*
X549657Y249716D01*
X549597Y249606D01*
X549557Y249481D01*
X549547Y249356D01*
Y248226D01*
X549517Y248196D01*
X549417Y248056D01*
X549397Y248016D01*
X549382Y247981D01*
X549362Y247941D01*
X549347Y247901D01*
X549337Y247861D01*
X549322Y247816D01*
X549317Y247776D01*
X549307Y247736D01*
X549302Y247691D01*
Y247651D01*
X549297Y247606D01*
X549302Y247561D01*
Y247521D01*
X549307Y247476D01*
X549317Y247436D01*
X549322Y247396D01*
X549337Y247351D01*
X549347Y247311D01*
X549362Y247271D01*
X549382Y247231D01*
X549397Y247196D01*
X549417Y247156D01*
X549517Y247016D01*
X549547Y246986D01*
Y243556D01*
X549557Y243431D01*
X549597Y243306D01*
X549657Y243196D01*
X549737Y243096D01*
X549837Y243016D01*
X549947Y242956D01*
X550072Y242916D01*
X550197Y242906D01*
X550322Y242916D01*
X550447Y242956D01*
X550557Y243016D01*
X550657Y243096D01*
X550737Y243196D01*
X550797Y243306D01*
X550837Y243431D01*
X550847Y243556D01*
Y246986D01*
X550877Y247016D01*
X550977Y247156D01*
X550997Y247196D01*
X551012Y247231D01*
X551032Y247271D01*
X551047Y247311D01*
X551057Y247351D01*
X551072Y247396D01*
X551077Y247436D01*
X551087Y247476D01*
X551092Y247521D01*
Y247561D01*
X551097Y247606D01*
X551092Y247651D01*
Y247691D01*
X551087Y247736D01*
X551077Y247776D01*
X551072Y247816D01*
X551057Y247861D01*
X551047Y247901D01*
X551032Y247941D01*
X551012Y247981D01*
X550997Y248016D01*
X550977Y248056D01*
X550877Y248196D01*
X550847Y248226D01*
Y249356D01*
X550837Y249481D01*
X550797Y249606D01*
X550737Y249716D01*
X550657Y249816D01*
X550557Y249896D01*
X550447Y249956D01*
X550322Y249996D01*
X550197Y250006D01*
G37*
G36*
G01X554922D02*
X554797Y249996D01*
X554672Y249956D01*
X554562Y249896D01*
X554462Y249816D01*
X554382Y249716D01*
X554322Y249606D01*
X554282Y249481D01*
X554272Y249356D01*
Y248226D01*
X554242Y248196D01*
X554142Y248056D01*
X554122Y248016D01*
X554107Y247981D01*
X554087Y247941D01*
X554072Y247901D01*
X554062Y247861D01*
X554047Y247816D01*
X554042Y247776D01*
X554032Y247736D01*
X554027Y247691D01*
Y247651D01*
X554022Y247606D01*
X554027Y247561D01*
Y247521D01*
X554032Y247476D01*
X554042Y247436D01*
X554047Y247396D01*
X554062Y247351D01*
X554072Y247311D01*
X554087Y247271D01*
X554107Y247231D01*
X554122Y247196D01*
X554142Y247156D01*
X554242Y247016D01*
X554272Y246986D01*
Y243556D01*
X554282Y243431D01*
X554322Y243306D01*
X554382Y243196D01*
X554462Y243096D01*
X554562Y243016D01*
X554672Y242956D01*
X554797Y242916D01*
X554922Y242906D01*
X555047Y242916D01*
X555172Y242956D01*
X555282Y243016D01*
X555382Y243096D01*
X555462Y243196D01*
X555522Y243306D01*
X555562Y243431D01*
X555572Y243556D01*
Y246986D01*
X555602Y247016D01*
X555702Y247156D01*
X555722Y247196D01*
X555737Y247231D01*
X555757Y247271D01*
X555772Y247311D01*
X555782Y247351D01*
X555797Y247396D01*
X555802Y247436D01*
X555812Y247476D01*
X555817Y247521D01*
Y247561D01*
X555822Y247606D01*
X555817Y247651D01*
Y247691D01*
X555812Y247736D01*
X555802Y247776D01*
X555797Y247816D01*
X555782Y247861D01*
X555772Y247901D01*
X555757Y247941D01*
X555737Y247981D01*
X555722Y248016D01*
X555702Y248056D01*
X555602Y248196D01*
X555572Y248226D01*
Y249356D01*
X555562Y249481D01*
X555522Y249606D01*
X555462Y249716D01*
X555382Y249816D01*
X555282Y249896D01*
X555172Y249956D01*
X555047Y249996D01*
X554922Y250006D01*
G37*
G36*
G01X559646D02*
X559521Y249996D01*
X559396Y249956D01*
X559286Y249896D01*
X559186Y249816D01*
X559106Y249716D01*
X559046Y249606D01*
X559006Y249481D01*
X558996Y249356D01*
Y248226D01*
X558966Y248196D01*
X558866Y248056D01*
X558846Y248016D01*
X558831Y247981D01*
X558811Y247941D01*
X558796Y247901D01*
X558786Y247861D01*
X558771Y247816D01*
X558766Y247776D01*
X558756Y247736D01*
X558751Y247691D01*
Y247651D01*
X558746Y247606D01*
X558751Y247561D01*
Y247521D01*
X558756Y247476D01*
X558766Y247436D01*
X558771Y247396D01*
X558786Y247351D01*
X558796Y247311D01*
X558811Y247271D01*
X558831Y247231D01*
X558846Y247196D01*
X558866Y247156D01*
X558966Y247016D01*
X558996Y246986D01*
Y243556D01*
X559006Y243431D01*
X559046Y243306D01*
X559106Y243196D01*
X559186Y243096D01*
X559286Y243016D01*
X559396Y242956D01*
X559521Y242916D01*
X559646Y242906D01*
X559771Y242916D01*
X559896Y242956D01*
X560006Y243016D01*
X560106Y243096D01*
X560186Y243196D01*
X560246Y243306D01*
X560286Y243431D01*
X560296Y243556D01*
Y246986D01*
X560326Y247016D01*
X560426Y247156D01*
X560446Y247196D01*
X560461Y247231D01*
X560481Y247271D01*
X560496Y247311D01*
X560506Y247351D01*
X560521Y247396D01*
X560526Y247436D01*
X560536Y247476D01*
X560541Y247521D01*
Y247561D01*
X560546Y247606D01*
X560541Y247651D01*
Y247691D01*
X560536Y247736D01*
X560526Y247776D01*
X560521Y247816D01*
X560506Y247861D01*
X560496Y247901D01*
X560481Y247941D01*
X560461Y247981D01*
X560446Y248016D01*
X560426Y248056D01*
X560326Y248196D01*
X560296Y248226D01*
Y249356D01*
X560286Y249481D01*
X560246Y249606D01*
X560186Y249716D01*
X560106Y249816D01*
X560006Y249896D01*
X559896Y249956D01*
X559771Y249996D01*
X559646Y250006D01*
G37*
G36*
G01X564370D02*
X564245Y249996D01*
X564120Y249956D01*
X564010Y249896D01*
X563910Y249816D01*
X563830Y249716D01*
X563770Y249606D01*
X563730Y249481D01*
X563720Y249356D01*
Y248226D01*
X563690Y248196D01*
X563590Y248056D01*
X563570Y248016D01*
X563555Y247981D01*
X563535Y247941D01*
X563520Y247901D01*
X563510Y247861D01*
X563495Y247816D01*
X563490Y247776D01*
X563480Y247736D01*
X563475Y247691D01*
Y247651D01*
X563470Y247606D01*
X563475Y247561D01*
Y247521D01*
X563480Y247476D01*
X563490Y247436D01*
X563495Y247396D01*
X563510Y247351D01*
X563520Y247311D01*
X563535Y247271D01*
X563555Y247231D01*
X563570Y247196D01*
X563590Y247156D01*
X563690Y247016D01*
X563720Y246986D01*
Y243556D01*
X563730Y243431D01*
X563770Y243306D01*
X563830Y243196D01*
X563910Y243096D01*
X564010Y243016D01*
X564120Y242956D01*
X564245Y242916D01*
X564370Y242906D01*
X564495Y242916D01*
X564620Y242956D01*
X564730Y243016D01*
X564830Y243096D01*
X564910Y243196D01*
X564970Y243306D01*
X565010Y243431D01*
X565020Y243556D01*
Y246986D01*
X565050Y247016D01*
X565150Y247156D01*
X565170Y247196D01*
X565185Y247231D01*
X565205Y247271D01*
X565220Y247311D01*
X565230Y247351D01*
X565245Y247396D01*
X565250Y247436D01*
X565260Y247476D01*
X565265Y247521D01*
Y247561D01*
X565270Y247606D01*
X565265Y247651D01*
Y247691D01*
X565260Y247736D01*
X565250Y247776D01*
X565245Y247816D01*
X565230Y247861D01*
X565220Y247901D01*
X565205Y247941D01*
X565185Y247981D01*
X565170Y248016D01*
X565150Y248056D01*
X565050Y248196D01*
X565020Y248226D01*
Y249356D01*
X565010Y249481D01*
X564970Y249606D01*
X564910Y249716D01*
X564830Y249816D01*
X564730Y249896D01*
X564620Y249956D01*
X564495Y249996D01*
X564370Y250006D01*
G37*
G36*
G01X569095D02*
X568970Y249996D01*
X568845Y249956D01*
X568735Y249896D01*
X568635Y249816D01*
X568555Y249716D01*
X568495Y249606D01*
X568455Y249481D01*
X568445Y249356D01*
Y248226D01*
X568415Y248196D01*
X568315Y248056D01*
X568295Y248016D01*
X568280Y247981D01*
X568260Y247941D01*
X568245Y247901D01*
X568235Y247861D01*
X568220Y247816D01*
X568215Y247776D01*
X568205Y247736D01*
X568200Y247691D01*
Y247651D01*
X568195Y247606D01*
X568200Y247561D01*
Y247521D01*
X568205Y247476D01*
X568215Y247436D01*
X568220Y247396D01*
X568235Y247351D01*
X568245Y247311D01*
X568260Y247271D01*
X568280Y247231D01*
X568295Y247196D01*
X568315Y247156D01*
X568415Y247016D01*
X568445Y246986D01*
Y243556D01*
X568455Y243431D01*
X568495Y243306D01*
X568555Y243196D01*
X568635Y243096D01*
X568735Y243016D01*
X568845Y242956D01*
X568970Y242916D01*
X569095Y242906D01*
X569220Y242916D01*
X569345Y242956D01*
X569455Y243016D01*
X569555Y243096D01*
X569635Y243196D01*
X569695Y243306D01*
X569735Y243431D01*
X569745Y243556D01*
Y246986D01*
X569775Y247016D01*
X569875Y247156D01*
X569895Y247196D01*
X569910Y247231D01*
X569930Y247271D01*
X569945Y247311D01*
X569955Y247351D01*
X569970Y247396D01*
X569975Y247436D01*
X569985Y247476D01*
X569990Y247521D01*
Y247561D01*
X569995Y247606D01*
X569990Y247651D01*
Y247691D01*
X569985Y247736D01*
X569975Y247776D01*
X569970Y247816D01*
X569955Y247861D01*
X569945Y247901D01*
X569930Y247941D01*
X569910Y247981D01*
X569895Y248016D01*
X569875Y248056D01*
X569775Y248196D01*
X569745Y248226D01*
Y249356D01*
X569735Y249481D01*
X569695Y249606D01*
X569635Y249716D01*
X569555Y249816D01*
X569455Y249896D01*
X569345Y249956D01*
X569220Y249996D01*
X569095Y250006D01*
G37*
G36*
G01X573819D02*
X573694Y249996D01*
X573569Y249956D01*
X573459Y249896D01*
X573359Y249816D01*
X573279Y249716D01*
X573219Y249606D01*
X573179Y249481D01*
X573169Y249356D01*
Y248226D01*
X573139Y248196D01*
X573039Y248056D01*
X573019Y248016D01*
X573004Y247981D01*
X572984Y247941D01*
X572969Y247901D01*
X572959Y247861D01*
X572944Y247816D01*
X572939Y247776D01*
X572929Y247736D01*
X572924Y247691D01*
Y247651D01*
X572919Y247606D01*
X572924Y247561D01*
Y247521D01*
X572929Y247476D01*
X572939Y247436D01*
X572944Y247396D01*
X572959Y247351D01*
X572969Y247311D01*
X572984Y247271D01*
X573004Y247231D01*
X573019Y247196D01*
X573039Y247156D01*
X573139Y247016D01*
X573169Y246986D01*
Y243556D01*
X573179Y243431D01*
X573219Y243306D01*
X573279Y243196D01*
X573359Y243096D01*
X573459Y243016D01*
X573569Y242956D01*
X573694Y242916D01*
X573819Y242906D01*
X573944Y242916D01*
X574069Y242956D01*
X574179Y243016D01*
X574279Y243096D01*
X574359Y243196D01*
X574419Y243306D01*
X574459Y243431D01*
X574469Y243556D01*
Y246986D01*
X574499Y247016D01*
X574599Y247156D01*
X574619Y247196D01*
X574634Y247231D01*
X574654Y247271D01*
X574669Y247311D01*
X574679Y247351D01*
X574694Y247396D01*
X574699Y247436D01*
X574709Y247476D01*
X574714Y247521D01*
Y247561D01*
X574719Y247606D01*
X574714Y247651D01*
Y247691D01*
X574709Y247736D01*
X574699Y247776D01*
X574694Y247816D01*
X574679Y247861D01*
X574669Y247901D01*
X574654Y247941D01*
X574634Y247981D01*
X574619Y248016D01*
X574599Y248056D01*
X574499Y248196D01*
X574469Y248226D01*
Y249356D01*
X574459Y249481D01*
X574419Y249606D01*
X574359Y249716D01*
X574279Y249816D01*
X574179Y249896D01*
X574069Y249956D01*
X573944Y249996D01*
X573819Y250006D01*
G37*
G36*
G01X578544D02*
X578419Y249996D01*
X578294Y249956D01*
X578184Y249896D01*
X578084Y249816D01*
X578004Y249716D01*
X577944Y249606D01*
X577904Y249481D01*
X577894Y249356D01*
Y248226D01*
X577864Y248196D01*
X577764Y248056D01*
X577744Y248016D01*
X577729Y247981D01*
X577709Y247941D01*
X577694Y247901D01*
X577684Y247861D01*
X577669Y247816D01*
X577664Y247776D01*
X577654Y247736D01*
X577649Y247691D01*
Y247651D01*
X577644Y247606D01*
X577649Y247561D01*
Y247521D01*
X577654Y247476D01*
X577664Y247436D01*
X577669Y247396D01*
X577684Y247351D01*
X577694Y247311D01*
X577709Y247271D01*
X577729Y247231D01*
X577744Y247196D01*
X577764Y247156D01*
X577864Y247016D01*
X577894Y246986D01*
Y243556D01*
X577904Y243431D01*
X577944Y243306D01*
X578004Y243196D01*
X578084Y243096D01*
X578184Y243016D01*
X578294Y242956D01*
X578419Y242916D01*
X578544Y242906D01*
X578669Y242916D01*
X578794Y242956D01*
X578904Y243016D01*
X579004Y243096D01*
X579084Y243196D01*
X579144Y243306D01*
X579184Y243431D01*
X579194Y243556D01*
Y246986D01*
X579224Y247016D01*
X579324Y247156D01*
X579344Y247196D01*
X579359Y247231D01*
X579379Y247271D01*
X579394Y247311D01*
X579404Y247351D01*
X579419Y247396D01*
X579424Y247436D01*
X579434Y247476D01*
X579439Y247521D01*
Y247561D01*
X579444Y247606D01*
X579439Y247651D01*
Y247691D01*
X579434Y247736D01*
X579424Y247776D01*
X579419Y247816D01*
X579404Y247861D01*
X579394Y247901D01*
X579379Y247941D01*
X579359Y247981D01*
X579344Y248016D01*
X579324Y248056D01*
X579224Y248196D01*
X579194Y248226D01*
Y249356D01*
X579184Y249481D01*
X579144Y249606D01*
X579084Y249716D01*
X579004Y249816D01*
X578904Y249896D01*
X578794Y249956D01*
X578669Y249996D01*
X578544Y250006D01*
G37*
G36*
G01X583268D02*
X583143Y249996D01*
X583018Y249956D01*
X582908Y249896D01*
X582808Y249816D01*
X582728Y249716D01*
X582668Y249606D01*
X582628Y249481D01*
X582618Y249356D01*
Y248226D01*
X582588Y248196D01*
X582488Y248056D01*
X582468Y248016D01*
X582453Y247981D01*
X582433Y247941D01*
X582418Y247901D01*
X582408Y247861D01*
X582393Y247816D01*
X582388Y247776D01*
X582378Y247736D01*
X582373Y247691D01*
Y247651D01*
X582368Y247606D01*
X582373Y247561D01*
Y247521D01*
X582378Y247476D01*
X582388Y247436D01*
X582393Y247396D01*
X582408Y247351D01*
X582418Y247311D01*
X582433Y247271D01*
X582453Y247231D01*
X582468Y247196D01*
X582488Y247156D01*
X582588Y247016D01*
X582618Y246986D01*
Y243556D01*
X582628Y243431D01*
X582668Y243306D01*
X582728Y243196D01*
X582808Y243096D01*
X582908Y243016D01*
X583018Y242956D01*
X583143Y242916D01*
X583268Y242906D01*
X583393Y242916D01*
X583518Y242956D01*
X583628Y243016D01*
X583728Y243096D01*
X583808Y243196D01*
X583868Y243306D01*
X583908Y243431D01*
X583918Y243556D01*
Y246986D01*
X583948Y247016D01*
X584048Y247156D01*
X584068Y247196D01*
X584083Y247231D01*
X584103Y247271D01*
X584118Y247311D01*
X584128Y247351D01*
X584143Y247396D01*
X584148Y247436D01*
X584158Y247476D01*
X584163Y247521D01*
Y247561D01*
X584168Y247606D01*
X584163Y247651D01*
Y247691D01*
X584158Y247736D01*
X584148Y247776D01*
X584143Y247816D01*
X584128Y247861D01*
X584118Y247901D01*
X584103Y247941D01*
X584083Y247981D01*
X584068Y248016D01*
X584048Y248056D01*
X583948Y248196D01*
X583918Y248226D01*
Y249356D01*
X583908Y249481D01*
X583868Y249606D01*
X583808Y249716D01*
X583728Y249816D01*
X583628Y249896D01*
X583518Y249956D01*
X583393Y249996D01*
X583268Y250006D01*
G37*
G36*
G01X587992D02*
X587867Y249996D01*
X587742Y249956D01*
X587632Y249896D01*
X587532Y249816D01*
X587452Y249716D01*
X587392Y249606D01*
X587352Y249481D01*
X587342Y249356D01*
Y248226D01*
X587312Y248196D01*
X587212Y248056D01*
X587192Y248016D01*
X587177Y247981D01*
X587157Y247941D01*
X587142Y247901D01*
X587132Y247861D01*
X587117Y247816D01*
X587112Y247776D01*
X587102Y247736D01*
X587097Y247691D01*
Y247651D01*
X587092Y247606D01*
X587097Y247561D01*
Y247521D01*
X587102Y247476D01*
X587112Y247436D01*
X587117Y247396D01*
X587132Y247351D01*
X587142Y247311D01*
X587157Y247271D01*
X587177Y247231D01*
X587192Y247196D01*
X587212Y247156D01*
X587312Y247016D01*
X587342Y246986D01*
Y243556D01*
X587352Y243431D01*
X587392Y243306D01*
X587452Y243196D01*
X587532Y243096D01*
X587632Y243016D01*
X587742Y242956D01*
X587867Y242916D01*
X587992Y242906D01*
X588117Y242916D01*
X588242Y242956D01*
X588352Y243016D01*
X588452Y243096D01*
X588532Y243196D01*
X588592Y243306D01*
X588632Y243431D01*
X588642Y243556D01*
Y246986D01*
X588672Y247016D01*
X588772Y247156D01*
X588792Y247196D01*
X588807Y247231D01*
X588827Y247271D01*
X588842Y247311D01*
X588852Y247351D01*
X588867Y247396D01*
X588872Y247436D01*
X588882Y247476D01*
X588887Y247521D01*
Y247561D01*
X588892Y247606D01*
X588887Y247651D01*
Y247691D01*
X588882Y247736D01*
X588872Y247776D01*
X588867Y247816D01*
X588852Y247861D01*
X588842Y247901D01*
X588827Y247941D01*
X588807Y247981D01*
X588792Y248016D01*
X588772Y248056D01*
X588672Y248196D01*
X588642Y248226D01*
Y249356D01*
X588632Y249481D01*
X588592Y249606D01*
X588532Y249716D01*
X588452Y249816D01*
X588352Y249896D01*
X588242Y249956D01*
X588117Y249996D01*
X587992Y250006D01*
G37*
G36*
G01X592717D02*
X592592Y249996D01*
X592467Y249956D01*
X592357Y249896D01*
X592257Y249816D01*
X592177Y249716D01*
X592117Y249606D01*
X592077Y249481D01*
X592067Y249356D01*
Y248226D01*
X592037Y248196D01*
X591937Y248056D01*
X591917Y248016D01*
X591902Y247981D01*
X591882Y247941D01*
X591867Y247901D01*
X591857Y247861D01*
X591842Y247816D01*
X591837Y247776D01*
X591827Y247736D01*
X591822Y247691D01*
Y247651D01*
X591817Y247606D01*
X591822Y247561D01*
Y247521D01*
X591827Y247476D01*
X591837Y247436D01*
X591842Y247396D01*
X591857Y247351D01*
X591867Y247311D01*
X591882Y247271D01*
X591902Y247231D01*
X591917Y247196D01*
X591937Y247156D01*
X592037Y247016D01*
X592067Y246986D01*
Y243556D01*
X592077Y243431D01*
X592117Y243306D01*
X592177Y243196D01*
X592257Y243096D01*
X592357Y243016D01*
X592467Y242956D01*
X592592Y242916D01*
X592717Y242906D01*
X592842Y242916D01*
X592967Y242956D01*
X593077Y243016D01*
X593177Y243096D01*
X593257Y243196D01*
X593317Y243306D01*
X593357Y243431D01*
X593367Y243556D01*
Y246986D01*
X593397Y247016D01*
X593497Y247156D01*
X593517Y247196D01*
X593532Y247231D01*
X593552Y247271D01*
X593567Y247311D01*
X593577Y247351D01*
X593592Y247396D01*
X593597Y247436D01*
X593607Y247476D01*
X593612Y247521D01*
Y247561D01*
X593617Y247606D01*
X593612Y247651D01*
Y247691D01*
X593607Y247736D01*
X593597Y247776D01*
X593592Y247816D01*
X593577Y247861D01*
X593567Y247901D01*
X593552Y247941D01*
X593532Y247981D01*
X593517Y248016D01*
X593497Y248056D01*
X593397Y248196D01*
X593367Y248226D01*
Y249356D01*
X593357Y249481D01*
X593317Y249606D01*
X593257Y249716D01*
X593177Y249816D01*
X593077Y249896D01*
X592967Y249956D01*
X592842Y249996D01*
X592717Y250006D01*
G37*
G36*
G01X597441D02*
X597316Y249996D01*
X597191Y249956D01*
X597081Y249896D01*
X596981Y249816D01*
X596901Y249716D01*
X596841Y249606D01*
X596801Y249481D01*
X596791Y249356D01*
Y248226D01*
X596761Y248196D01*
X596661Y248056D01*
X596641Y248016D01*
X596626Y247981D01*
X596606Y247941D01*
X596591Y247901D01*
X596581Y247861D01*
X596566Y247816D01*
X596561Y247776D01*
X596551Y247736D01*
X596546Y247691D01*
Y247651D01*
X596541Y247606D01*
X596546Y247561D01*
Y247521D01*
X596551Y247476D01*
X596561Y247436D01*
X596566Y247396D01*
X596581Y247351D01*
X596591Y247311D01*
X596606Y247271D01*
X596626Y247231D01*
X596641Y247196D01*
X596661Y247156D01*
X596761Y247016D01*
X596791Y246986D01*
Y243556D01*
X596801Y243431D01*
X596841Y243306D01*
X596901Y243196D01*
X596981Y243096D01*
X597081Y243016D01*
X597191Y242956D01*
X597316Y242916D01*
X597441Y242906D01*
X597566Y242916D01*
X597691Y242956D01*
X597801Y243016D01*
X597901Y243096D01*
X597981Y243196D01*
X598041Y243306D01*
X598081Y243431D01*
X598091Y243556D01*
Y246986D01*
X598121Y247016D01*
X598221Y247156D01*
X598241Y247196D01*
X598256Y247231D01*
X598276Y247271D01*
X598291Y247311D01*
X598301Y247351D01*
X598316Y247396D01*
X598321Y247436D01*
X598331Y247476D01*
X598336Y247521D01*
Y247561D01*
X598341Y247606D01*
X598336Y247651D01*
Y247691D01*
X598331Y247736D01*
X598321Y247776D01*
X598316Y247816D01*
X598301Y247861D01*
X598291Y247901D01*
X598276Y247941D01*
X598256Y247981D01*
X598241Y248016D01*
X598221Y248056D01*
X598121Y248196D01*
X598091Y248226D01*
Y249356D01*
X598081Y249481D01*
X598041Y249606D01*
X597981Y249716D01*
X597901Y249816D01*
X597801Y249896D01*
X597691Y249956D01*
X597566Y249996D01*
X597441Y250006D01*
G37*
G36*
G01X602166D02*
X602041Y249996D01*
X601916Y249956D01*
X601806Y249896D01*
X601706Y249816D01*
X601626Y249716D01*
X601566Y249606D01*
X601526Y249481D01*
X601516Y249356D01*
Y248226D01*
X601486Y248196D01*
X601386Y248056D01*
X601366Y248016D01*
X601351Y247981D01*
X601331Y247941D01*
X601316Y247901D01*
X601306Y247861D01*
X601291Y247816D01*
X601286Y247776D01*
X601276Y247736D01*
X601271Y247691D01*
Y247651D01*
X601266Y247606D01*
X601271Y247561D01*
Y247521D01*
X601276Y247476D01*
X601286Y247436D01*
X601291Y247396D01*
X601306Y247351D01*
X601316Y247311D01*
X601331Y247271D01*
X601351Y247231D01*
X601366Y247196D01*
X601386Y247156D01*
X601486Y247016D01*
X601516Y246986D01*
Y243556D01*
X601526Y243431D01*
X601566Y243306D01*
X601626Y243196D01*
X601706Y243096D01*
X601806Y243016D01*
X601916Y242956D01*
X602041Y242916D01*
X602166Y242906D01*
X602291Y242916D01*
X602416Y242956D01*
X602526Y243016D01*
X602626Y243096D01*
X602706Y243196D01*
X602766Y243306D01*
X602806Y243431D01*
X602816Y243556D01*
Y246986D01*
X602846Y247016D01*
X602946Y247156D01*
X602966Y247196D01*
X602981Y247231D01*
X603001Y247271D01*
X603016Y247311D01*
X603026Y247351D01*
X603041Y247396D01*
X603046Y247436D01*
X603056Y247476D01*
X603061Y247521D01*
Y247561D01*
X603066Y247606D01*
X603061Y247651D01*
Y247691D01*
X603056Y247736D01*
X603046Y247776D01*
X603041Y247816D01*
X603026Y247861D01*
X603016Y247901D01*
X603001Y247941D01*
X602981Y247981D01*
X602966Y248016D01*
X602946Y248056D01*
X602846Y248196D01*
X602816Y248226D01*
Y249356D01*
X602806Y249481D01*
X602766Y249606D01*
X602706Y249716D01*
X602626Y249816D01*
X602526Y249896D01*
X602416Y249956D01*
X602291Y249996D01*
X602166Y250006D01*
G37*
G36*
G01X606890D02*
X606765Y249996D01*
X606640Y249956D01*
X606530Y249896D01*
X606430Y249816D01*
X606350Y249716D01*
X606290Y249606D01*
X606250Y249481D01*
X606240Y249356D01*
Y248226D01*
X606210Y248196D01*
X606110Y248056D01*
X606090Y248016D01*
X606075Y247981D01*
X606055Y247941D01*
X606040Y247901D01*
X606030Y247861D01*
X606015Y247816D01*
X606010Y247776D01*
X606000Y247736D01*
X605995Y247691D01*
Y247651D01*
X605990Y247606D01*
X605995Y247561D01*
Y247521D01*
X606000Y247476D01*
X606010Y247436D01*
X606015Y247396D01*
X606030Y247351D01*
X606040Y247311D01*
X606055Y247271D01*
X606075Y247231D01*
X606090Y247196D01*
X606110Y247156D01*
X606210Y247016D01*
X606240Y246986D01*
Y243556D01*
X606250Y243431D01*
X606290Y243306D01*
X606350Y243196D01*
X606430Y243096D01*
X606530Y243016D01*
X606640Y242956D01*
X606765Y242916D01*
X606890Y242906D01*
X607015Y242916D01*
X607140Y242956D01*
X607250Y243016D01*
X607350Y243096D01*
X607430Y243196D01*
X607490Y243306D01*
X607530Y243431D01*
X607540Y243556D01*
Y246986D01*
X607570Y247016D01*
X607670Y247156D01*
X607690Y247196D01*
X607705Y247231D01*
X607725Y247271D01*
X607740Y247311D01*
X607750Y247351D01*
X607765Y247396D01*
X607770Y247436D01*
X607780Y247476D01*
X607785Y247521D01*
Y247561D01*
X607790Y247606D01*
X607785Y247651D01*
Y247691D01*
X607780Y247736D01*
X607770Y247776D01*
X607765Y247816D01*
X607750Y247861D01*
X607740Y247901D01*
X607725Y247941D01*
X607705Y247981D01*
X607690Y248016D01*
X607670Y248056D01*
X607570Y248196D01*
X607540Y248226D01*
Y249356D01*
X607530Y249481D01*
X607490Y249606D01*
X607430Y249716D01*
X607350Y249816D01*
X607250Y249896D01*
X607140Y249956D01*
X607015Y249996D01*
X606890Y250006D01*
G37*
G36*
G01X611614D02*
X611489Y249996D01*
X611364Y249956D01*
X611254Y249896D01*
X611154Y249816D01*
X611074Y249716D01*
X611014Y249606D01*
X610974Y249481D01*
X610964Y249356D01*
Y248226D01*
X610934Y248196D01*
X610834Y248056D01*
X610814Y248016D01*
X610799Y247981D01*
X610779Y247941D01*
X610764Y247901D01*
X610754Y247861D01*
X610739Y247816D01*
X610734Y247776D01*
X610724Y247736D01*
X610719Y247691D01*
Y247651D01*
X610714Y247606D01*
X610719Y247561D01*
Y247521D01*
X610724Y247476D01*
X610734Y247436D01*
X610739Y247396D01*
X610754Y247351D01*
X610764Y247311D01*
X610779Y247271D01*
X610799Y247231D01*
X610814Y247196D01*
X610834Y247156D01*
X610934Y247016D01*
X610964Y246986D01*
Y243556D01*
X610974Y243431D01*
X611014Y243306D01*
X611074Y243196D01*
X611154Y243096D01*
X611254Y243016D01*
X611364Y242956D01*
X611489Y242916D01*
X611614Y242906D01*
X611739Y242916D01*
X611864Y242956D01*
X611974Y243016D01*
X612074Y243096D01*
X612154Y243196D01*
X612214Y243306D01*
X612254Y243431D01*
X612264Y243556D01*
Y246986D01*
X612294Y247016D01*
X612394Y247156D01*
X612414Y247196D01*
X612429Y247231D01*
X612449Y247271D01*
X612464Y247311D01*
X612474Y247351D01*
X612489Y247396D01*
X612494Y247436D01*
X612504Y247476D01*
X612509Y247521D01*
Y247561D01*
X612514Y247606D01*
X612509Y247651D01*
Y247691D01*
X612504Y247736D01*
X612494Y247776D01*
X612489Y247816D01*
X612474Y247861D01*
X612464Y247901D01*
X612449Y247941D01*
X612429Y247981D01*
X612414Y248016D01*
X612394Y248056D01*
X612294Y248196D01*
X612264Y248226D01*
Y249356D01*
X612254Y249481D01*
X612214Y249606D01*
X612154Y249716D01*
X612074Y249816D01*
X611974Y249896D01*
X611864Y249956D01*
X611739Y249996D01*
X611614Y250006D01*
G37*
G36*
G01X616339D02*
X616214Y249996D01*
X616089Y249956D01*
X615979Y249896D01*
X615879Y249816D01*
X615799Y249716D01*
X615739Y249606D01*
X615699Y249481D01*
X615689Y249356D01*
Y248226D01*
X615659Y248196D01*
X615559Y248056D01*
X615539Y248016D01*
X615524Y247981D01*
X615504Y247941D01*
X615489Y247901D01*
X615479Y247861D01*
X615464Y247816D01*
X615459Y247776D01*
X615449Y247736D01*
X615444Y247691D01*
Y247651D01*
X615439Y247606D01*
X615444Y247561D01*
Y247521D01*
X615449Y247476D01*
X615459Y247436D01*
X615464Y247396D01*
X615479Y247351D01*
X615489Y247311D01*
X615504Y247271D01*
X615524Y247231D01*
X615539Y247196D01*
X615559Y247156D01*
X615659Y247016D01*
X615689Y246986D01*
Y243556D01*
X615699Y243431D01*
X615739Y243306D01*
X615799Y243196D01*
X615879Y243096D01*
X615979Y243016D01*
X616089Y242956D01*
X616214Y242916D01*
X616339Y242906D01*
X616464Y242916D01*
X616589Y242956D01*
X616699Y243016D01*
X616799Y243096D01*
X616879Y243196D01*
X616939Y243306D01*
X616979Y243431D01*
X616989Y243556D01*
Y246986D01*
X617019Y247016D01*
X617119Y247156D01*
X617139Y247196D01*
X617154Y247231D01*
X617174Y247271D01*
X617189Y247311D01*
X617199Y247351D01*
X617214Y247396D01*
X617219Y247436D01*
X617229Y247476D01*
X617234Y247521D01*
Y247561D01*
X617239Y247606D01*
X617234Y247651D01*
Y247691D01*
X617229Y247736D01*
X617219Y247776D01*
X617214Y247816D01*
X617199Y247861D01*
X617189Y247901D01*
X617174Y247941D01*
X617154Y247981D01*
X617139Y248016D01*
X617119Y248056D01*
X617019Y248196D01*
X616989Y248226D01*
Y249356D01*
X616979Y249481D01*
X616939Y249606D01*
X616879Y249716D01*
X616799Y249816D01*
X616699Y249896D01*
X616589Y249956D01*
X616464Y249996D01*
X616339Y250006D01*
G37*
G36*
G01X621063D02*
X620938Y249996D01*
X620813Y249956D01*
X620703Y249896D01*
X620603Y249816D01*
X620523Y249716D01*
X620463Y249606D01*
X620423Y249481D01*
X620413Y249356D01*
Y248226D01*
X620383Y248196D01*
X620283Y248056D01*
X620263Y248016D01*
X620248Y247981D01*
X620228Y247941D01*
X620213Y247901D01*
X620203Y247861D01*
X620188Y247816D01*
X620183Y247776D01*
X620173Y247736D01*
X620168Y247691D01*
Y247651D01*
X620163Y247606D01*
X620168Y247561D01*
Y247521D01*
X620173Y247476D01*
X620183Y247436D01*
X620188Y247396D01*
X620203Y247351D01*
X620213Y247311D01*
X620228Y247271D01*
X620248Y247231D01*
X620263Y247196D01*
X620283Y247156D01*
X620383Y247016D01*
X620413Y246986D01*
Y243556D01*
X620423Y243431D01*
X620463Y243306D01*
X620523Y243196D01*
X620603Y243096D01*
X620703Y243016D01*
X620813Y242956D01*
X620938Y242916D01*
X621063Y242906D01*
X621188Y242916D01*
X621313Y242956D01*
X621423Y243016D01*
X621523Y243096D01*
X621603Y243196D01*
X621663Y243306D01*
X621703Y243431D01*
X621713Y243556D01*
Y246986D01*
X621743Y247016D01*
X621843Y247156D01*
X621863Y247196D01*
X621878Y247231D01*
X621898Y247271D01*
X621913Y247311D01*
X621923Y247351D01*
X621938Y247396D01*
X621943Y247436D01*
X621953Y247476D01*
X621958Y247521D01*
Y247561D01*
X621963Y247606D01*
X621958Y247651D01*
Y247691D01*
X621953Y247736D01*
X621943Y247776D01*
X621938Y247816D01*
X621923Y247861D01*
X621913Y247901D01*
X621898Y247941D01*
X621878Y247981D01*
X621863Y248016D01*
X621843Y248056D01*
X621743Y248196D01*
X621713Y248226D01*
Y249356D01*
X621703Y249481D01*
X621663Y249606D01*
X621603Y249716D01*
X621523Y249816D01*
X621423Y249896D01*
X621313Y249956D01*
X621188Y249996D01*
X621063Y250006D01*
G37*
G36*
G01X625788D02*
X625663Y249996D01*
X625538Y249956D01*
X625428Y249896D01*
X625328Y249816D01*
X625248Y249716D01*
X625188Y249606D01*
X625148Y249481D01*
X625138Y249356D01*
Y248226D01*
X625108Y248196D01*
X625008Y248056D01*
X624988Y248016D01*
X624973Y247981D01*
X624953Y247941D01*
X624938Y247901D01*
X624928Y247861D01*
X624913Y247816D01*
X624908Y247776D01*
X624898Y247736D01*
X624893Y247691D01*
Y247651D01*
X624888Y247606D01*
X624893Y247561D01*
Y247521D01*
X624898Y247476D01*
X624908Y247436D01*
X624913Y247396D01*
X624928Y247351D01*
X624938Y247311D01*
X624953Y247271D01*
X624973Y247231D01*
X624988Y247196D01*
X625008Y247156D01*
X625108Y247016D01*
X625138Y246986D01*
Y243556D01*
X625148Y243431D01*
X625188Y243306D01*
X625248Y243196D01*
X625328Y243096D01*
X625428Y243016D01*
X625538Y242956D01*
X625663Y242916D01*
X625788Y242906D01*
X625913Y242916D01*
X626038Y242956D01*
X626148Y243016D01*
X626248Y243096D01*
X626328Y243196D01*
X626388Y243306D01*
X626428Y243431D01*
X626438Y243556D01*
Y246986D01*
X626468Y247016D01*
X626568Y247156D01*
X626588Y247196D01*
X626603Y247231D01*
X626623Y247271D01*
X626638Y247311D01*
X626648Y247351D01*
X626663Y247396D01*
X626668Y247436D01*
X626678Y247476D01*
X626683Y247521D01*
Y247561D01*
X626688Y247606D01*
X626683Y247651D01*
Y247691D01*
X626678Y247736D01*
X626668Y247776D01*
X626663Y247816D01*
X626648Y247861D01*
X626638Y247901D01*
X626623Y247941D01*
X626603Y247981D01*
X626588Y248016D01*
X626568Y248056D01*
X626468Y248196D01*
X626438Y248226D01*
Y249356D01*
X626428Y249481D01*
X626388Y249606D01*
X626328Y249716D01*
X626248Y249816D01*
X626148Y249896D01*
X626038Y249956D01*
X625913Y249996D01*
X625788Y250006D01*
G37*
G36*
G01X630512D02*
X630387Y249996D01*
X630262Y249956D01*
X630152Y249896D01*
X630052Y249816D01*
X629972Y249716D01*
X629912Y249606D01*
X629872Y249481D01*
X629862Y249356D01*
Y248226D01*
X629832Y248196D01*
X629732Y248056D01*
X629712Y248016D01*
X629697Y247981D01*
X629677Y247941D01*
X629662Y247901D01*
X629652Y247861D01*
X629637Y247816D01*
X629632Y247776D01*
X629622Y247736D01*
X629617Y247691D01*
Y247651D01*
X629612Y247606D01*
X629617Y247561D01*
Y247521D01*
X629622Y247476D01*
X629632Y247436D01*
X629637Y247396D01*
X629652Y247351D01*
X629662Y247311D01*
X629677Y247271D01*
X629697Y247231D01*
X629712Y247196D01*
X629732Y247156D01*
X629832Y247016D01*
X629862Y246986D01*
Y243556D01*
X629872Y243431D01*
X629912Y243306D01*
X629972Y243196D01*
X630052Y243096D01*
X630152Y243016D01*
X630262Y242956D01*
X630387Y242916D01*
X630512Y242906D01*
X630637Y242916D01*
X630762Y242956D01*
X630872Y243016D01*
X630972Y243096D01*
X631052Y243196D01*
X631112Y243306D01*
X631152Y243431D01*
X631162Y243556D01*
Y246986D01*
X631192Y247016D01*
X631292Y247156D01*
X631312Y247196D01*
X631327Y247231D01*
X631347Y247271D01*
X631362Y247311D01*
X631372Y247351D01*
X631387Y247396D01*
X631392Y247436D01*
X631402Y247476D01*
X631407Y247521D01*
Y247561D01*
X631412Y247606D01*
X631407Y247651D01*
Y247691D01*
X631402Y247736D01*
X631392Y247776D01*
X631387Y247816D01*
X631372Y247861D01*
X631362Y247901D01*
X631347Y247941D01*
X631327Y247981D01*
X631312Y248016D01*
X631292Y248056D01*
X631192Y248196D01*
X631162Y248226D01*
Y249356D01*
X631152Y249481D01*
X631112Y249606D01*
X631052Y249716D01*
X630972Y249816D01*
X630872Y249896D01*
X630762Y249956D01*
X630637Y249996D01*
X630512Y250006D01*
G37*
G36*
G01X635236D02*
X635111Y249996D01*
X634986Y249956D01*
X634876Y249896D01*
X634776Y249816D01*
X634696Y249716D01*
X634636Y249606D01*
X634596Y249481D01*
X634586Y249356D01*
Y248226D01*
X634556Y248196D01*
X634456Y248056D01*
X634436Y248016D01*
X634421Y247981D01*
X634401Y247941D01*
X634386Y247901D01*
X634376Y247861D01*
X634361Y247816D01*
X634356Y247776D01*
X634346Y247736D01*
X634341Y247691D01*
Y247651D01*
X634336Y247606D01*
X634341Y247561D01*
Y247521D01*
X634346Y247476D01*
X634356Y247436D01*
X634361Y247396D01*
X634376Y247351D01*
X634386Y247311D01*
X634401Y247271D01*
X634421Y247231D01*
X634436Y247196D01*
X634456Y247156D01*
X634556Y247016D01*
X634586Y246986D01*
Y243556D01*
X634596Y243431D01*
X634636Y243306D01*
X634696Y243196D01*
X634776Y243096D01*
X634876Y243016D01*
X634986Y242956D01*
X635111Y242916D01*
X635236Y242906D01*
X635361Y242916D01*
X635486Y242956D01*
X635596Y243016D01*
X635696Y243096D01*
X635776Y243196D01*
X635836Y243306D01*
X635876Y243431D01*
X635886Y243556D01*
Y246986D01*
X635916Y247016D01*
X636016Y247156D01*
X636036Y247196D01*
X636051Y247231D01*
X636071Y247271D01*
X636086Y247311D01*
X636096Y247351D01*
X636111Y247396D01*
X636116Y247436D01*
X636126Y247476D01*
X636131Y247521D01*
Y247561D01*
X636136Y247606D01*
X636131Y247651D01*
Y247691D01*
X636126Y247736D01*
X636116Y247776D01*
X636111Y247816D01*
X636096Y247861D01*
X636086Y247901D01*
X636071Y247941D01*
X636051Y247981D01*
X636036Y248016D01*
X636016Y248056D01*
X635916Y248196D01*
X635886Y248226D01*
Y249356D01*
X635876Y249481D01*
X635836Y249606D01*
X635776Y249716D01*
X635696Y249816D01*
X635596Y249896D01*
X635486Y249956D01*
X635361Y249996D01*
X635236Y250006D01*
G37*
G36*
G01X639961D02*
X639836Y249996D01*
X639711Y249956D01*
X639601Y249896D01*
X639501Y249816D01*
X639421Y249716D01*
X639361Y249606D01*
X639321Y249481D01*
X639311Y249356D01*
Y248226D01*
X639281Y248196D01*
X639181Y248056D01*
X639161Y248016D01*
X639146Y247981D01*
X639126Y247941D01*
X639111Y247901D01*
X639101Y247861D01*
X639086Y247816D01*
X639081Y247776D01*
X639071Y247736D01*
X639066Y247691D01*
Y247651D01*
X639061Y247606D01*
X639066Y247561D01*
Y247521D01*
X639071Y247476D01*
X639081Y247436D01*
X639086Y247396D01*
X639101Y247351D01*
X639111Y247311D01*
X639126Y247271D01*
X639146Y247231D01*
X639161Y247196D01*
X639181Y247156D01*
X639281Y247016D01*
X639311Y246986D01*
Y243556D01*
X639321Y243431D01*
X639361Y243306D01*
X639421Y243196D01*
X639501Y243096D01*
X639601Y243016D01*
X639711Y242956D01*
X639836Y242916D01*
X639961Y242906D01*
X640086Y242916D01*
X640211Y242956D01*
X640321Y243016D01*
X640421Y243096D01*
X640501Y243196D01*
X640561Y243306D01*
X640601Y243431D01*
X640611Y243556D01*
Y246986D01*
X640641Y247016D01*
X640741Y247156D01*
X640761Y247196D01*
X640776Y247231D01*
X640796Y247271D01*
X640811Y247311D01*
X640821Y247351D01*
X640836Y247396D01*
X640841Y247436D01*
X640851Y247476D01*
X640856Y247521D01*
Y247561D01*
X640861Y247606D01*
X640856Y247651D01*
Y247691D01*
X640851Y247736D01*
X640841Y247776D01*
X640836Y247816D01*
X640821Y247861D01*
X640811Y247901D01*
X640796Y247941D01*
X640776Y247981D01*
X640761Y248016D01*
X640741Y248056D01*
X640641Y248196D01*
X640611Y248226D01*
Y249356D01*
X640601Y249481D01*
X640561Y249606D01*
X640501Y249716D01*
X640421Y249816D01*
X640321Y249896D01*
X640211Y249956D01*
X640086Y249996D01*
X639961Y250006D01*
G37*
G36*
G01X644685D02*
X644560Y249996D01*
X644435Y249956D01*
X644325Y249896D01*
X644225Y249816D01*
X644145Y249716D01*
X644085Y249606D01*
X644045Y249481D01*
X644035Y249356D01*
Y248226D01*
X644005Y248196D01*
X643905Y248056D01*
X643885Y248016D01*
X643870Y247981D01*
X643850Y247941D01*
X643835Y247901D01*
X643825Y247861D01*
X643810Y247816D01*
X643805Y247776D01*
X643795Y247736D01*
X643790Y247691D01*
Y247651D01*
X643785Y247606D01*
X643790Y247561D01*
Y247521D01*
X643795Y247476D01*
X643805Y247436D01*
X643810Y247396D01*
X643825Y247351D01*
X643835Y247311D01*
X643850Y247271D01*
X643870Y247231D01*
X643885Y247196D01*
X643905Y247156D01*
X644005Y247016D01*
X644035Y246986D01*
Y243556D01*
X644045Y243431D01*
X644085Y243306D01*
X644145Y243196D01*
X644225Y243096D01*
X644325Y243016D01*
X644435Y242956D01*
X644560Y242916D01*
X644685Y242906D01*
X644810Y242916D01*
X644935Y242956D01*
X645045Y243016D01*
X645145Y243096D01*
X645225Y243196D01*
X645285Y243306D01*
X645325Y243431D01*
X645335Y243556D01*
Y246986D01*
X645365Y247016D01*
X645465Y247156D01*
X645485Y247196D01*
X645500Y247231D01*
X645520Y247271D01*
X645535Y247311D01*
X645545Y247351D01*
X645560Y247396D01*
X645565Y247436D01*
X645575Y247476D01*
X645580Y247521D01*
Y247561D01*
X645585Y247606D01*
X645580Y247651D01*
Y247691D01*
X645575Y247736D01*
X645565Y247776D01*
X645560Y247816D01*
X645545Y247861D01*
X645535Y247901D01*
X645520Y247941D01*
X645500Y247981D01*
X645485Y248016D01*
X645465Y248056D01*
X645365Y248196D01*
X645335Y248226D01*
Y249356D01*
X645325Y249481D01*
X645285Y249606D01*
X645225Y249716D01*
X645145Y249816D01*
X645045Y249896D01*
X644935Y249956D01*
X644810Y249996D01*
X644685Y250006D01*
G37*
G36*
G01X649410D02*
X649285Y249996D01*
X649160Y249956D01*
X649050Y249896D01*
X648950Y249816D01*
X648870Y249716D01*
X648810Y249606D01*
X648770Y249481D01*
X648760Y249356D01*
Y248226D01*
X648730Y248196D01*
X648630Y248056D01*
X648610Y248016D01*
X648595Y247981D01*
X648575Y247941D01*
X648560Y247901D01*
X648550Y247861D01*
X648535Y247816D01*
X648530Y247776D01*
X648520Y247736D01*
X648515Y247691D01*
Y247651D01*
X648510Y247606D01*
X648515Y247561D01*
Y247521D01*
X648520Y247476D01*
X648530Y247436D01*
X648535Y247396D01*
X648550Y247351D01*
X648560Y247311D01*
X648575Y247271D01*
X648595Y247231D01*
X648610Y247196D01*
X648630Y247156D01*
X648730Y247016D01*
X648760Y246986D01*
Y243556D01*
X648770Y243431D01*
X648810Y243306D01*
X648870Y243196D01*
X648950Y243096D01*
X649050Y243016D01*
X649160Y242956D01*
X649285Y242916D01*
X649410Y242906D01*
X649535Y242916D01*
X649660Y242956D01*
X649770Y243016D01*
X649870Y243096D01*
X649950Y243196D01*
X650010Y243306D01*
X650050Y243431D01*
X650060Y243556D01*
Y246986D01*
X650090Y247016D01*
X650190Y247156D01*
X650210Y247196D01*
X650225Y247231D01*
X650245Y247271D01*
X650260Y247311D01*
X650270Y247351D01*
X650285Y247396D01*
X650290Y247436D01*
X650300Y247476D01*
X650305Y247521D01*
Y247561D01*
X650310Y247606D01*
X650305Y247651D01*
Y247691D01*
X650300Y247736D01*
X650290Y247776D01*
X650285Y247816D01*
X650270Y247861D01*
X650260Y247901D01*
X650245Y247941D01*
X650225Y247981D01*
X650210Y248016D01*
X650190Y248056D01*
X650090Y248196D01*
X650060Y248226D01*
Y249356D01*
X650050Y249481D01*
X650010Y249606D01*
X649950Y249716D01*
X649870Y249816D01*
X649770Y249896D01*
X649660Y249956D01*
X649535Y249996D01*
X649410Y250006D01*
G37*
G36*
G01X654134D02*
X654009Y249996D01*
X653884Y249956D01*
X653774Y249896D01*
X653674Y249816D01*
X653594Y249716D01*
X653534Y249606D01*
X653494Y249481D01*
X653484Y249356D01*
Y248226D01*
X653454Y248196D01*
X653354Y248056D01*
X653334Y248016D01*
X653319Y247981D01*
X653299Y247941D01*
X653284Y247901D01*
X653274Y247861D01*
X653259Y247816D01*
X653254Y247776D01*
X653244Y247736D01*
X653239Y247691D01*
Y247651D01*
X653234Y247606D01*
X653239Y247561D01*
Y247521D01*
X653244Y247476D01*
X653254Y247436D01*
X653259Y247396D01*
X653274Y247351D01*
X653284Y247311D01*
X653299Y247271D01*
X653319Y247231D01*
X653334Y247196D01*
X653354Y247156D01*
X653454Y247016D01*
X653484Y246986D01*
Y243556D01*
X653494Y243431D01*
X653534Y243306D01*
X653594Y243196D01*
X653674Y243096D01*
X653774Y243016D01*
X653884Y242956D01*
X654009Y242916D01*
X654134Y242906D01*
X654259Y242916D01*
X654384Y242956D01*
X654494Y243016D01*
X654594Y243096D01*
X654674Y243196D01*
X654734Y243306D01*
X654774Y243431D01*
X654784Y243556D01*
Y246986D01*
X654814Y247016D01*
X654914Y247156D01*
X654934Y247196D01*
X654949Y247231D01*
X654969Y247271D01*
X654984Y247311D01*
X654994Y247351D01*
X655009Y247396D01*
X655014Y247436D01*
X655024Y247476D01*
X655029Y247521D01*
Y247561D01*
X655034Y247606D01*
X655029Y247651D01*
Y247691D01*
X655024Y247736D01*
X655014Y247776D01*
X655009Y247816D01*
X654994Y247861D01*
X654984Y247901D01*
X654969Y247941D01*
X654949Y247981D01*
X654934Y248016D01*
X654914Y248056D01*
X654814Y248196D01*
X654784Y248226D01*
Y249356D01*
X654774Y249481D01*
X654734Y249606D01*
X654674Y249716D01*
X654594Y249816D01*
X654494Y249896D01*
X654384Y249956D01*
X654259Y249996D01*
X654134Y250006D01*
G37*
G36*
G01X668307D02*
X668182Y249996D01*
X668057Y249956D01*
X667947Y249896D01*
X667847Y249816D01*
X667767Y249716D01*
X667707Y249606D01*
X667667Y249481D01*
X667657Y249356D01*
Y248226D01*
X667627Y248196D01*
X667527Y248056D01*
X667507Y248016D01*
X667492Y247981D01*
X667472Y247941D01*
X667457Y247901D01*
X667447Y247861D01*
X667432Y247816D01*
X667427Y247776D01*
X667417Y247736D01*
X667412Y247691D01*
Y247651D01*
X667407Y247606D01*
X667412Y247561D01*
Y247521D01*
X667417Y247476D01*
X667427Y247436D01*
X667432Y247396D01*
X667447Y247351D01*
X667457Y247311D01*
X667472Y247271D01*
X667492Y247231D01*
X667507Y247196D01*
X667527Y247156D01*
X667627Y247016D01*
X667657Y246986D01*
Y243556D01*
X667667Y243431D01*
X667707Y243306D01*
X667767Y243196D01*
X667847Y243096D01*
X667947Y243016D01*
X668057Y242956D01*
X668182Y242916D01*
X668307Y242906D01*
X668432Y242916D01*
X668557Y242956D01*
X668667Y243016D01*
X668767Y243096D01*
X668847Y243196D01*
X668907Y243306D01*
X668947Y243431D01*
X668957Y243556D01*
Y246986D01*
X668987Y247016D01*
X669087Y247156D01*
X669107Y247196D01*
X669122Y247231D01*
X669142Y247271D01*
X669157Y247311D01*
X669167Y247351D01*
X669182Y247396D01*
X669187Y247436D01*
X669197Y247476D01*
X669202Y247521D01*
Y247561D01*
X669207Y247606D01*
X669202Y247651D01*
Y247691D01*
X669197Y247736D01*
X669187Y247776D01*
X669182Y247816D01*
X669167Y247861D01*
X669157Y247901D01*
X669142Y247941D01*
X669122Y247981D01*
X669107Y248016D01*
X669087Y248056D01*
X668987Y248196D01*
X668957Y248226D01*
Y249356D01*
X668947Y249481D01*
X668907Y249606D01*
X668847Y249716D01*
X668767Y249816D01*
X668667Y249896D01*
X668557Y249956D01*
X668432Y249996D01*
X668307Y250006D01*
G37*
G36*
G01X673032D02*
X672907Y249996D01*
X672782Y249956D01*
X672672Y249896D01*
X672572Y249816D01*
X672492Y249716D01*
X672432Y249606D01*
X672392Y249481D01*
X672382Y249356D01*
Y248226D01*
X672352Y248196D01*
X672252Y248056D01*
X672232Y248016D01*
X672217Y247981D01*
X672197Y247941D01*
X672182Y247901D01*
X672172Y247861D01*
X672157Y247816D01*
X672152Y247776D01*
X672142Y247736D01*
X672137Y247691D01*
Y247651D01*
X672132Y247606D01*
X672137Y247561D01*
Y247521D01*
X672142Y247476D01*
X672152Y247436D01*
X672157Y247396D01*
X672172Y247351D01*
X672182Y247311D01*
X672197Y247271D01*
X672217Y247231D01*
X672232Y247196D01*
X672252Y247156D01*
X672352Y247016D01*
X672382Y246986D01*
Y243556D01*
X672392Y243431D01*
X672432Y243306D01*
X672492Y243196D01*
X672572Y243096D01*
X672672Y243016D01*
X672782Y242956D01*
X672907Y242916D01*
X673032Y242906D01*
X673157Y242916D01*
X673282Y242956D01*
X673392Y243016D01*
X673492Y243096D01*
X673572Y243196D01*
X673632Y243306D01*
X673672Y243431D01*
X673682Y243556D01*
Y246986D01*
X673712Y247016D01*
X673812Y247156D01*
X673832Y247196D01*
X673847Y247231D01*
X673867Y247271D01*
X673882Y247311D01*
X673892Y247351D01*
X673907Y247396D01*
X673912Y247436D01*
X673922Y247476D01*
X673927Y247521D01*
Y247561D01*
X673932Y247606D01*
X673927Y247651D01*
Y247691D01*
X673922Y247736D01*
X673912Y247776D01*
X673907Y247816D01*
X673892Y247861D01*
X673882Y247901D01*
X673867Y247941D01*
X673847Y247981D01*
X673832Y248016D01*
X673812Y248056D01*
X673712Y248196D01*
X673682Y248226D01*
Y249356D01*
X673672Y249481D01*
X673632Y249606D01*
X673572Y249716D01*
X673492Y249816D01*
X673392Y249896D01*
X673282Y249956D01*
X673157Y249996D01*
X673032Y250006D01*
G37*
G36*
G01X677756D02*
X677631Y249996D01*
X677506Y249956D01*
X677396Y249896D01*
X677296Y249816D01*
X677216Y249716D01*
X677156Y249606D01*
X677116Y249481D01*
X677106Y249356D01*
Y248226D01*
X677076Y248196D01*
X676976Y248056D01*
X676956Y248016D01*
X676941Y247981D01*
X676921Y247941D01*
X676906Y247901D01*
X676896Y247861D01*
X676881Y247816D01*
X676876Y247776D01*
X676866Y247736D01*
X676861Y247691D01*
Y247651D01*
X676856Y247606D01*
X676861Y247561D01*
Y247521D01*
X676866Y247476D01*
X676876Y247436D01*
X676881Y247396D01*
X676896Y247351D01*
X676906Y247311D01*
X676921Y247271D01*
X676941Y247231D01*
X676956Y247196D01*
X676976Y247156D01*
X677076Y247016D01*
X677106Y246986D01*
Y243556D01*
X677116Y243431D01*
X677156Y243306D01*
X677216Y243196D01*
X677296Y243096D01*
X677396Y243016D01*
X677506Y242956D01*
X677631Y242916D01*
X677756Y242906D01*
X677881Y242916D01*
X678006Y242956D01*
X678116Y243016D01*
X678216Y243096D01*
X678296Y243196D01*
X678356Y243306D01*
X678396Y243431D01*
X678406Y243556D01*
Y246986D01*
X678436Y247016D01*
X678536Y247156D01*
X678556Y247196D01*
X678571Y247231D01*
X678591Y247271D01*
X678606Y247311D01*
X678616Y247351D01*
X678631Y247396D01*
X678636Y247436D01*
X678646Y247476D01*
X678651Y247521D01*
Y247561D01*
X678656Y247606D01*
X678651Y247651D01*
Y247691D01*
X678646Y247736D01*
X678636Y247776D01*
X678631Y247816D01*
X678616Y247861D01*
X678606Y247901D01*
X678591Y247941D01*
X678571Y247981D01*
X678556Y248016D01*
X678536Y248056D01*
X678436Y248196D01*
X678406Y248226D01*
Y249356D01*
X678396Y249481D01*
X678356Y249606D01*
X678296Y249716D01*
X678216Y249816D01*
X678116Y249896D01*
X678006Y249956D01*
X677881Y249996D01*
X677756Y250006D01*
G37*
G36*
G01X682481D02*
X682356Y249996D01*
X682231Y249956D01*
X682121Y249896D01*
X682021Y249816D01*
X681941Y249716D01*
X681881Y249606D01*
X681841Y249481D01*
X681831Y249356D01*
Y248226D01*
X681801Y248196D01*
X681701Y248056D01*
X681681Y248016D01*
X681666Y247981D01*
X681646Y247941D01*
X681631Y247901D01*
X681621Y247861D01*
X681606Y247816D01*
X681601Y247776D01*
X681591Y247736D01*
X681586Y247691D01*
Y247651D01*
X681581Y247606D01*
X681586Y247561D01*
Y247521D01*
X681591Y247476D01*
X681601Y247436D01*
X681606Y247396D01*
X681621Y247351D01*
X681631Y247311D01*
X681646Y247271D01*
X681666Y247231D01*
X681681Y247196D01*
X681701Y247156D01*
X681801Y247016D01*
X681831Y246986D01*
Y243556D01*
X681841Y243431D01*
X681881Y243306D01*
X681941Y243196D01*
X682021Y243096D01*
X682121Y243016D01*
X682231Y242956D01*
X682356Y242916D01*
X682481Y242906D01*
X682606Y242916D01*
X682731Y242956D01*
X682841Y243016D01*
X682941Y243096D01*
X683021Y243196D01*
X683081Y243306D01*
X683121Y243431D01*
X683131Y243556D01*
Y246986D01*
X683161Y247016D01*
X683261Y247156D01*
X683281Y247196D01*
X683296Y247231D01*
X683316Y247271D01*
X683331Y247311D01*
X683341Y247351D01*
X683356Y247396D01*
X683361Y247436D01*
X683371Y247476D01*
X683376Y247521D01*
Y247561D01*
X683381Y247606D01*
X683376Y247651D01*
Y247691D01*
X683371Y247736D01*
X683361Y247776D01*
X683356Y247816D01*
X683341Y247861D01*
X683331Y247901D01*
X683316Y247941D01*
X683296Y247981D01*
X683281Y248016D01*
X683261Y248056D01*
X683161Y248196D01*
X683131Y248226D01*
Y249356D01*
X683121Y249481D01*
X683081Y249606D01*
X683021Y249716D01*
X682941Y249816D01*
X682841Y249896D01*
X682731Y249956D01*
X682606Y249996D01*
X682481Y250006D01*
G37*
G36*
G01X687205D02*
X687080Y249996D01*
X686955Y249956D01*
X686845Y249896D01*
X686745Y249816D01*
X686665Y249716D01*
X686605Y249606D01*
X686565Y249481D01*
X686555Y249356D01*
Y248226D01*
X686525Y248196D01*
X686425Y248056D01*
X686405Y248016D01*
X686390Y247981D01*
X686370Y247941D01*
X686355Y247901D01*
X686345Y247861D01*
X686330Y247816D01*
X686325Y247776D01*
X686315Y247736D01*
X686310Y247691D01*
Y247651D01*
X686305Y247606D01*
X686310Y247561D01*
Y247521D01*
X686315Y247476D01*
X686325Y247436D01*
X686330Y247396D01*
X686345Y247351D01*
X686355Y247311D01*
X686370Y247271D01*
X686390Y247231D01*
X686405Y247196D01*
X686425Y247156D01*
X686525Y247016D01*
X686555Y246986D01*
Y243556D01*
X686565Y243431D01*
X686605Y243306D01*
X686665Y243196D01*
X686745Y243096D01*
X686845Y243016D01*
X686955Y242956D01*
X687080Y242916D01*
X687205Y242906D01*
X687330Y242916D01*
X687455Y242956D01*
X687565Y243016D01*
X687665Y243096D01*
X687745Y243196D01*
X687805Y243306D01*
X687845Y243431D01*
X687855Y243556D01*
Y246986D01*
X687885Y247016D01*
X687985Y247156D01*
X688005Y247196D01*
X688020Y247231D01*
X688040Y247271D01*
X688055Y247311D01*
X688065Y247351D01*
X688080Y247396D01*
X688085Y247436D01*
X688095Y247476D01*
X688100Y247521D01*
Y247561D01*
X688105Y247606D01*
X688100Y247651D01*
Y247691D01*
X688095Y247736D01*
X688085Y247776D01*
X688080Y247816D01*
X688065Y247861D01*
X688055Y247901D01*
X688040Y247941D01*
X688020Y247981D01*
X688005Y248016D01*
X687985Y248056D01*
X687885Y248196D01*
X687855Y248226D01*
Y249356D01*
X687845Y249481D01*
X687805Y249606D01*
X687745Y249716D01*
X687665Y249816D01*
X687565Y249896D01*
X687455Y249956D01*
X687330Y249996D01*
X687205Y250006D01*
G37*
G36*
G01X691929D02*
X691804Y249996D01*
X691679Y249956D01*
X691569Y249896D01*
X691469Y249816D01*
X691389Y249716D01*
X691329Y249606D01*
X691289Y249481D01*
X691279Y249356D01*
Y248226D01*
X691249Y248196D01*
X691149Y248056D01*
X691129Y248016D01*
X691114Y247981D01*
X691094Y247941D01*
X691079Y247901D01*
X691069Y247861D01*
X691054Y247816D01*
X691049Y247776D01*
X691039Y247736D01*
X691034Y247691D01*
Y247651D01*
X691029Y247606D01*
X691034Y247561D01*
Y247521D01*
X691039Y247476D01*
X691049Y247436D01*
X691054Y247396D01*
X691069Y247351D01*
X691079Y247311D01*
X691094Y247271D01*
X691114Y247231D01*
X691129Y247196D01*
X691149Y247156D01*
X691249Y247016D01*
X691279Y246986D01*
Y243556D01*
X691289Y243431D01*
X691329Y243306D01*
X691389Y243196D01*
X691469Y243096D01*
X691569Y243016D01*
X691679Y242956D01*
X691804Y242916D01*
X691929Y242906D01*
X692054Y242916D01*
X692179Y242956D01*
X692289Y243016D01*
X692389Y243096D01*
X692469Y243196D01*
X692529Y243306D01*
X692569Y243431D01*
X692579Y243556D01*
Y246986D01*
X692609Y247016D01*
X692709Y247156D01*
X692729Y247196D01*
X692744Y247231D01*
X692764Y247271D01*
X692779Y247311D01*
X692789Y247351D01*
X692804Y247396D01*
X692809Y247436D01*
X692819Y247476D01*
X692824Y247521D01*
Y247561D01*
X692829Y247606D01*
X692824Y247651D01*
Y247691D01*
X692819Y247736D01*
X692809Y247776D01*
X692804Y247816D01*
X692789Y247861D01*
X692779Y247901D01*
X692764Y247941D01*
X692744Y247981D01*
X692729Y248016D01*
X692709Y248056D01*
X692609Y248196D01*
X692579Y248226D01*
Y249356D01*
X692569Y249481D01*
X692529Y249606D01*
X692469Y249716D01*
X692389Y249816D01*
X692289Y249896D01*
X692179Y249956D01*
X692054Y249996D01*
X691929Y250006D01*
G37*
G36*
G01X696654D02*
X696529Y249996D01*
X696404Y249956D01*
X696294Y249896D01*
X696194Y249816D01*
X696114Y249716D01*
X696054Y249606D01*
X696014Y249481D01*
X696004Y249356D01*
Y248226D01*
X695974Y248196D01*
X695874Y248056D01*
X695854Y248016D01*
X695839Y247981D01*
X695819Y247941D01*
X695804Y247901D01*
X695794Y247861D01*
X695779Y247816D01*
X695774Y247776D01*
X695764Y247736D01*
X695759Y247691D01*
Y247651D01*
X695754Y247606D01*
X695759Y247561D01*
Y247521D01*
X695764Y247476D01*
X695774Y247436D01*
X695779Y247396D01*
X695794Y247351D01*
X695804Y247311D01*
X695819Y247271D01*
X695839Y247231D01*
X695854Y247196D01*
X695874Y247156D01*
X695974Y247016D01*
X696004Y246986D01*
Y243556D01*
X696014Y243431D01*
X696054Y243306D01*
X696114Y243196D01*
X696194Y243096D01*
X696294Y243016D01*
X696404Y242956D01*
X696529Y242916D01*
X696654Y242906D01*
X696779Y242916D01*
X696904Y242956D01*
X697014Y243016D01*
X697114Y243096D01*
X697194Y243196D01*
X697254Y243306D01*
X697294Y243431D01*
X697304Y243556D01*
Y246986D01*
X697334Y247016D01*
X697434Y247156D01*
X697454Y247196D01*
X697469Y247231D01*
X697489Y247271D01*
X697504Y247311D01*
X697514Y247351D01*
X697529Y247396D01*
X697534Y247436D01*
X697544Y247476D01*
X697549Y247521D01*
Y247561D01*
X697554Y247606D01*
X697549Y247651D01*
Y247691D01*
X697544Y247736D01*
X697534Y247776D01*
X697529Y247816D01*
X697514Y247861D01*
X697504Y247901D01*
X697489Y247941D01*
X697469Y247981D01*
X697454Y248016D01*
X697434Y248056D01*
X697334Y248196D01*
X697304Y248226D01*
Y249356D01*
X697294Y249481D01*
X697254Y249606D01*
X697194Y249716D01*
X697114Y249816D01*
X697014Y249896D01*
X696904Y249956D01*
X696779Y249996D01*
X696654Y250006D01*
G37*
G36*
G01X701378D02*
X701253Y249996D01*
X701128Y249956D01*
X701018Y249896D01*
X700918Y249816D01*
X700838Y249716D01*
X700778Y249606D01*
X700738Y249481D01*
X700728Y249356D01*
Y248226D01*
X700698Y248196D01*
X700598Y248056D01*
X700578Y248016D01*
X700563Y247981D01*
X700543Y247941D01*
X700528Y247901D01*
X700518Y247861D01*
X700503Y247816D01*
X700498Y247776D01*
X700488Y247736D01*
X700483Y247691D01*
Y247651D01*
X700478Y247606D01*
X700483Y247561D01*
Y247521D01*
X700488Y247476D01*
X700498Y247436D01*
X700503Y247396D01*
X700518Y247351D01*
X700528Y247311D01*
X700543Y247271D01*
X700563Y247231D01*
X700578Y247196D01*
X700598Y247156D01*
X700698Y247016D01*
X700728Y246986D01*
Y243556D01*
X700738Y243431D01*
X700778Y243306D01*
X700838Y243196D01*
X700918Y243096D01*
X701018Y243016D01*
X701128Y242956D01*
X701253Y242916D01*
X701378Y242906D01*
X701503Y242916D01*
X701628Y242956D01*
X701738Y243016D01*
X701838Y243096D01*
X701918Y243196D01*
X701978Y243306D01*
X702018Y243431D01*
X702028Y243556D01*
Y246986D01*
X702058Y247016D01*
X702158Y247156D01*
X702178Y247196D01*
X702193Y247231D01*
X702213Y247271D01*
X702228Y247311D01*
X702238Y247351D01*
X702253Y247396D01*
X702258Y247436D01*
X702268Y247476D01*
X702273Y247521D01*
Y247561D01*
X702278Y247606D01*
X702273Y247651D01*
Y247691D01*
X702268Y247736D01*
X702258Y247776D01*
X702253Y247816D01*
X702238Y247861D01*
X702228Y247901D01*
X702213Y247941D01*
X702193Y247981D01*
X702178Y248016D01*
X702158Y248056D01*
X702058Y248196D01*
X702028Y248226D01*
Y249356D01*
X702018Y249481D01*
X701978Y249606D01*
X701918Y249716D01*
X701838Y249816D01*
X701738Y249896D01*
X701628Y249956D01*
X701503Y249996D01*
X701378Y250006D01*
G37*
G36*
G01X706103D02*
X705978Y249996D01*
X705853Y249956D01*
X705743Y249896D01*
X705643Y249816D01*
X705563Y249716D01*
X705503Y249606D01*
X705463Y249481D01*
X705453Y249356D01*
Y248226D01*
X705423Y248196D01*
X705323Y248056D01*
X705303Y248016D01*
X705288Y247981D01*
X705268Y247941D01*
X705253Y247901D01*
X705243Y247861D01*
X705228Y247816D01*
X705223Y247776D01*
X705213Y247736D01*
X705208Y247691D01*
Y247651D01*
X705203Y247606D01*
X705208Y247561D01*
Y247521D01*
X705213Y247476D01*
X705223Y247436D01*
X705228Y247396D01*
X705243Y247351D01*
X705253Y247311D01*
X705268Y247271D01*
X705288Y247231D01*
X705303Y247196D01*
X705323Y247156D01*
X705423Y247016D01*
X705453Y246986D01*
Y243556D01*
X705463Y243431D01*
X705503Y243306D01*
X705563Y243196D01*
X705643Y243096D01*
X705743Y243016D01*
X705853Y242956D01*
X705978Y242916D01*
X706103Y242906D01*
X706228Y242916D01*
X706353Y242956D01*
X706463Y243016D01*
X706563Y243096D01*
X706643Y243196D01*
X706703Y243306D01*
X706743Y243431D01*
X706753Y243556D01*
Y246986D01*
X706783Y247016D01*
X706883Y247156D01*
X706903Y247196D01*
X706918Y247231D01*
X706938Y247271D01*
X706953Y247311D01*
X706963Y247351D01*
X706978Y247396D01*
X706983Y247436D01*
X706993Y247476D01*
X706998Y247521D01*
Y247561D01*
X707003Y247606D01*
X706998Y247651D01*
Y247691D01*
X706993Y247736D01*
X706983Y247776D01*
X706978Y247816D01*
X706963Y247861D01*
X706953Y247901D01*
X706938Y247941D01*
X706918Y247981D01*
X706903Y248016D01*
X706883Y248056D01*
X706783Y248196D01*
X706753Y248226D01*
Y249356D01*
X706743Y249481D01*
X706703Y249606D01*
X706643Y249716D01*
X706563Y249816D01*
X706463Y249896D01*
X706353Y249956D01*
X706228Y249996D01*
X706103Y250006D01*
G37*
G36*
G01X710827D02*
X710702Y249996D01*
X710577Y249956D01*
X710467Y249896D01*
X710367Y249816D01*
X710287Y249716D01*
X710227Y249606D01*
X710187Y249481D01*
X710177Y249356D01*
Y248226D01*
X710147Y248196D01*
X710047Y248056D01*
X710027Y248016D01*
X710012Y247981D01*
X709992Y247941D01*
X709977Y247901D01*
X709967Y247861D01*
X709952Y247816D01*
X709947Y247776D01*
X709937Y247736D01*
X709932Y247691D01*
Y247651D01*
X709927Y247606D01*
X709932Y247561D01*
Y247521D01*
X709937Y247476D01*
X709947Y247436D01*
X709952Y247396D01*
X709967Y247351D01*
X709977Y247311D01*
X709992Y247271D01*
X710012Y247231D01*
X710027Y247196D01*
X710047Y247156D01*
X710147Y247016D01*
X710177Y246986D01*
Y243556D01*
X710187Y243431D01*
X710227Y243306D01*
X710287Y243196D01*
X710367Y243096D01*
X710467Y243016D01*
X710577Y242956D01*
X710702Y242916D01*
X710827Y242906D01*
X710952Y242916D01*
X711077Y242956D01*
X711187Y243016D01*
X711287Y243096D01*
X711367Y243196D01*
X711427Y243306D01*
X711467Y243431D01*
X711477Y243556D01*
Y246986D01*
X711507Y247016D01*
X711607Y247156D01*
X711627Y247196D01*
X711642Y247231D01*
X711662Y247271D01*
X711677Y247311D01*
X711687Y247351D01*
X711702Y247396D01*
X711707Y247436D01*
X711717Y247476D01*
X711722Y247521D01*
Y247561D01*
X711727Y247606D01*
X711722Y247651D01*
Y247691D01*
X711717Y247736D01*
X711707Y247776D01*
X711702Y247816D01*
X711687Y247861D01*
X711677Y247901D01*
X711662Y247941D01*
X711642Y247981D01*
X711627Y248016D01*
X711607Y248056D01*
X711507Y248196D01*
X711477Y248226D01*
Y249356D01*
X711467Y249481D01*
X711427Y249606D01*
X711367Y249716D01*
X711287Y249816D01*
X711187Y249896D01*
X711077Y249956D01*
X710952Y249996D01*
X710827Y250006D01*
G37*
G36*
G01X715551D02*
X715426Y249996D01*
X715301Y249956D01*
X715191Y249896D01*
X715091Y249816D01*
X715011Y249716D01*
X714951Y249606D01*
X714911Y249481D01*
X714901Y249356D01*
Y248226D01*
X714871Y248196D01*
X714771Y248056D01*
X714751Y248016D01*
X714736Y247981D01*
X714716Y247941D01*
X714701Y247901D01*
X714691Y247861D01*
X714676Y247816D01*
X714671Y247776D01*
X714661Y247736D01*
X714656Y247691D01*
Y247651D01*
X714651Y247606D01*
X714656Y247561D01*
Y247521D01*
X714661Y247476D01*
X714671Y247436D01*
X714676Y247396D01*
X714691Y247351D01*
X714701Y247311D01*
X714716Y247271D01*
X714736Y247231D01*
X714751Y247196D01*
X714771Y247156D01*
X714871Y247016D01*
X714901Y246986D01*
Y243556D01*
X714911Y243431D01*
X714951Y243306D01*
X715011Y243196D01*
X715091Y243096D01*
X715191Y243016D01*
X715301Y242956D01*
X715426Y242916D01*
X715551Y242906D01*
X715676Y242916D01*
X715801Y242956D01*
X715911Y243016D01*
X716011Y243096D01*
X716091Y243196D01*
X716151Y243306D01*
X716191Y243431D01*
X716201Y243556D01*
Y246986D01*
X716231Y247016D01*
X716331Y247156D01*
X716351Y247196D01*
X716366Y247231D01*
X716386Y247271D01*
X716401Y247311D01*
X716411Y247351D01*
X716426Y247396D01*
X716431Y247436D01*
X716441Y247476D01*
X716446Y247521D01*
Y247561D01*
X716451Y247606D01*
X716446Y247651D01*
Y247691D01*
X716441Y247736D01*
X716431Y247776D01*
X716426Y247816D01*
X716411Y247861D01*
X716401Y247901D01*
X716386Y247941D01*
X716366Y247981D01*
X716351Y248016D01*
X716331Y248056D01*
X716231Y248196D01*
X716201Y248226D01*
Y249356D01*
X716191Y249481D01*
X716151Y249606D01*
X716091Y249716D01*
X716011Y249816D01*
X715911Y249896D01*
X715801Y249956D01*
X715676Y249996D01*
X715551Y250006D01*
G37*
G36*
G01X720276D02*
X720151Y249996D01*
X720026Y249956D01*
X719916Y249896D01*
X719816Y249816D01*
X719736Y249716D01*
X719676Y249606D01*
X719636Y249481D01*
X719626Y249356D01*
Y248226D01*
X719596Y248196D01*
X719496Y248056D01*
X719476Y248016D01*
X719461Y247981D01*
X719441Y247941D01*
X719426Y247901D01*
X719416Y247861D01*
X719401Y247816D01*
X719396Y247776D01*
X719386Y247736D01*
X719381Y247691D01*
Y247651D01*
X719376Y247606D01*
X719381Y247561D01*
Y247521D01*
X719386Y247476D01*
X719396Y247436D01*
X719401Y247396D01*
X719416Y247351D01*
X719426Y247311D01*
X719441Y247271D01*
X719461Y247231D01*
X719476Y247196D01*
X719496Y247156D01*
X719596Y247016D01*
X719626Y246986D01*
Y243556D01*
X719636Y243431D01*
X719676Y243306D01*
X719736Y243196D01*
X719816Y243096D01*
X719916Y243016D01*
X720026Y242956D01*
X720151Y242916D01*
X720276Y242906D01*
X720401Y242916D01*
X720526Y242956D01*
X720636Y243016D01*
X720736Y243096D01*
X720816Y243196D01*
X720876Y243306D01*
X720916Y243431D01*
X720926Y243556D01*
Y246986D01*
X720956Y247016D01*
X721056Y247156D01*
X721076Y247196D01*
X721091Y247231D01*
X721111Y247271D01*
X721126Y247311D01*
X721136Y247351D01*
X721151Y247396D01*
X721156Y247436D01*
X721166Y247476D01*
X721171Y247521D01*
Y247561D01*
X721176Y247606D01*
X721171Y247651D01*
Y247691D01*
X721166Y247736D01*
X721156Y247776D01*
X721151Y247816D01*
X721136Y247861D01*
X721126Y247901D01*
X721111Y247941D01*
X721091Y247981D01*
X721076Y248016D01*
X721056Y248056D01*
X720956Y248196D01*
X720926Y248226D01*
Y249356D01*
X720916Y249481D01*
X720876Y249606D01*
X720816Y249716D01*
X720736Y249816D01*
X720636Y249896D01*
X720526Y249956D01*
X720401Y249996D01*
X720276Y250006D01*
G37*
G36*
G01X725000D02*
X724875Y249996D01*
X724750Y249956D01*
X724640Y249896D01*
X724540Y249816D01*
X724460Y249716D01*
X724400Y249606D01*
X724360Y249481D01*
X724350Y249356D01*
Y248226D01*
X724320Y248196D01*
X724220Y248056D01*
X724200Y248016D01*
X724185Y247981D01*
X724165Y247941D01*
X724150Y247901D01*
X724140Y247861D01*
X724125Y247816D01*
X724120Y247776D01*
X724110Y247736D01*
X724105Y247691D01*
Y247651D01*
X724100Y247606D01*
X724105Y247561D01*
Y247521D01*
X724110Y247476D01*
X724120Y247436D01*
X724125Y247396D01*
X724140Y247351D01*
X724150Y247311D01*
X724165Y247271D01*
X724185Y247231D01*
X724200Y247196D01*
X724220Y247156D01*
X724320Y247016D01*
X724350Y246986D01*
Y243556D01*
X724360Y243431D01*
X724400Y243306D01*
X724460Y243196D01*
X724540Y243096D01*
X724640Y243016D01*
X724750Y242956D01*
X724875Y242916D01*
X725000Y242906D01*
X725125Y242916D01*
X725250Y242956D01*
X725360Y243016D01*
X725460Y243096D01*
X725540Y243196D01*
X725600Y243306D01*
X725640Y243431D01*
X725650Y243556D01*
Y246986D01*
X725680Y247016D01*
X725780Y247156D01*
X725800Y247196D01*
X725815Y247231D01*
X725835Y247271D01*
X725850Y247311D01*
X725860Y247351D01*
X725875Y247396D01*
X725880Y247436D01*
X725890Y247476D01*
X725895Y247521D01*
Y247561D01*
X725900Y247606D01*
X725895Y247651D01*
Y247691D01*
X725890Y247736D01*
X725880Y247776D01*
X725875Y247816D01*
X725860Y247861D01*
X725850Y247901D01*
X725835Y247941D01*
X725815Y247981D01*
X725800Y248016D01*
X725780Y248056D01*
X725680Y248196D01*
X725650Y248226D01*
Y249356D01*
X725640Y249481D01*
X725600Y249606D01*
X725540Y249716D01*
X725460Y249816D01*
X725360Y249896D01*
X725250Y249956D01*
X725125Y249996D01*
X725000Y250006D01*
G37*
G36*
G01X729725D02*
X729600Y249996D01*
X729475Y249956D01*
X729365Y249896D01*
X729265Y249816D01*
X729185Y249716D01*
X729125Y249606D01*
X729085Y249481D01*
X729075Y249356D01*
Y248226D01*
X729045Y248196D01*
X728945Y248056D01*
X728925Y248016D01*
X728910Y247981D01*
X728890Y247941D01*
X728875Y247901D01*
X728865Y247861D01*
X728850Y247816D01*
X728845Y247776D01*
X728835Y247736D01*
X728830Y247691D01*
Y247651D01*
X728825Y247606D01*
X728830Y247561D01*
Y247521D01*
X728835Y247476D01*
X728845Y247436D01*
X728850Y247396D01*
X728865Y247351D01*
X728875Y247311D01*
X728890Y247271D01*
X728910Y247231D01*
X728925Y247196D01*
X728945Y247156D01*
X729045Y247016D01*
X729075Y246986D01*
Y243556D01*
X729085Y243431D01*
X729125Y243306D01*
X729185Y243196D01*
X729265Y243096D01*
X729365Y243016D01*
X729475Y242956D01*
X729600Y242916D01*
X729725Y242906D01*
X729850Y242916D01*
X729975Y242956D01*
X730085Y243016D01*
X730185Y243096D01*
X730265Y243196D01*
X730325Y243306D01*
X730365Y243431D01*
X730375Y243556D01*
Y246986D01*
X730405Y247016D01*
X730505Y247156D01*
X730525Y247196D01*
X730540Y247231D01*
X730560Y247271D01*
X730575Y247311D01*
X730585Y247351D01*
X730600Y247396D01*
X730605Y247436D01*
X730615Y247476D01*
X730620Y247521D01*
Y247561D01*
X730625Y247606D01*
X730620Y247651D01*
Y247691D01*
X730615Y247736D01*
X730605Y247776D01*
X730600Y247816D01*
X730585Y247861D01*
X730575Y247901D01*
X730560Y247941D01*
X730540Y247981D01*
X730525Y248016D01*
X730505Y248056D01*
X730405Y248196D01*
X730375Y248226D01*
Y249356D01*
X730365Y249481D01*
X730325Y249606D01*
X730265Y249716D01*
X730185Y249816D01*
X730085Y249896D01*
X729975Y249956D01*
X729850Y249996D01*
X729725Y250006D01*
G37*
G36*
G01X734449D02*
X734324Y249996D01*
X734199Y249956D01*
X734089Y249896D01*
X733989Y249816D01*
X733909Y249716D01*
X733849Y249606D01*
X733809Y249481D01*
X733799Y249356D01*
Y248226D01*
X733769Y248196D01*
X733669Y248056D01*
X733649Y248016D01*
X733634Y247981D01*
X733614Y247941D01*
X733599Y247901D01*
X733589Y247861D01*
X733574Y247816D01*
X733569Y247776D01*
X733559Y247736D01*
X733554Y247691D01*
Y247651D01*
X733549Y247606D01*
X733554Y247561D01*
Y247521D01*
X733559Y247476D01*
X733569Y247436D01*
X733574Y247396D01*
X733589Y247351D01*
X733599Y247311D01*
X733614Y247271D01*
X733634Y247231D01*
X733649Y247196D01*
X733669Y247156D01*
X733769Y247016D01*
X733799Y246986D01*
Y243556D01*
X733809Y243431D01*
X733849Y243306D01*
X733909Y243196D01*
X733989Y243096D01*
X734089Y243016D01*
X734199Y242956D01*
X734324Y242916D01*
X734449Y242906D01*
X734574Y242916D01*
X734699Y242956D01*
X734809Y243016D01*
X734909Y243096D01*
X734989Y243196D01*
X735049Y243306D01*
X735089Y243431D01*
X735099Y243556D01*
Y246986D01*
X735129Y247016D01*
X735229Y247156D01*
X735249Y247196D01*
X735264Y247231D01*
X735284Y247271D01*
X735299Y247311D01*
X735309Y247351D01*
X735324Y247396D01*
X735329Y247436D01*
X735339Y247476D01*
X735344Y247521D01*
Y247561D01*
X735349Y247606D01*
X735344Y247651D01*
Y247691D01*
X735339Y247736D01*
X735329Y247776D01*
X735324Y247816D01*
X735309Y247861D01*
X735299Y247901D01*
X735284Y247941D01*
X735264Y247981D01*
X735249Y248016D01*
X735229Y248056D01*
X735129Y248196D01*
X735099Y248226D01*
Y249356D01*
X735089Y249481D01*
X735049Y249606D01*
X734989Y249716D01*
X734909Y249816D01*
X734809Y249896D01*
X734699Y249956D01*
X734574Y249996D01*
X734449Y250006D01*
G37*
G36*
G01X739173D02*
X739048Y249996D01*
X738923Y249956D01*
X738813Y249896D01*
X738713Y249816D01*
X738633Y249716D01*
X738573Y249606D01*
X738533Y249481D01*
X738523Y249356D01*
Y248226D01*
X738493Y248196D01*
X738393Y248056D01*
X738373Y248016D01*
X738358Y247981D01*
X738338Y247941D01*
X738323Y247901D01*
X738313Y247861D01*
X738298Y247816D01*
X738293Y247776D01*
X738283Y247736D01*
X738278Y247691D01*
Y247651D01*
X738273Y247606D01*
X738278Y247561D01*
Y247521D01*
X738283Y247476D01*
X738293Y247436D01*
X738298Y247396D01*
X738313Y247351D01*
X738323Y247311D01*
X738338Y247271D01*
X738358Y247231D01*
X738373Y247196D01*
X738393Y247156D01*
X738493Y247016D01*
X738523Y246986D01*
Y243556D01*
X738533Y243431D01*
X738573Y243306D01*
X738633Y243196D01*
X738713Y243096D01*
X738813Y243016D01*
X738923Y242956D01*
X739048Y242916D01*
X739173Y242906D01*
X739298Y242916D01*
X739423Y242956D01*
X739533Y243016D01*
X739633Y243096D01*
X739713Y243196D01*
X739773Y243306D01*
X739813Y243431D01*
X739823Y243556D01*
Y246986D01*
X739853Y247016D01*
X739953Y247156D01*
X739973Y247196D01*
X739988Y247231D01*
X740008Y247271D01*
X740023Y247311D01*
X740033Y247351D01*
X740048Y247396D01*
X740053Y247436D01*
X740063Y247476D01*
X740068Y247521D01*
Y247561D01*
X740073Y247606D01*
X740068Y247651D01*
Y247691D01*
X740063Y247736D01*
X740053Y247776D01*
X740048Y247816D01*
X740033Y247861D01*
X740023Y247901D01*
X740008Y247941D01*
X739988Y247981D01*
X739973Y248016D01*
X739953Y248056D01*
X739853Y248196D01*
X739823Y248226D01*
Y249356D01*
X739813Y249481D01*
X739773Y249606D01*
X739713Y249716D01*
X739633Y249816D01*
X739533Y249896D01*
X739423Y249956D01*
X739298Y249996D01*
X739173Y250006D01*
G37*
G36*
G01X743898D02*
X743773Y249996D01*
X743648Y249956D01*
X743538Y249896D01*
X743438Y249816D01*
X743358Y249716D01*
X743298Y249606D01*
X743258Y249481D01*
X743248Y249356D01*
Y248226D01*
X743218Y248196D01*
X743118Y248056D01*
X743098Y248016D01*
X743083Y247981D01*
X743063Y247941D01*
X743048Y247901D01*
X743038Y247861D01*
X743023Y247816D01*
X743018Y247776D01*
X743008Y247736D01*
X743003Y247691D01*
Y247651D01*
X742998Y247606D01*
X743003Y247561D01*
Y247521D01*
X743008Y247476D01*
X743018Y247436D01*
X743023Y247396D01*
X743038Y247351D01*
X743048Y247311D01*
X743063Y247271D01*
X743083Y247231D01*
X743098Y247196D01*
X743118Y247156D01*
X743218Y247016D01*
X743248Y246986D01*
Y243556D01*
X743258Y243431D01*
X743298Y243306D01*
X743358Y243196D01*
X743438Y243096D01*
X743538Y243016D01*
X743648Y242956D01*
X743773Y242916D01*
X743898Y242906D01*
X744023Y242916D01*
X744148Y242956D01*
X744258Y243016D01*
X744358Y243096D01*
X744438Y243196D01*
X744498Y243306D01*
X744538Y243431D01*
X744548Y243556D01*
Y246986D01*
X744578Y247016D01*
X744678Y247156D01*
X744698Y247196D01*
X744713Y247231D01*
X744733Y247271D01*
X744748Y247311D01*
X744758Y247351D01*
X744773Y247396D01*
X744778Y247436D01*
X744788Y247476D01*
X744793Y247521D01*
Y247561D01*
X744798Y247606D01*
X744793Y247651D01*
Y247691D01*
X744788Y247736D01*
X744778Y247776D01*
X744773Y247816D01*
X744758Y247861D01*
X744748Y247901D01*
X744733Y247941D01*
X744713Y247981D01*
X744698Y248016D01*
X744678Y248056D01*
X744578Y248196D01*
X744548Y248226D01*
Y249356D01*
X744538Y249481D01*
X744498Y249606D01*
X744438Y249716D01*
X744358Y249816D01*
X744258Y249896D01*
X744148Y249956D01*
X744023Y249996D01*
X743898Y250006D01*
G37*
G36*
G01X748622D02*
X748497Y249996D01*
X748372Y249956D01*
X748262Y249896D01*
X748162Y249816D01*
X748082Y249716D01*
X748022Y249606D01*
X747982Y249481D01*
X747972Y249356D01*
Y248226D01*
X747942Y248196D01*
X747842Y248056D01*
X747822Y248016D01*
X747807Y247981D01*
X747787Y247941D01*
X747772Y247901D01*
X747762Y247861D01*
X747747Y247816D01*
X747742Y247776D01*
X747732Y247736D01*
X747727Y247691D01*
Y247651D01*
X747722Y247606D01*
X747727Y247561D01*
Y247521D01*
X747732Y247476D01*
X747742Y247436D01*
X747747Y247396D01*
X747762Y247351D01*
X747772Y247311D01*
X747787Y247271D01*
X747807Y247231D01*
X747822Y247196D01*
X747842Y247156D01*
X747942Y247016D01*
X747972Y246986D01*
Y243556D01*
X747982Y243431D01*
X748022Y243306D01*
X748082Y243196D01*
X748162Y243096D01*
X748262Y243016D01*
X748372Y242956D01*
X748497Y242916D01*
X748622Y242906D01*
X748747Y242916D01*
X748872Y242956D01*
X748982Y243016D01*
X749082Y243096D01*
X749162Y243196D01*
X749222Y243306D01*
X749262Y243431D01*
X749272Y243556D01*
Y246986D01*
X749302Y247016D01*
X749402Y247156D01*
X749422Y247196D01*
X749437Y247231D01*
X749457Y247271D01*
X749472Y247311D01*
X749482Y247351D01*
X749497Y247396D01*
X749502Y247436D01*
X749512Y247476D01*
X749517Y247521D01*
Y247561D01*
X749522Y247606D01*
X749517Y247651D01*
Y247691D01*
X749512Y247736D01*
X749502Y247776D01*
X749497Y247816D01*
X749482Y247861D01*
X749472Y247901D01*
X749457Y247941D01*
X749437Y247981D01*
X749422Y248016D01*
X749402Y248056D01*
X749302Y248196D01*
X749272Y248226D01*
Y249356D01*
X749262Y249481D01*
X749222Y249606D01*
X749162Y249716D01*
X749082Y249816D01*
X748982Y249896D01*
X748872Y249956D01*
X748747Y249996D01*
X748622Y250006D01*
G37*
G54D65*
X339200Y269500D03*
X349800D03*
G54D38*
X110517Y196537D03*
Y193978D03*
Y191419D03*
Y188860D03*
Y186301D03*
X129003D03*
Y188860D03*
Y191419D03*
Y193978D03*
Y196537D03*
G54D92*
X804032Y27032D03*
X794032D03*
X804032Y37032D03*
Y47032D03*
X794032Y37032D03*
Y47032D03*
X804032Y57032D03*
X794032D03*
X804032Y67032D03*
X794032D03*
G54D66*
X346500Y67700D03*
Y78300D03*
X365000Y260700D03*
Y271300D03*
X777000Y146900D03*
Y157500D03*
G54D75*
X439441Y260531D03*
Y264469D03*
G54D39*
X114642Y182176D03*
X117201D03*
X119760D03*
X122319D03*
X124878D03*
Y200662D03*
X122319D03*
X119760D03*
X117201D03*
X114642D03*
G54D57*
X268520Y132540D03*
X275880D03*
Y135100D03*
Y137660D03*
X268520D03*
X402820Y59440D03*
Y64560D03*
Y62000D03*
X410180Y59440D03*
Y64560D03*
X461520Y20060D03*
Y14940D03*
X468880Y20060D03*
Y14940D03*
Y17500D03*
G36*
G01X499410Y282290D02*
X499285Y282280D01*
X499160Y282240D01*
X499050Y282180D01*
X498950Y282100D01*
X498870Y282000D01*
X498810Y281890D01*
X498770Y281765D01*
X498760Y281640D01*
Y279210D01*
X498730Y279180D01*
X498630Y279040D01*
X498610Y279000D01*
X498595Y278965D01*
X498575Y278925D01*
X498560Y278885D01*
X498550Y278845D01*
X498535Y278800D01*
X498530Y278760D01*
X498520Y278720D01*
X498515Y278675D01*
Y278635D01*
X498510Y278590D01*
X498515Y278545D01*
Y278505D01*
X498520Y278460D01*
X498530Y278420D01*
X498535Y278380D01*
X498550Y278335D01*
X498560Y278295D01*
X498575Y278255D01*
X498595Y278215D01*
X498610Y278180D01*
X498630Y278140D01*
X498730Y278000D01*
X498760Y277970D01*
Y275840D01*
X498770Y275715D01*
X498810Y275590D01*
X498870Y275480D01*
X498950Y275380D01*
X499050Y275300D01*
X499160Y275240D01*
X499285Y275200D01*
X499410Y275190D01*
X499535Y275200D01*
X499660Y275240D01*
X499770Y275300D01*
X499870Y275380D01*
X499950Y275480D01*
X500010Y275590D01*
X500050Y275715D01*
X500060Y275840D01*
Y277965D01*
X500090Y277995D01*
X500115Y278030D01*
X500145Y278065D01*
X500165Y278100D01*
X500190Y278135D01*
X500230Y278215D01*
X500275Y278335D01*
X500285Y278375D01*
X500295Y278420D01*
X500300Y278460D01*
X500310Y278505D01*
Y278675D01*
X500300Y278720D01*
X500295Y278760D01*
X500285Y278805D01*
X500275Y278845D01*
X500230Y278965D01*
X500190Y279045D01*
X500165Y279080D01*
X500145Y279115D01*
X500115Y279150D01*
X500090Y279185D01*
X500060Y279215D01*
Y281640D01*
X500050Y281765D01*
X500010Y281890D01*
X499950Y282000D01*
X499870Y282100D01*
X499770Y282180D01*
X499660Y282240D01*
X499535Y282280D01*
X499410Y282290D01*
G37*
G36*
G01X504134D02*
X504009Y282280D01*
X503884Y282240D01*
X503774Y282180D01*
X503674Y282100D01*
X503594Y282000D01*
X503534Y281890D01*
X503494Y281765D01*
X503484Y281640D01*
Y279210D01*
X503454Y279180D01*
X503354Y279040D01*
X503334Y279000D01*
X503319Y278965D01*
X503299Y278925D01*
X503284Y278885D01*
X503274Y278845D01*
X503259Y278800D01*
X503254Y278760D01*
X503244Y278720D01*
X503239Y278675D01*
Y278635D01*
X503234Y278590D01*
X503239Y278545D01*
Y278505D01*
X503244Y278460D01*
X503254Y278420D01*
X503259Y278380D01*
X503274Y278335D01*
X503284Y278295D01*
X503299Y278255D01*
X503319Y278215D01*
X503334Y278180D01*
X503354Y278140D01*
X503454Y278000D01*
X503484Y277970D01*
Y275840D01*
X503494Y275715D01*
X503534Y275590D01*
X503594Y275480D01*
X503674Y275380D01*
X503774Y275300D01*
X503884Y275240D01*
X504009Y275200D01*
X504134Y275190D01*
X504259Y275200D01*
X504384Y275240D01*
X504494Y275300D01*
X504594Y275380D01*
X504674Y275480D01*
X504734Y275590D01*
X504774Y275715D01*
X504784Y275840D01*
Y277965D01*
X504814Y277995D01*
X504839Y278030D01*
X504869Y278065D01*
X504889Y278100D01*
X504914Y278135D01*
X504954Y278215D01*
X504999Y278335D01*
X505009Y278375D01*
X505019Y278420D01*
X505024Y278460D01*
X505034Y278505D01*
Y278675D01*
X505024Y278720D01*
X505019Y278760D01*
X505009Y278805D01*
X504999Y278845D01*
X504954Y278965D01*
X504914Y279045D01*
X504889Y279080D01*
X504869Y279115D01*
X504839Y279150D01*
X504814Y279185D01*
X504784Y279215D01*
Y281640D01*
X504774Y281765D01*
X504734Y281890D01*
X504674Y282000D01*
X504594Y282100D01*
X504494Y282180D01*
X504384Y282240D01*
X504259Y282280D01*
X504134Y282290D01*
G37*
G36*
G01X508859D02*
X508734Y282280D01*
X508609Y282240D01*
X508499Y282180D01*
X508399Y282100D01*
X508319Y282000D01*
X508259Y281890D01*
X508219Y281765D01*
X508209Y281640D01*
Y279210D01*
X508179Y279180D01*
X508079Y279040D01*
X508059Y279000D01*
X508044Y278965D01*
X508024Y278925D01*
X508009Y278885D01*
X507999Y278845D01*
X507984Y278800D01*
X507979Y278760D01*
X507969Y278720D01*
X507964Y278675D01*
Y278635D01*
X507959Y278590D01*
X507964Y278545D01*
Y278505D01*
X507969Y278460D01*
X507979Y278420D01*
X507984Y278380D01*
X507999Y278335D01*
X508009Y278295D01*
X508024Y278255D01*
X508044Y278215D01*
X508059Y278180D01*
X508079Y278140D01*
X508179Y278000D01*
X508209Y277970D01*
Y275840D01*
X508219Y275715D01*
X508259Y275590D01*
X508319Y275480D01*
X508399Y275380D01*
X508499Y275300D01*
X508609Y275240D01*
X508734Y275200D01*
X508859Y275190D01*
X508984Y275200D01*
X509109Y275240D01*
X509219Y275300D01*
X509319Y275380D01*
X509399Y275480D01*
X509459Y275590D01*
X509499Y275715D01*
X509509Y275840D01*
Y277965D01*
X509539Y277995D01*
X509564Y278030D01*
X509594Y278065D01*
X509614Y278100D01*
X509639Y278135D01*
X509679Y278215D01*
X509724Y278335D01*
X509734Y278375D01*
X509744Y278420D01*
X509749Y278460D01*
X509759Y278505D01*
Y278675D01*
X509749Y278720D01*
X509744Y278760D01*
X509734Y278805D01*
X509724Y278845D01*
X509679Y278965D01*
X509639Y279045D01*
X509614Y279080D01*
X509594Y279115D01*
X509564Y279150D01*
X509539Y279185D01*
X509509Y279215D01*
Y281640D01*
X509499Y281765D01*
X509459Y281890D01*
X509399Y282000D01*
X509319Y282100D01*
X509219Y282180D01*
X509109Y282240D01*
X508984Y282280D01*
X508859Y282290D01*
G37*
G36*
G01X513583D02*
X513458Y282280D01*
X513333Y282240D01*
X513223Y282180D01*
X513123Y282100D01*
X513043Y282000D01*
X512983Y281890D01*
X512943Y281765D01*
X512933Y281640D01*
Y279210D01*
X512903Y279180D01*
X512803Y279040D01*
X512783Y279000D01*
X512768Y278965D01*
X512748Y278925D01*
X512733Y278885D01*
X512723Y278845D01*
X512708Y278800D01*
X512703Y278760D01*
X512693Y278720D01*
X512688Y278675D01*
Y278635D01*
X512683Y278590D01*
X512688Y278545D01*
Y278505D01*
X512693Y278460D01*
X512703Y278420D01*
X512708Y278380D01*
X512723Y278335D01*
X512733Y278295D01*
X512748Y278255D01*
X512768Y278215D01*
X512783Y278180D01*
X512803Y278140D01*
X512903Y278000D01*
X512933Y277970D01*
Y275840D01*
X512943Y275715D01*
X512983Y275590D01*
X513043Y275480D01*
X513123Y275380D01*
X513223Y275300D01*
X513333Y275240D01*
X513458Y275200D01*
X513583Y275190D01*
X513708Y275200D01*
X513833Y275240D01*
X513943Y275300D01*
X514043Y275380D01*
X514123Y275480D01*
X514183Y275590D01*
X514223Y275715D01*
X514233Y275840D01*
Y277965D01*
X514263Y277995D01*
X514288Y278030D01*
X514318Y278065D01*
X514338Y278100D01*
X514363Y278135D01*
X514403Y278215D01*
X514448Y278335D01*
X514458Y278375D01*
X514468Y278420D01*
X514473Y278460D01*
X514483Y278505D01*
Y278675D01*
X514473Y278720D01*
X514468Y278760D01*
X514458Y278805D01*
X514448Y278845D01*
X514403Y278965D01*
X514363Y279045D01*
X514338Y279080D01*
X514318Y279115D01*
X514288Y279150D01*
X514263Y279185D01*
X514233Y279215D01*
Y281640D01*
X514223Y281765D01*
X514183Y281890D01*
X514123Y282000D01*
X514043Y282100D01*
X513943Y282180D01*
X513833Y282240D01*
X513708Y282280D01*
X513583Y282290D01*
G37*
G36*
G01X518307D02*
X518182Y282280D01*
X518057Y282240D01*
X517947Y282180D01*
X517847Y282100D01*
X517767Y282000D01*
X517707Y281890D01*
X517667Y281765D01*
X517657Y281640D01*
Y279210D01*
X517627Y279180D01*
X517527Y279040D01*
X517507Y279000D01*
X517492Y278965D01*
X517472Y278925D01*
X517457Y278885D01*
X517447Y278845D01*
X517432Y278800D01*
X517427Y278760D01*
X517417Y278720D01*
X517412Y278675D01*
Y278635D01*
X517407Y278590D01*
X517412Y278545D01*
Y278505D01*
X517417Y278460D01*
X517427Y278420D01*
X517432Y278380D01*
X517447Y278335D01*
X517457Y278295D01*
X517472Y278255D01*
X517492Y278215D01*
X517507Y278180D01*
X517527Y278140D01*
X517627Y278000D01*
X517657Y277970D01*
Y275840D01*
X517667Y275715D01*
X517707Y275590D01*
X517767Y275480D01*
X517847Y275380D01*
X517947Y275300D01*
X518057Y275240D01*
X518182Y275200D01*
X518307Y275190D01*
X518432Y275200D01*
X518557Y275240D01*
X518667Y275300D01*
X518767Y275380D01*
X518847Y275480D01*
X518907Y275590D01*
X518947Y275715D01*
X518957Y275840D01*
Y277965D01*
X518987Y277995D01*
X519012Y278030D01*
X519042Y278065D01*
X519062Y278100D01*
X519087Y278135D01*
X519127Y278215D01*
X519172Y278335D01*
X519182Y278375D01*
X519192Y278420D01*
X519197Y278460D01*
X519207Y278505D01*
Y278675D01*
X519197Y278720D01*
X519192Y278760D01*
X519182Y278805D01*
X519172Y278845D01*
X519127Y278965D01*
X519087Y279045D01*
X519062Y279080D01*
X519042Y279115D01*
X519012Y279150D01*
X518987Y279185D01*
X518957Y279215D01*
Y281640D01*
X518947Y281765D01*
X518907Y281890D01*
X518847Y282000D01*
X518767Y282100D01*
X518667Y282180D01*
X518557Y282240D01*
X518432Y282280D01*
X518307Y282290D01*
G37*
G36*
G01X523032D02*
X522907Y282280D01*
X522782Y282240D01*
X522672Y282180D01*
X522572Y282100D01*
X522492Y282000D01*
X522432Y281890D01*
X522392Y281765D01*
X522382Y281640D01*
Y279210D01*
X522352Y279180D01*
X522252Y279040D01*
X522232Y279000D01*
X522217Y278965D01*
X522197Y278925D01*
X522182Y278885D01*
X522172Y278845D01*
X522157Y278800D01*
X522152Y278760D01*
X522142Y278720D01*
X522137Y278675D01*
Y278635D01*
X522132Y278590D01*
X522137Y278545D01*
Y278505D01*
X522142Y278460D01*
X522152Y278420D01*
X522157Y278380D01*
X522172Y278335D01*
X522182Y278295D01*
X522197Y278255D01*
X522217Y278215D01*
X522232Y278180D01*
X522252Y278140D01*
X522352Y278000D01*
X522382Y277970D01*
Y275840D01*
X522392Y275715D01*
X522432Y275590D01*
X522492Y275480D01*
X522572Y275380D01*
X522672Y275300D01*
X522782Y275240D01*
X522907Y275200D01*
X523032Y275190D01*
X523157Y275200D01*
X523282Y275240D01*
X523392Y275300D01*
X523492Y275380D01*
X523572Y275480D01*
X523632Y275590D01*
X523672Y275715D01*
X523682Y275840D01*
Y277965D01*
X523712Y277995D01*
X523737Y278030D01*
X523767Y278065D01*
X523787Y278100D01*
X523812Y278135D01*
X523852Y278215D01*
X523897Y278335D01*
X523907Y278375D01*
X523917Y278420D01*
X523922Y278460D01*
X523932Y278505D01*
Y278675D01*
X523922Y278720D01*
X523917Y278760D01*
X523907Y278805D01*
X523897Y278845D01*
X523852Y278965D01*
X523812Y279045D01*
X523787Y279080D01*
X523767Y279115D01*
X523737Y279150D01*
X523712Y279185D01*
X523682Y279215D01*
Y281640D01*
X523672Y281765D01*
X523632Y281890D01*
X523572Y282000D01*
X523492Y282100D01*
X523392Y282180D01*
X523282Y282240D01*
X523157Y282280D01*
X523032Y282290D01*
G37*
G36*
G01X527756D02*
X527631Y282280D01*
X527506Y282240D01*
X527396Y282180D01*
X527296Y282100D01*
X527216Y282000D01*
X527156Y281890D01*
X527116Y281765D01*
X527106Y281640D01*
Y279210D01*
X527076Y279180D01*
X526976Y279040D01*
X526956Y279000D01*
X526941Y278965D01*
X526921Y278925D01*
X526906Y278885D01*
X526896Y278845D01*
X526881Y278800D01*
X526876Y278760D01*
X526866Y278720D01*
X526861Y278675D01*
Y278635D01*
X526856Y278590D01*
X526861Y278545D01*
Y278505D01*
X526866Y278460D01*
X526876Y278420D01*
X526881Y278380D01*
X526896Y278335D01*
X526906Y278295D01*
X526921Y278255D01*
X526941Y278215D01*
X526956Y278180D01*
X526976Y278140D01*
X527076Y278000D01*
X527106Y277970D01*
Y275840D01*
X527116Y275715D01*
X527156Y275590D01*
X527216Y275480D01*
X527296Y275380D01*
X527396Y275300D01*
X527506Y275240D01*
X527631Y275200D01*
X527756Y275190D01*
X527881Y275200D01*
X528006Y275240D01*
X528116Y275300D01*
X528216Y275380D01*
X528296Y275480D01*
X528356Y275590D01*
X528396Y275715D01*
X528406Y275840D01*
Y277965D01*
X528436Y277995D01*
X528461Y278030D01*
X528491Y278065D01*
X528511Y278100D01*
X528536Y278135D01*
X528576Y278215D01*
X528621Y278335D01*
X528631Y278375D01*
X528641Y278420D01*
X528646Y278460D01*
X528656Y278505D01*
Y278675D01*
X528646Y278720D01*
X528641Y278760D01*
X528631Y278805D01*
X528621Y278845D01*
X528576Y278965D01*
X528536Y279045D01*
X528511Y279080D01*
X528491Y279115D01*
X528461Y279150D01*
X528436Y279185D01*
X528406Y279215D01*
Y281640D01*
X528396Y281765D01*
X528356Y281890D01*
X528296Y282000D01*
X528216Y282100D01*
X528116Y282180D01*
X528006Y282240D01*
X527881Y282280D01*
X527756Y282290D01*
G37*
G36*
G01X532481D02*
X532356Y282280D01*
X532231Y282240D01*
X532121Y282180D01*
X532021Y282100D01*
X531941Y282000D01*
X531881Y281890D01*
X531841Y281765D01*
X531831Y281640D01*
Y279210D01*
X531801Y279180D01*
X531701Y279040D01*
X531681Y279000D01*
X531666Y278965D01*
X531646Y278925D01*
X531631Y278885D01*
X531621Y278845D01*
X531606Y278800D01*
X531601Y278760D01*
X531591Y278720D01*
X531586Y278675D01*
Y278635D01*
X531581Y278590D01*
X531586Y278545D01*
Y278505D01*
X531591Y278460D01*
X531601Y278420D01*
X531606Y278380D01*
X531621Y278335D01*
X531631Y278295D01*
X531646Y278255D01*
X531666Y278215D01*
X531681Y278180D01*
X531701Y278140D01*
X531801Y278000D01*
X531831Y277970D01*
Y275840D01*
X531841Y275715D01*
X531881Y275590D01*
X531941Y275480D01*
X532021Y275380D01*
X532121Y275300D01*
X532231Y275240D01*
X532356Y275200D01*
X532481Y275190D01*
X532606Y275200D01*
X532731Y275240D01*
X532841Y275300D01*
X532941Y275380D01*
X533021Y275480D01*
X533081Y275590D01*
X533121Y275715D01*
X533131Y275840D01*
Y277965D01*
X533161Y277995D01*
X533186Y278030D01*
X533216Y278065D01*
X533236Y278100D01*
X533261Y278135D01*
X533301Y278215D01*
X533346Y278335D01*
X533356Y278375D01*
X533366Y278420D01*
X533371Y278460D01*
X533381Y278505D01*
Y278675D01*
X533371Y278720D01*
X533366Y278760D01*
X533356Y278805D01*
X533346Y278845D01*
X533301Y278965D01*
X533261Y279045D01*
X533236Y279080D01*
X533216Y279115D01*
X533186Y279150D01*
X533161Y279185D01*
X533131Y279215D01*
Y281640D01*
X533121Y281765D01*
X533081Y281890D01*
X533021Y282000D01*
X532941Y282100D01*
X532841Y282180D01*
X532731Y282240D01*
X532606Y282280D01*
X532481Y282290D01*
G37*
G36*
G01X537205D02*
X537080Y282280D01*
X536955Y282240D01*
X536845Y282180D01*
X536745Y282100D01*
X536665Y282000D01*
X536605Y281890D01*
X536565Y281765D01*
X536555Y281640D01*
Y279210D01*
X536525Y279180D01*
X536425Y279040D01*
X536405Y279000D01*
X536390Y278965D01*
X536370Y278925D01*
X536355Y278885D01*
X536345Y278845D01*
X536330Y278800D01*
X536325Y278760D01*
X536315Y278720D01*
X536310Y278675D01*
Y278635D01*
X536305Y278590D01*
X536310Y278545D01*
Y278505D01*
X536315Y278460D01*
X536325Y278420D01*
X536330Y278380D01*
X536345Y278335D01*
X536355Y278295D01*
X536370Y278255D01*
X536390Y278215D01*
X536405Y278180D01*
X536425Y278140D01*
X536525Y278000D01*
X536555Y277970D01*
Y275840D01*
X536565Y275715D01*
X536605Y275590D01*
X536665Y275480D01*
X536745Y275380D01*
X536845Y275300D01*
X536955Y275240D01*
X537080Y275200D01*
X537205Y275190D01*
X537330Y275200D01*
X537455Y275240D01*
X537565Y275300D01*
X537665Y275380D01*
X537745Y275480D01*
X537805Y275590D01*
X537845Y275715D01*
X537855Y275840D01*
Y277965D01*
X537885Y277995D01*
X537910Y278030D01*
X537940Y278065D01*
X537960Y278100D01*
X537985Y278135D01*
X538025Y278215D01*
X538070Y278335D01*
X538080Y278375D01*
X538090Y278420D01*
X538095Y278460D01*
X538105Y278505D01*
Y278675D01*
X538095Y278720D01*
X538090Y278760D01*
X538080Y278805D01*
X538070Y278845D01*
X538025Y278965D01*
X537985Y279045D01*
X537960Y279080D01*
X537940Y279115D01*
X537910Y279150D01*
X537885Y279185D01*
X537855Y279215D01*
Y281640D01*
X537845Y281765D01*
X537805Y281890D01*
X537745Y282000D01*
X537665Y282100D01*
X537565Y282180D01*
X537455Y282240D01*
X537330Y282280D01*
X537205Y282290D01*
G37*
G36*
G01X541929D02*
X541804Y282280D01*
X541679Y282240D01*
X541569Y282180D01*
X541469Y282100D01*
X541389Y282000D01*
X541329Y281890D01*
X541289Y281765D01*
X541279Y281640D01*
Y279210D01*
X541249Y279180D01*
X541149Y279040D01*
X541129Y279000D01*
X541114Y278965D01*
X541094Y278925D01*
X541079Y278885D01*
X541069Y278845D01*
X541054Y278800D01*
X541049Y278760D01*
X541039Y278720D01*
X541034Y278675D01*
Y278635D01*
X541029Y278590D01*
X541034Y278545D01*
Y278505D01*
X541039Y278460D01*
X541049Y278420D01*
X541054Y278380D01*
X541069Y278335D01*
X541079Y278295D01*
X541094Y278255D01*
X541114Y278215D01*
X541129Y278180D01*
X541149Y278140D01*
X541249Y278000D01*
X541279Y277970D01*
Y275840D01*
X541289Y275715D01*
X541329Y275590D01*
X541389Y275480D01*
X541469Y275380D01*
X541569Y275300D01*
X541679Y275240D01*
X541804Y275200D01*
X541929Y275190D01*
X542054Y275200D01*
X542179Y275240D01*
X542289Y275300D01*
X542389Y275380D01*
X542469Y275480D01*
X542529Y275590D01*
X542569Y275715D01*
X542579Y275840D01*
Y277965D01*
X542609Y277995D01*
X542634Y278030D01*
X542664Y278065D01*
X542684Y278100D01*
X542709Y278135D01*
X542749Y278215D01*
X542794Y278335D01*
X542804Y278375D01*
X542814Y278420D01*
X542819Y278460D01*
X542829Y278505D01*
Y278675D01*
X542819Y278720D01*
X542814Y278760D01*
X542804Y278805D01*
X542794Y278845D01*
X542749Y278965D01*
X542709Y279045D01*
X542684Y279080D01*
X542664Y279115D01*
X542634Y279150D01*
X542609Y279185D01*
X542579Y279215D01*
Y281640D01*
X542569Y281765D01*
X542529Y281890D01*
X542469Y282000D01*
X542389Y282100D01*
X542289Y282180D01*
X542179Y282240D01*
X542054Y282280D01*
X541929Y282290D01*
G37*
G36*
G01X546654D02*
X546529Y282280D01*
X546404Y282240D01*
X546294Y282180D01*
X546194Y282100D01*
X546114Y282000D01*
X546054Y281890D01*
X546014Y281765D01*
X546004Y281640D01*
Y279210D01*
X545974Y279180D01*
X545874Y279040D01*
X545854Y279000D01*
X545839Y278965D01*
X545819Y278925D01*
X545804Y278885D01*
X545794Y278845D01*
X545779Y278800D01*
X545774Y278760D01*
X545764Y278720D01*
X545759Y278675D01*
Y278635D01*
X545754Y278590D01*
X545759Y278545D01*
Y278505D01*
X545764Y278460D01*
X545774Y278420D01*
X545779Y278380D01*
X545794Y278335D01*
X545804Y278295D01*
X545819Y278255D01*
X545839Y278215D01*
X545854Y278180D01*
X545874Y278140D01*
X545974Y278000D01*
X546004Y277970D01*
Y275840D01*
X546014Y275715D01*
X546054Y275590D01*
X546114Y275480D01*
X546194Y275380D01*
X546294Y275300D01*
X546404Y275240D01*
X546529Y275200D01*
X546654Y275190D01*
X546779Y275200D01*
X546904Y275240D01*
X547014Y275300D01*
X547114Y275380D01*
X547194Y275480D01*
X547254Y275590D01*
X547294Y275715D01*
X547304Y275840D01*
Y277965D01*
X547334Y277995D01*
X547359Y278030D01*
X547389Y278065D01*
X547409Y278100D01*
X547434Y278135D01*
X547474Y278215D01*
X547519Y278335D01*
X547529Y278375D01*
X547539Y278420D01*
X547544Y278460D01*
X547554Y278505D01*
Y278675D01*
X547544Y278720D01*
X547539Y278760D01*
X547529Y278805D01*
X547519Y278845D01*
X547474Y278965D01*
X547434Y279045D01*
X547409Y279080D01*
X547389Y279115D01*
X547359Y279150D01*
X547334Y279185D01*
X547304Y279215D01*
Y281640D01*
X547294Y281765D01*
X547254Y281890D01*
X547194Y282000D01*
X547114Y282100D01*
X547014Y282180D01*
X546904Y282240D01*
X546779Y282280D01*
X546654Y282290D01*
G37*
G36*
G01X551378D02*
X551253Y282280D01*
X551128Y282240D01*
X551018Y282180D01*
X550918Y282100D01*
X550838Y282000D01*
X550778Y281890D01*
X550738Y281765D01*
X550728Y281640D01*
Y279210D01*
X550698Y279180D01*
X550598Y279040D01*
X550578Y279000D01*
X550563Y278965D01*
X550543Y278925D01*
X550528Y278885D01*
X550518Y278845D01*
X550503Y278800D01*
X550498Y278760D01*
X550488Y278720D01*
X550483Y278675D01*
Y278635D01*
X550478Y278590D01*
X550483Y278545D01*
Y278505D01*
X550488Y278460D01*
X550498Y278420D01*
X550503Y278380D01*
X550518Y278335D01*
X550528Y278295D01*
X550543Y278255D01*
X550563Y278215D01*
X550578Y278180D01*
X550598Y278140D01*
X550698Y278000D01*
X550728Y277970D01*
Y275840D01*
X550738Y275715D01*
X550778Y275590D01*
X550838Y275480D01*
X550918Y275380D01*
X551018Y275300D01*
X551128Y275240D01*
X551253Y275200D01*
X551378Y275190D01*
X551503Y275200D01*
X551628Y275240D01*
X551738Y275300D01*
X551838Y275380D01*
X551918Y275480D01*
X551978Y275590D01*
X552018Y275715D01*
X552028Y275840D01*
Y277965D01*
X552058Y277995D01*
X552083Y278030D01*
X552113Y278065D01*
X552133Y278100D01*
X552158Y278135D01*
X552198Y278215D01*
X552243Y278335D01*
X552253Y278375D01*
X552263Y278420D01*
X552268Y278460D01*
X552278Y278505D01*
Y278675D01*
X552268Y278720D01*
X552263Y278760D01*
X552253Y278805D01*
X552243Y278845D01*
X552198Y278965D01*
X552158Y279045D01*
X552133Y279080D01*
X552113Y279115D01*
X552083Y279150D01*
X552058Y279185D01*
X552028Y279215D01*
Y281640D01*
X552018Y281765D01*
X551978Y281890D01*
X551918Y282000D01*
X551838Y282100D01*
X551738Y282180D01*
X551628Y282240D01*
X551503Y282280D01*
X551378Y282290D01*
G37*
G36*
G01X556103D02*
X555978Y282280D01*
X555853Y282240D01*
X555743Y282180D01*
X555643Y282100D01*
X555563Y282000D01*
X555503Y281890D01*
X555463Y281765D01*
X555453Y281640D01*
Y279210D01*
X555423Y279180D01*
X555323Y279040D01*
X555303Y279000D01*
X555288Y278965D01*
X555268Y278925D01*
X555253Y278885D01*
X555243Y278845D01*
X555228Y278800D01*
X555223Y278760D01*
X555213Y278720D01*
X555208Y278675D01*
Y278635D01*
X555203Y278590D01*
X555208Y278545D01*
Y278505D01*
X555213Y278460D01*
X555223Y278420D01*
X555228Y278380D01*
X555243Y278335D01*
X555253Y278295D01*
X555268Y278255D01*
X555288Y278215D01*
X555303Y278180D01*
X555323Y278140D01*
X555423Y278000D01*
X555453Y277970D01*
Y275840D01*
X555463Y275715D01*
X555503Y275590D01*
X555563Y275480D01*
X555643Y275380D01*
X555743Y275300D01*
X555853Y275240D01*
X555978Y275200D01*
X556103Y275190D01*
X556228Y275200D01*
X556353Y275240D01*
X556463Y275300D01*
X556563Y275380D01*
X556643Y275480D01*
X556703Y275590D01*
X556743Y275715D01*
X556753Y275840D01*
Y277965D01*
X556783Y277995D01*
X556808Y278030D01*
X556838Y278065D01*
X556858Y278100D01*
X556883Y278135D01*
X556923Y278215D01*
X556968Y278335D01*
X556978Y278375D01*
X556988Y278420D01*
X556993Y278460D01*
X557003Y278505D01*
Y278675D01*
X556993Y278720D01*
X556988Y278760D01*
X556978Y278805D01*
X556968Y278845D01*
X556923Y278965D01*
X556883Y279045D01*
X556858Y279080D01*
X556838Y279115D01*
X556808Y279150D01*
X556783Y279185D01*
X556753Y279215D01*
Y281640D01*
X556743Y281765D01*
X556703Y281890D01*
X556643Y282000D01*
X556563Y282100D01*
X556463Y282180D01*
X556353Y282240D01*
X556228Y282280D01*
X556103Y282290D01*
G37*
G36*
G01X560827D02*
X560702Y282280D01*
X560577Y282240D01*
X560467Y282180D01*
X560367Y282100D01*
X560287Y282000D01*
X560227Y281890D01*
X560187Y281765D01*
X560177Y281640D01*
Y279210D01*
X560147Y279180D01*
X560047Y279040D01*
X560027Y279000D01*
X560012Y278965D01*
X559992Y278925D01*
X559977Y278885D01*
X559967Y278845D01*
X559952Y278800D01*
X559947Y278760D01*
X559937Y278720D01*
X559932Y278675D01*
Y278635D01*
X559927Y278590D01*
X559932Y278545D01*
Y278505D01*
X559937Y278460D01*
X559947Y278420D01*
X559952Y278380D01*
X559967Y278335D01*
X559977Y278295D01*
X559992Y278255D01*
X560012Y278215D01*
X560027Y278180D01*
X560047Y278140D01*
X560147Y278000D01*
X560177Y277970D01*
Y275840D01*
X560187Y275715D01*
X560227Y275590D01*
X560287Y275480D01*
X560367Y275380D01*
X560467Y275300D01*
X560577Y275240D01*
X560702Y275200D01*
X560827Y275190D01*
X560952Y275200D01*
X561077Y275240D01*
X561187Y275300D01*
X561287Y275380D01*
X561367Y275480D01*
X561427Y275590D01*
X561467Y275715D01*
X561477Y275840D01*
Y277965D01*
X561507Y277995D01*
X561532Y278030D01*
X561562Y278065D01*
X561582Y278100D01*
X561607Y278135D01*
X561647Y278215D01*
X561692Y278335D01*
X561702Y278375D01*
X561712Y278420D01*
X561717Y278460D01*
X561727Y278505D01*
Y278675D01*
X561717Y278720D01*
X561712Y278760D01*
X561702Y278805D01*
X561692Y278845D01*
X561647Y278965D01*
X561607Y279045D01*
X561582Y279080D01*
X561562Y279115D01*
X561532Y279150D01*
X561507Y279185D01*
X561477Y279215D01*
Y281640D01*
X561467Y281765D01*
X561427Y281890D01*
X561367Y282000D01*
X561287Y282100D01*
X561187Y282180D01*
X561077Y282240D01*
X560952Y282280D01*
X560827Y282290D01*
G37*
G36*
G01X565551D02*
X565426Y282280D01*
X565301Y282240D01*
X565191Y282180D01*
X565091Y282100D01*
X565011Y282000D01*
X564951Y281890D01*
X564911Y281765D01*
X564901Y281640D01*
Y279210D01*
X564871Y279180D01*
X564771Y279040D01*
X564751Y279000D01*
X564736Y278965D01*
X564716Y278925D01*
X564701Y278885D01*
X564691Y278845D01*
X564676Y278800D01*
X564671Y278760D01*
X564661Y278720D01*
X564656Y278675D01*
Y278635D01*
X564651Y278590D01*
X564656Y278545D01*
Y278505D01*
X564661Y278460D01*
X564671Y278420D01*
X564676Y278380D01*
X564691Y278335D01*
X564701Y278295D01*
X564716Y278255D01*
X564736Y278215D01*
X564751Y278180D01*
X564771Y278140D01*
X564871Y278000D01*
X564901Y277970D01*
Y275840D01*
X564911Y275715D01*
X564951Y275590D01*
X565011Y275480D01*
X565091Y275380D01*
X565191Y275300D01*
X565301Y275240D01*
X565426Y275200D01*
X565551Y275190D01*
X565676Y275200D01*
X565801Y275240D01*
X565911Y275300D01*
X566011Y275380D01*
X566091Y275480D01*
X566151Y275590D01*
X566191Y275715D01*
X566201Y275840D01*
Y277965D01*
X566231Y277995D01*
X566256Y278030D01*
X566286Y278065D01*
X566306Y278100D01*
X566331Y278135D01*
X566371Y278215D01*
X566416Y278335D01*
X566426Y278375D01*
X566436Y278420D01*
X566441Y278460D01*
X566451Y278505D01*
Y278675D01*
X566441Y278720D01*
X566436Y278760D01*
X566426Y278805D01*
X566416Y278845D01*
X566371Y278965D01*
X566331Y279045D01*
X566306Y279080D01*
X566286Y279115D01*
X566256Y279150D01*
X566231Y279185D01*
X566201Y279215D01*
Y281640D01*
X566191Y281765D01*
X566151Y281890D01*
X566091Y282000D01*
X566011Y282100D01*
X565911Y282180D01*
X565801Y282240D01*
X565676Y282280D01*
X565551Y282290D01*
G37*
G36*
G01X570276D02*
X570151Y282280D01*
X570026Y282240D01*
X569916Y282180D01*
X569816Y282100D01*
X569736Y282000D01*
X569676Y281890D01*
X569636Y281765D01*
X569626Y281640D01*
Y279210D01*
X569596Y279180D01*
X569496Y279040D01*
X569476Y279000D01*
X569461Y278965D01*
X569441Y278925D01*
X569426Y278885D01*
X569416Y278845D01*
X569401Y278800D01*
X569396Y278760D01*
X569386Y278720D01*
X569381Y278675D01*
Y278635D01*
X569376Y278590D01*
X569381Y278545D01*
Y278505D01*
X569386Y278460D01*
X569396Y278420D01*
X569401Y278380D01*
X569416Y278335D01*
X569426Y278295D01*
X569441Y278255D01*
X569461Y278215D01*
X569476Y278180D01*
X569496Y278140D01*
X569596Y278000D01*
X569626Y277970D01*
Y275840D01*
X569636Y275715D01*
X569676Y275590D01*
X569736Y275480D01*
X569816Y275380D01*
X569916Y275300D01*
X570026Y275240D01*
X570151Y275200D01*
X570276Y275190D01*
X570401Y275200D01*
X570526Y275240D01*
X570636Y275300D01*
X570736Y275380D01*
X570816Y275480D01*
X570876Y275590D01*
X570916Y275715D01*
X570926Y275840D01*
Y277965D01*
X570956Y277995D01*
X570981Y278030D01*
X571011Y278065D01*
X571031Y278100D01*
X571056Y278135D01*
X571096Y278215D01*
X571141Y278335D01*
X571151Y278375D01*
X571161Y278420D01*
X571166Y278460D01*
X571176Y278505D01*
Y278675D01*
X571166Y278720D01*
X571161Y278760D01*
X571151Y278805D01*
X571141Y278845D01*
X571096Y278965D01*
X571056Y279045D01*
X571031Y279080D01*
X571011Y279115D01*
X570981Y279150D01*
X570956Y279185D01*
X570926Y279215D01*
Y281640D01*
X570916Y281765D01*
X570876Y281890D01*
X570816Y282000D01*
X570736Y282100D01*
X570636Y282180D01*
X570526Y282240D01*
X570401Y282280D01*
X570276Y282290D01*
G37*
G36*
G01X575000D02*
X574875Y282280D01*
X574750Y282240D01*
X574640Y282180D01*
X574540Y282100D01*
X574460Y282000D01*
X574400Y281890D01*
X574360Y281765D01*
X574350Y281640D01*
Y279210D01*
X574320Y279180D01*
X574220Y279040D01*
X574200Y279000D01*
X574185Y278965D01*
X574165Y278925D01*
X574150Y278885D01*
X574140Y278845D01*
X574125Y278800D01*
X574120Y278760D01*
X574110Y278720D01*
X574105Y278675D01*
Y278635D01*
X574100Y278590D01*
X574105Y278545D01*
Y278505D01*
X574110Y278460D01*
X574120Y278420D01*
X574125Y278380D01*
X574140Y278335D01*
X574150Y278295D01*
X574165Y278255D01*
X574185Y278215D01*
X574200Y278180D01*
X574220Y278140D01*
X574320Y278000D01*
X574350Y277970D01*
Y275840D01*
X574360Y275715D01*
X574400Y275590D01*
X574460Y275480D01*
X574540Y275380D01*
X574640Y275300D01*
X574750Y275240D01*
X574875Y275200D01*
X575000Y275190D01*
X575125Y275200D01*
X575250Y275240D01*
X575360Y275300D01*
X575460Y275380D01*
X575540Y275480D01*
X575600Y275590D01*
X575640Y275715D01*
X575650Y275840D01*
Y277965D01*
X575680Y277995D01*
X575705Y278030D01*
X575735Y278065D01*
X575755Y278100D01*
X575780Y278135D01*
X575820Y278215D01*
X575865Y278335D01*
X575875Y278375D01*
X575885Y278420D01*
X575890Y278460D01*
X575900Y278505D01*
Y278675D01*
X575890Y278720D01*
X575885Y278760D01*
X575875Y278805D01*
X575865Y278845D01*
X575820Y278965D01*
X575780Y279045D01*
X575755Y279080D01*
X575735Y279115D01*
X575705Y279150D01*
X575680Y279185D01*
X575650Y279215D01*
Y281640D01*
X575640Y281765D01*
X575600Y281890D01*
X575540Y282000D01*
X575460Y282100D01*
X575360Y282180D01*
X575250Y282240D01*
X575125Y282280D01*
X575000Y282290D01*
G37*
G36*
G01X579725D02*
X579600Y282280D01*
X579475Y282240D01*
X579365Y282180D01*
X579265Y282100D01*
X579185Y282000D01*
X579125Y281890D01*
X579085Y281765D01*
X579075Y281640D01*
Y279210D01*
X579045Y279180D01*
X578945Y279040D01*
X578925Y279000D01*
X578910Y278965D01*
X578890Y278925D01*
X578875Y278885D01*
X578865Y278845D01*
X578850Y278800D01*
X578845Y278760D01*
X578835Y278720D01*
X578830Y278675D01*
Y278635D01*
X578825Y278590D01*
X578830Y278545D01*
Y278505D01*
X578835Y278460D01*
X578845Y278420D01*
X578850Y278380D01*
X578865Y278335D01*
X578875Y278295D01*
X578890Y278255D01*
X578910Y278215D01*
X578925Y278180D01*
X578945Y278140D01*
X579045Y278000D01*
X579075Y277970D01*
Y275840D01*
X579085Y275715D01*
X579125Y275590D01*
X579185Y275480D01*
X579265Y275380D01*
X579365Y275300D01*
X579475Y275240D01*
X579600Y275200D01*
X579725Y275190D01*
X579850Y275200D01*
X579975Y275240D01*
X580085Y275300D01*
X580185Y275380D01*
X580265Y275480D01*
X580325Y275590D01*
X580365Y275715D01*
X580375Y275840D01*
Y277965D01*
X580405Y277995D01*
X580430Y278030D01*
X580460Y278065D01*
X580480Y278100D01*
X580505Y278135D01*
X580545Y278215D01*
X580590Y278335D01*
X580600Y278375D01*
X580610Y278420D01*
X580615Y278460D01*
X580625Y278505D01*
Y278675D01*
X580615Y278720D01*
X580610Y278760D01*
X580600Y278805D01*
X580590Y278845D01*
X580545Y278965D01*
X580505Y279045D01*
X580480Y279080D01*
X580460Y279115D01*
X580430Y279150D01*
X580405Y279185D01*
X580375Y279215D01*
Y281640D01*
X580365Y281765D01*
X580325Y281890D01*
X580265Y282000D01*
X580185Y282100D01*
X580085Y282180D01*
X579975Y282240D01*
X579850Y282280D01*
X579725Y282290D01*
G37*
G36*
G01X584449D02*
X584324Y282280D01*
X584199Y282240D01*
X584089Y282180D01*
X583989Y282100D01*
X583909Y282000D01*
X583849Y281890D01*
X583809Y281765D01*
X583799Y281640D01*
Y279210D01*
X583769Y279180D01*
X583669Y279040D01*
X583649Y279000D01*
X583634Y278965D01*
X583614Y278925D01*
X583599Y278885D01*
X583589Y278845D01*
X583574Y278800D01*
X583569Y278760D01*
X583559Y278720D01*
X583554Y278675D01*
Y278635D01*
X583549Y278590D01*
X583554Y278545D01*
Y278505D01*
X583559Y278460D01*
X583569Y278420D01*
X583574Y278380D01*
X583589Y278335D01*
X583599Y278295D01*
X583614Y278255D01*
X583634Y278215D01*
X583649Y278180D01*
X583669Y278140D01*
X583769Y278000D01*
X583799Y277970D01*
Y275840D01*
X583809Y275715D01*
X583849Y275590D01*
X583909Y275480D01*
X583989Y275380D01*
X584089Y275300D01*
X584199Y275240D01*
X584324Y275200D01*
X584449Y275190D01*
X584574Y275200D01*
X584699Y275240D01*
X584809Y275300D01*
X584909Y275380D01*
X584989Y275480D01*
X585049Y275590D01*
X585089Y275715D01*
X585099Y275840D01*
Y277965D01*
X585129Y277995D01*
X585154Y278030D01*
X585184Y278065D01*
X585204Y278100D01*
X585229Y278135D01*
X585269Y278215D01*
X585314Y278335D01*
X585324Y278375D01*
X585334Y278420D01*
X585339Y278460D01*
X585349Y278505D01*
Y278675D01*
X585339Y278720D01*
X585334Y278760D01*
X585324Y278805D01*
X585314Y278845D01*
X585269Y278965D01*
X585229Y279045D01*
X585204Y279080D01*
X585184Y279115D01*
X585154Y279150D01*
X585129Y279185D01*
X585099Y279215D01*
Y281640D01*
X585089Y281765D01*
X585049Y281890D01*
X584989Y282000D01*
X584909Y282100D01*
X584809Y282180D01*
X584699Y282240D01*
X584574Y282280D01*
X584449Y282290D01*
G37*
G36*
G01X589173D02*
X589048Y282280D01*
X588923Y282240D01*
X588813Y282180D01*
X588713Y282100D01*
X588633Y282000D01*
X588573Y281890D01*
X588533Y281765D01*
X588523Y281640D01*
Y279210D01*
X588493Y279180D01*
X588393Y279040D01*
X588373Y279000D01*
X588358Y278965D01*
X588338Y278925D01*
X588323Y278885D01*
X588313Y278845D01*
X588298Y278800D01*
X588293Y278760D01*
X588283Y278720D01*
X588278Y278675D01*
Y278635D01*
X588273Y278590D01*
X588278Y278545D01*
Y278505D01*
X588283Y278460D01*
X588293Y278420D01*
X588298Y278380D01*
X588313Y278335D01*
X588323Y278295D01*
X588338Y278255D01*
X588358Y278215D01*
X588373Y278180D01*
X588393Y278140D01*
X588493Y278000D01*
X588523Y277970D01*
Y275840D01*
X588533Y275715D01*
X588573Y275590D01*
X588633Y275480D01*
X588713Y275380D01*
X588813Y275300D01*
X588923Y275240D01*
X589048Y275200D01*
X589173Y275190D01*
X589298Y275200D01*
X589423Y275240D01*
X589533Y275300D01*
X589633Y275380D01*
X589713Y275480D01*
X589773Y275590D01*
X589813Y275715D01*
X589823Y275840D01*
Y277965D01*
X589853Y277995D01*
X589878Y278030D01*
X589908Y278065D01*
X589928Y278100D01*
X589953Y278135D01*
X589993Y278215D01*
X590038Y278335D01*
X590048Y278375D01*
X590058Y278420D01*
X590063Y278460D01*
X590073Y278505D01*
Y278675D01*
X590063Y278720D01*
X590058Y278760D01*
X590048Y278805D01*
X590038Y278845D01*
X589993Y278965D01*
X589953Y279045D01*
X589928Y279080D01*
X589908Y279115D01*
X589878Y279150D01*
X589853Y279185D01*
X589823Y279215D01*
Y281640D01*
X589813Y281765D01*
X589773Y281890D01*
X589713Y282000D01*
X589633Y282100D01*
X589533Y282180D01*
X589423Y282240D01*
X589298Y282280D01*
X589173Y282290D01*
G37*
G36*
G01X593898D02*
X593773Y282280D01*
X593648Y282240D01*
X593538Y282180D01*
X593438Y282100D01*
X593358Y282000D01*
X593298Y281890D01*
X593258Y281765D01*
X593248Y281640D01*
Y279210D01*
X593218Y279180D01*
X593118Y279040D01*
X593098Y279000D01*
X593083Y278965D01*
X593063Y278925D01*
X593048Y278885D01*
X593038Y278845D01*
X593023Y278800D01*
X593018Y278760D01*
X593008Y278720D01*
X593003Y278675D01*
Y278635D01*
X592998Y278590D01*
X593003Y278545D01*
Y278505D01*
X593008Y278460D01*
X593018Y278420D01*
X593023Y278380D01*
X593038Y278335D01*
X593048Y278295D01*
X593063Y278255D01*
X593083Y278215D01*
X593098Y278180D01*
X593118Y278140D01*
X593218Y278000D01*
X593248Y277970D01*
Y275840D01*
X593258Y275715D01*
X593298Y275590D01*
X593358Y275480D01*
X593438Y275380D01*
X593538Y275300D01*
X593648Y275240D01*
X593773Y275200D01*
X593898Y275190D01*
X594023Y275200D01*
X594148Y275240D01*
X594258Y275300D01*
X594358Y275380D01*
X594438Y275480D01*
X594498Y275590D01*
X594538Y275715D01*
X594548Y275840D01*
Y277965D01*
X594578Y277995D01*
X594603Y278030D01*
X594633Y278065D01*
X594653Y278100D01*
X594678Y278135D01*
X594718Y278215D01*
X594763Y278335D01*
X594773Y278375D01*
X594783Y278420D01*
X594788Y278460D01*
X594798Y278505D01*
Y278675D01*
X594788Y278720D01*
X594783Y278760D01*
X594773Y278805D01*
X594763Y278845D01*
X594718Y278965D01*
X594678Y279045D01*
X594653Y279080D01*
X594633Y279115D01*
X594603Y279150D01*
X594578Y279185D01*
X594548Y279215D01*
Y281640D01*
X594538Y281765D01*
X594498Y281890D01*
X594438Y282000D01*
X594358Y282100D01*
X594258Y282180D01*
X594148Y282240D01*
X594023Y282280D01*
X593898Y282290D01*
G37*
G36*
G01X598622D02*
X598497Y282280D01*
X598372Y282240D01*
X598262Y282180D01*
X598162Y282100D01*
X598082Y282000D01*
X598022Y281890D01*
X597982Y281765D01*
X597972Y281640D01*
Y279210D01*
X597942Y279180D01*
X597842Y279040D01*
X597822Y279000D01*
X597807Y278965D01*
X597787Y278925D01*
X597772Y278885D01*
X597762Y278845D01*
X597747Y278800D01*
X597742Y278760D01*
X597732Y278720D01*
X597727Y278675D01*
Y278635D01*
X597722Y278590D01*
X597727Y278545D01*
Y278505D01*
X597732Y278460D01*
X597742Y278420D01*
X597747Y278380D01*
X597762Y278335D01*
X597772Y278295D01*
X597787Y278255D01*
X597807Y278215D01*
X597822Y278180D01*
X597842Y278140D01*
X597942Y278000D01*
X597972Y277970D01*
Y275840D01*
X597982Y275715D01*
X598022Y275590D01*
X598082Y275480D01*
X598162Y275380D01*
X598262Y275300D01*
X598372Y275240D01*
X598497Y275200D01*
X598622Y275190D01*
X598747Y275200D01*
X598872Y275240D01*
X598982Y275300D01*
X599082Y275380D01*
X599162Y275480D01*
X599222Y275590D01*
X599262Y275715D01*
X599272Y275840D01*
Y277965D01*
X599302Y277995D01*
X599327Y278030D01*
X599357Y278065D01*
X599377Y278100D01*
X599402Y278135D01*
X599442Y278215D01*
X599487Y278335D01*
X599497Y278375D01*
X599507Y278420D01*
X599512Y278460D01*
X599522Y278505D01*
Y278675D01*
X599512Y278720D01*
X599507Y278760D01*
X599497Y278805D01*
X599487Y278845D01*
X599442Y278965D01*
X599402Y279045D01*
X599377Y279080D01*
X599357Y279115D01*
X599327Y279150D01*
X599302Y279185D01*
X599272Y279215D01*
Y281640D01*
X599262Y281765D01*
X599222Y281890D01*
X599162Y282000D01*
X599082Y282100D01*
X598982Y282180D01*
X598872Y282240D01*
X598747Y282280D01*
X598622Y282290D01*
G37*
G36*
G01X603347D02*
X603222Y282280D01*
X603097Y282240D01*
X602987Y282180D01*
X602887Y282100D01*
X602807Y282000D01*
X602747Y281890D01*
X602707Y281765D01*
X602697Y281640D01*
Y279210D01*
X602667Y279180D01*
X602567Y279040D01*
X602547Y279000D01*
X602532Y278965D01*
X602512Y278925D01*
X602497Y278885D01*
X602487Y278845D01*
X602472Y278800D01*
X602467Y278760D01*
X602457Y278720D01*
X602452Y278675D01*
Y278635D01*
X602447Y278590D01*
X602452Y278545D01*
Y278505D01*
X602457Y278460D01*
X602467Y278420D01*
X602472Y278380D01*
X602487Y278335D01*
X602497Y278295D01*
X602512Y278255D01*
X602532Y278215D01*
X602547Y278180D01*
X602567Y278140D01*
X602667Y278000D01*
X602697Y277970D01*
Y275840D01*
X602707Y275715D01*
X602747Y275590D01*
X602807Y275480D01*
X602887Y275380D01*
X602987Y275300D01*
X603097Y275240D01*
X603222Y275200D01*
X603347Y275190D01*
X603472Y275200D01*
X603597Y275240D01*
X603707Y275300D01*
X603807Y275380D01*
X603887Y275480D01*
X603947Y275590D01*
X603987Y275715D01*
X603997Y275840D01*
Y277965D01*
X604027Y277995D01*
X604052Y278030D01*
X604082Y278065D01*
X604102Y278100D01*
X604127Y278135D01*
X604167Y278215D01*
X604212Y278335D01*
X604222Y278375D01*
X604232Y278420D01*
X604237Y278460D01*
X604247Y278505D01*
Y278675D01*
X604237Y278720D01*
X604232Y278760D01*
X604222Y278805D01*
X604212Y278845D01*
X604167Y278965D01*
X604127Y279045D01*
X604102Y279080D01*
X604082Y279115D01*
X604052Y279150D01*
X604027Y279185D01*
X603997Y279215D01*
Y281640D01*
X603987Y281765D01*
X603947Y281890D01*
X603887Y282000D01*
X603807Y282100D01*
X603707Y282180D01*
X603597Y282240D01*
X603472Y282280D01*
X603347Y282290D01*
G37*
G36*
G01X608071D02*
X607946Y282280D01*
X607821Y282240D01*
X607711Y282180D01*
X607611Y282100D01*
X607531Y282000D01*
X607471Y281890D01*
X607431Y281765D01*
X607421Y281640D01*
Y279210D01*
X607391Y279180D01*
X607291Y279040D01*
X607271Y279000D01*
X607256Y278965D01*
X607236Y278925D01*
X607221Y278885D01*
X607211Y278845D01*
X607196Y278800D01*
X607191Y278760D01*
X607181Y278720D01*
X607176Y278675D01*
Y278635D01*
X607171Y278590D01*
X607176Y278545D01*
Y278505D01*
X607181Y278460D01*
X607191Y278420D01*
X607196Y278380D01*
X607211Y278335D01*
X607221Y278295D01*
X607236Y278255D01*
X607256Y278215D01*
X607271Y278180D01*
X607291Y278140D01*
X607391Y278000D01*
X607421Y277970D01*
Y275840D01*
X607431Y275715D01*
X607471Y275590D01*
X607531Y275480D01*
X607611Y275380D01*
X607711Y275300D01*
X607821Y275240D01*
X607946Y275200D01*
X608071Y275190D01*
X608196Y275200D01*
X608321Y275240D01*
X608431Y275300D01*
X608531Y275380D01*
X608611Y275480D01*
X608671Y275590D01*
X608711Y275715D01*
X608721Y275840D01*
Y277965D01*
X608751Y277995D01*
X608776Y278030D01*
X608806Y278065D01*
X608826Y278100D01*
X608851Y278135D01*
X608891Y278215D01*
X608936Y278335D01*
X608946Y278375D01*
X608956Y278420D01*
X608961Y278460D01*
X608971Y278505D01*
Y278675D01*
X608961Y278720D01*
X608956Y278760D01*
X608946Y278805D01*
X608936Y278845D01*
X608891Y278965D01*
X608851Y279045D01*
X608826Y279080D01*
X608806Y279115D01*
X608776Y279150D01*
X608751Y279185D01*
X608721Y279215D01*
Y281640D01*
X608711Y281765D01*
X608671Y281890D01*
X608611Y282000D01*
X608531Y282100D01*
X608431Y282180D01*
X608321Y282240D01*
X608196Y282280D01*
X608071Y282290D01*
G37*
G36*
G01X612796D02*
X612671Y282280D01*
X612546Y282240D01*
X612436Y282180D01*
X612336Y282100D01*
X612256Y282000D01*
X612196Y281890D01*
X612156Y281765D01*
X612146Y281640D01*
Y279210D01*
X612116Y279180D01*
X612016Y279040D01*
X611996Y279000D01*
X611981Y278965D01*
X611961Y278925D01*
X611946Y278885D01*
X611936Y278845D01*
X611921Y278800D01*
X611916Y278760D01*
X611906Y278720D01*
X611901Y278675D01*
Y278635D01*
X611896Y278590D01*
X611901Y278545D01*
Y278505D01*
X611906Y278460D01*
X611916Y278420D01*
X611921Y278380D01*
X611936Y278335D01*
X611946Y278295D01*
X611961Y278255D01*
X611981Y278215D01*
X611996Y278180D01*
X612016Y278140D01*
X612116Y278000D01*
X612146Y277970D01*
Y275840D01*
X612156Y275715D01*
X612196Y275590D01*
X612256Y275480D01*
X612336Y275380D01*
X612436Y275300D01*
X612546Y275240D01*
X612671Y275200D01*
X612796Y275190D01*
X612921Y275200D01*
X613046Y275240D01*
X613156Y275300D01*
X613256Y275380D01*
X613336Y275480D01*
X613396Y275590D01*
X613436Y275715D01*
X613446Y275840D01*
Y277965D01*
X613476Y277995D01*
X613501Y278030D01*
X613531Y278065D01*
X613551Y278100D01*
X613576Y278135D01*
X613616Y278215D01*
X613661Y278335D01*
X613671Y278375D01*
X613681Y278420D01*
X613686Y278460D01*
X613696Y278505D01*
Y278675D01*
X613686Y278720D01*
X613681Y278760D01*
X613671Y278805D01*
X613661Y278845D01*
X613616Y278965D01*
X613576Y279045D01*
X613551Y279080D01*
X613531Y279115D01*
X613501Y279150D01*
X613476Y279185D01*
X613446Y279215D01*
Y281640D01*
X613436Y281765D01*
X613396Y281890D01*
X613336Y282000D01*
X613256Y282100D01*
X613156Y282180D01*
X613046Y282240D01*
X612921Y282280D01*
X612796Y282290D01*
G37*
G36*
G01X617520D02*
X617395Y282280D01*
X617270Y282240D01*
X617160Y282180D01*
X617060Y282100D01*
X616980Y282000D01*
X616920Y281890D01*
X616880Y281765D01*
X616870Y281640D01*
Y279210D01*
X616840Y279180D01*
X616740Y279040D01*
X616720Y279000D01*
X616705Y278965D01*
X616685Y278925D01*
X616670Y278885D01*
X616660Y278845D01*
X616645Y278800D01*
X616640Y278760D01*
X616630Y278720D01*
X616625Y278675D01*
Y278635D01*
X616620Y278590D01*
X616625Y278545D01*
Y278505D01*
X616630Y278460D01*
X616640Y278420D01*
X616645Y278380D01*
X616660Y278335D01*
X616670Y278295D01*
X616685Y278255D01*
X616705Y278215D01*
X616720Y278180D01*
X616740Y278140D01*
X616840Y278000D01*
X616870Y277970D01*
Y275840D01*
X616880Y275715D01*
X616920Y275590D01*
X616980Y275480D01*
X617060Y275380D01*
X617160Y275300D01*
X617270Y275240D01*
X617395Y275200D01*
X617520Y275190D01*
X617645Y275200D01*
X617770Y275240D01*
X617880Y275300D01*
X617980Y275380D01*
X618060Y275480D01*
X618120Y275590D01*
X618160Y275715D01*
X618170Y275840D01*
Y277965D01*
X618200Y277995D01*
X618225Y278030D01*
X618255Y278065D01*
X618275Y278100D01*
X618300Y278135D01*
X618340Y278215D01*
X618385Y278335D01*
X618395Y278375D01*
X618405Y278420D01*
X618410Y278460D01*
X618420Y278505D01*
Y278675D01*
X618410Y278720D01*
X618405Y278760D01*
X618395Y278805D01*
X618385Y278845D01*
X618340Y278965D01*
X618300Y279045D01*
X618275Y279080D01*
X618255Y279115D01*
X618225Y279150D01*
X618200Y279185D01*
X618170Y279215D01*
Y281640D01*
X618160Y281765D01*
X618120Y281890D01*
X618060Y282000D01*
X617980Y282100D01*
X617880Y282180D01*
X617770Y282240D01*
X617645Y282280D01*
X617520Y282290D01*
G37*
G36*
G01X622244D02*
X622119Y282280D01*
X621994Y282240D01*
X621884Y282180D01*
X621784Y282100D01*
X621704Y282000D01*
X621644Y281890D01*
X621604Y281765D01*
X621594Y281640D01*
Y279210D01*
X621564Y279180D01*
X621464Y279040D01*
X621444Y279000D01*
X621429Y278965D01*
X621409Y278925D01*
X621394Y278885D01*
X621384Y278845D01*
X621369Y278800D01*
X621364Y278760D01*
X621354Y278720D01*
X621349Y278675D01*
Y278635D01*
X621344Y278590D01*
X621349Y278545D01*
Y278505D01*
X621354Y278460D01*
X621364Y278420D01*
X621369Y278380D01*
X621384Y278335D01*
X621394Y278295D01*
X621409Y278255D01*
X621429Y278215D01*
X621444Y278180D01*
X621464Y278140D01*
X621564Y278000D01*
X621594Y277970D01*
Y275840D01*
X621604Y275715D01*
X621644Y275590D01*
X621704Y275480D01*
X621784Y275380D01*
X621884Y275300D01*
X621994Y275240D01*
X622119Y275200D01*
X622244Y275190D01*
X622369Y275200D01*
X622494Y275240D01*
X622604Y275300D01*
X622704Y275380D01*
X622784Y275480D01*
X622844Y275590D01*
X622884Y275715D01*
X622894Y275840D01*
Y277965D01*
X622924Y277995D01*
X622949Y278030D01*
X622979Y278065D01*
X622999Y278100D01*
X623024Y278135D01*
X623064Y278215D01*
X623109Y278335D01*
X623119Y278375D01*
X623129Y278420D01*
X623134Y278460D01*
X623144Y278505D01*
Y278675D01*
X623134Y278720D01*
X623129Y278760D01*
X623119Y278805D01*
X623109Y278845D01*
X623064Y278965D01*
X623024Y279045D01*
X622999Y279080D01*
X622979Y279115D01*
X622949Y279150D01*
X622924Y279185D01*
X622894Y279215D01*
Y281640D01*
X622884Y281765D01*
X622844Y281890D01*
X622784Y282000D01*
X622704Y282100D01*
X622604Y282180D01*
X622494Y282240D01*
X622369Y282280D01*
X622244Y282290D01*
G37*
G36*
G01X626969D02*
X626844Y282280D01*
X626719Y282240D01*
X626609Y282180D01*
X626509Y282100D01*
X626429Y282000D01*
X626369Y281890D01*
X626329Y281765D01*
X626319Y281640D01*
Y279210D01*
X626289Y279180D01*
X626189Y279040D01*
X626169Y279000D01*
X626154Y278965D01*
X626134Y278925D01*
X626119Y278885D01*
X626109Y278845D01*
X626094Y278800D01*
X626089Y278760D01*
X626079Y278720D01*
X626074Y278675D01*
Y278635D01*
X626069Y278590D01*
X626074Y278545D01*
Y278505D01*
X626079Y278460D01*
X626089Y278420D01*
X626094Y278380D01*
X626109Y278335D01*
X626119Y278295D01*
X626134Y278255D01*
X626154Y278215D01*
X626169Y278180D01*
X626189Y278140D01*
X626289Y278000D01*
X626319Y277970D01*
Y275840D01*
X626329Y275715D01*
X626369Y275590D01*
X626429Y275480D01*
X626509Y275380D01*
X626609Y275300D01*
X626719Y275240D01*
X626844Y275200D01*
X626969Y275190D01*
X627094Y275200D01*
X627219Y275240D01*
X627329Y275300D01*
X627429Y275380D01*
X627509Y275480D01*
X627569Y275590D01*
X627609Y275715D01*
X627619Y275840D01*
Y277965D01*
X627649Y277995D01*
X627674Y278030D01*
X627704Y278065D01*
X627724Y278100D01*
X627749Y278135D01*
X627789Y278215D01*
X627834Y278335D01*
X627844Y278375D01*
X627854Y278420D01*
X627859Y278460D01*
X627869Y278505D01*
Y278675D01*
X627859Y278720D01*
X627854Y278760D01*
X627844Y278805D01*
X627834Y278845D01*
X627789Y278965D01*
X627749Y279045D01*
X627724Y279080D01*
X627704Y279115D01*
X627674Y279150D01*
X627649Y279185D01*
X627619Y279215D01*
Y281640D01*
X627609Y281765D01*
X627569Y281890D01*
X627509Y282000D01*
X627429Y282100D01*
X627329Y282180D01*
X627219Y282240D01*
X627094Y282280D01*
X626969Y282290D01*
G37*
G36*
G01X631693D02*
X631568Y282280D01*
X631443Y282240D01*
X631333Y282180D01*
X631233Y282100D01*
X631153Y282000D01*
X631093Y281890D01*
X631053Y281765D01*
X631043Y281640D01*
Y279210D01*
X631013Y279180D01*
X630913Y279040D01*
X630893Y279000D01*
X630878Y278965D01*
X630858Y278925D01*
X630843Y278885D01*
X630833Y278845D01*
X630818Y278800D01*
X630813Y278760D01*
X630803Y278720D01*
X630798Y278675D01*
Y278635D01*
X630793Y278590D01*
X630798Y278545D01*
Y278505D01*
X630803Y278460D01*
X630813Y278420D01*
X630818Y278380D01*
X630833Y278335D01*
X630843Y278295D01*
X630858Y278255D01*
X630878Y278215D01*
X630893Y278180D01*
X630913Y278140D01*
X631013Y278000D01*
X631043Y277970D01*
Y275840D01*
X631053Y275715D01*
X631093Y275590D01*
X631153Y275480D01*
X631233Y275380D01*
X631333Y275300D01*
X631443Y275240D01*
X631568Y275200D01*
X631693Y275190D01*
X631818Y275200D01*
X631943Y275240D01*
X632053Y275300D01*
X632153Y275380D01*
X632233Y275480D01*
X632293Y275590D01*
X632333Y275715D01*
X632343Y275840D01*
Y277965D01*
X632373Y277995D01*
X632398Y278030D01*
X632428Y278065D01*
X632448Y278100D01*
X632473Y278135D01*
X632513Y278215D01*
X632558Y278335D01*
X632568Y278375D01*
X632578Y278420D01*
X632583Y278460D01*
X632593Y278505D01*
Y278675D01*
X632583Y278720D01*
X632578Y278760D01*
X632568Y278805D01*
X632558Y278845D01*
X632513Y278965D01*
X632473Y279045D01*
X632448Y279080D01*
X632428Y279115D01*
X632398Y279150D01*
X632373Y279185D01*
X632343Y279215D01*
Y281640D01*
X632333Y281765D01*
X632293Y281890D01*
X632233Y282000D01*
X632153Y282100D01*
X632053Y282180D01*
X631943Y282240D01*
X631818Y282280D01*
X631693Y282290D01*
G37*
G36*
G01X636418D02*
X636293Y282280D01*
X636168Y282240D01*
X636058Y282180D01*
X635958Y282100D01*
X635878Y282000D01*
X635818Y281890D01*
X635778Y281765D01*
X635768Y281640D01*
Y279210D01*
X635738Y279180D01*
X635638Y279040D01*
X635618Y279000D01*
X635603Y278965D01*
X635583Y278925D01*
X635568Y278885D01*
X635558Y278845D01*
X635543Y278800D01*
X635538Y278760D01*
X635528Y278720D01*
X635523Y278675D01*
Y278635D01*
X635518Y278590D01*
X635523Y278545D01*
Y278505D01*
X635528Y278460D01*
X635538Y278420D01*
X635543Y278380D01*
X635558Y278335D01*
X635568Y278295D01*
X635583Y278255D01*
X635603Y278215D01*
X635618Y278180D01*
X635638Y278140D01*
X635738Y278000D01*
X635768Y277970D01*
Y275840D01*
X635778Y275715D01*
X635818Y275590D01*
X635878Y275480D01*
X635958Y275380D01*
X636058Y275300D01*
X636168Y275240D01*
X636293Y275200D01*
X636418Y275190D01*
X636543Y275200D01*
X636668Y275240D01*
X636778Y275300D01*
X636878Y275380D01*
X636958Y275480D01*
X637018Y275590D01*
X637058Y275715D01*
X637068Y275840D01*
Y277965D01*
X637098Y277995D01*
X637123Y278030D01*
X637153Y278065D01*
X637173Y278100D01*
X637198Y278135D01*
X637238Y278215D01*
X637283Y278335D01*
X637293Y278375D01*
X637303Y278420D01*
X637308Y278460D01*
X637318Y278505D01*
Y278675D01*
X637308Y278720D01*
X637303Y278760D01*
X637293Y278805D01*
X637283Y278845D01*
X637238Y278965D01*
X637198Y279045D01*
X637173Y279080D01*
X637153Y279115D01*
X637123Y279150D01*
X637098Y279185D01*
X637068Y279215D01*
Y281640D01*
X637058Y281765D01*
X637018Y281890D01*
X636958Y282000D01*
X636878Y282100D01*
X636778Y282180D01*
X636668Y282240D01*
X636543Y282280D01*
X636418Y282290D01*
G37*
G36*
G01X641142D02*
X641017Y282280D01*
X640892Y282240D01*
X640782Y282180D01*
X640682Y282100D01*
X640602Y282000D01*
X640542Y281890D01*
X640502Y281765D01*
X640492Y281640D01*
Y279210D01*
X640462Y279180D01*
X640362Y279040D01*
X640342Y279000D01*
X640327Y278965D01*
X640307Y278925D01*
X640292Y278885D01*
X640282Y278845D01*
X640267Y278800D01*
X640262Y278760D01*
X640252Y278720D01*
X640247Y278675D01*
Y278635D01*
X640242Y278590D01*
X640247Y278545D01*
Y278505D01*
X640252Y278460D01*
X640262Y278420D01*
X640267Y278380D01*
X640282Y278335D01*
X640292Y278295D01*
X640307Y278255D01*
X640327Y278215D01*
X640342Y278180D01*
X640362Y278140D01*
X640462Y278000D01*
X640492Y277970D01*
Y275840D01*
X640502Y275715D01*
X640542Y275590D01*
X640602Y275480D01*
X640682Y275380D01*
X640782Y275300D01*
X640892Y275240D01*
X641017Y275200D01*
X641142Y275190D01*
X641267Y275200D01*
X641392Y275240D01*
X641502Y275300D01*
X641602Y275380D01*
X641682Y275480D01*
X641742Y275590D01*
X641782Y275715D01*
X641792Y275840D01*
Y277965D01*
X641822Y277995D01*
X641847Y278030D01*
X641877Y278065D01*
X641897Y278100D01*
X641922Y278135D01*
X641962Y278215D01*
X642007Y278335D01*
X642017Y278375D01*
X642027Y278420D01*
X642032Y278460D01*
X642042Y278505D01*
Y278675D01*
X642032Y278720D01*
X642027Y278760D01*
X642017Y278805D01*
X642007Y278845D01*
X641962Y278965D01*
X641922Y279045D01*
X641897Y279080D01*
X641877Y279115D01*
X641847Y279150D01*
X641822Y279185D01*
X641792Y279215D01*
Y281640D01*
X641782Y281765D01*
X641742Y281890D01*
X641682Y282000D01*
X641602Y282100D01*
X641502Y282180D01*
X641392Y282240D01*
X641267Y282280D01*
X641142Y282290D01*
G37*
G36*
G01X645866D02*
X645741Y282280D01*
X645616Y282240D01*
X645506Y282180D01*
X645406Y282100D01*
X645326Y282000D01*
X645266Y281890D01*
X645226Y281765D01*
X645216Y281640D01*
Y279210D01*
X645186Y279180D01*
X645086Y279040D01*
X645066Y279000D01*
X645051Y278965D01*
X645031Y278925D01*
X645016Y278885D01*
X645006Y278845D01*
X644991Y278800D01*
X644986Y278760D01*
X644976Y278720D01*
X644971Y278675D01*
Y278635D01*
X644966Y278590D01*
X644971Y278545D01*
Y278505D01*
X644976Y278460D01*
X644986Y278420D01*
X644991Y278380D01*
X645006Y278335D01*
X645016Y278295D01*
X645031Y278255D01*
X645051Y278215D01*
X645066Y278180D01*
X645086Y278140D01*
X645186Y278000D01*
X645216Y277970D01*
Y275840D01*
X645226Y275715D01*
X645266Y275590D01*
X645326Y275480D01*
X645406Y275380D01*
X645506Y275300D01*
X645616Y275240D01*
X645741Y275200D01*
X645866Y275190D01*
X645991Y275200D01*
X646116Y275240D01*
X646226Y275300D01*
X646326Y275380D01*
X646406Y275480D01*
X646466Y275590D01*
X646506Y275715D01*
X646516Y275840D01*
Y277965D01*
X646546Y277995D01*
X646571Y278030D01*
X646601Y278065D01*
X646621Y278100D01*
X646646Y278135D01*
X646686Y278215D01*
X646731Y278335D01*
X646741Y278375D01*
X646751Y278420D01*
X646756Y278460D01*
X646766Y278505D01*
Y278675D01*
X646756Y278720D01*
X646751Y278760D01*
X646741Y278805D01*
X646731Y278845D01*
X646686Y278965D01*
X646646Y279045D01*
X646621Y279080D01*
X646601Y279115D01*
X646571Y279150D01*
X646546Y279185D01*
X646516Y279215D01*
Y281640D01*
X646506Y281765D01*
X646466Y281890D01*
X646406Y282000D01*
X646326Y282100D01*
X646226Y282180D01*
X646116Y282240D01*
X645991Y282280D01*
X645866Y282290D01*
G37*
G36*
G01X650591D02*
X650466Y282280D01*
X650341Y282240D01*
X650231Y282180D01*
X650131Y282100D01*
X650051Y282000D01*
X649991Y281890D01*
X649951Y281765D01*
X649941Y281640D01*
Y279210D01*
X649911Y279180D01*
X649811Y279040D01*
X649791Y279000D01*
X649776Y278965D01*
X649756Y278925D01*
X649741Y278885D01*
X649731Y278845D01*
X649716Y278800D01*
X649711Y278760D01*
X649701Y278720D01*
X649696Y278675D01*
Y278635D01*
X649691Y278590D01*
X649696Y278545D01*
Y278505D01*
X649701Y278460D01*
X649711Y278420D01*
X649716Y278380D01*
X649731Y278335D01*
X649741Y278295D01*
X649756Y278255D01*
X649776Y278215D01*
X649791Y278180D01*
X649811Y278140D01*
X649911Y278000D01*
X649941Y277970D01*
Y275840D01*
X649951Y275715D01*
X649991Y275590D01*
X650051Y275480D01*
X650131Y275380D01*
X650231Y275300D01*
X650341Y275240D01*
X650466Y275200D01*
X650591Y275190D01*
X650716Y275200D01*
X650841Y275240D01*
X650951Y275300D01*
X651051Y275380D01*
X651131Y275480D01*
X651191Y275590D01*
X651231Y275715D01*
X651241Y275840D01*
Y277965D01*
X651271Y277995D01*
X651296Y278030D01*
X651326Y278065D01*
X651346Y278100D01*
X651371Y278135D01*
X651411Y278215D01*
X651456Y278335D01*
X651466Y278375D01*
X651476Y278420D01*
X651481Y278460D01*
X651491Y278505D01*
Y278675D01*
X651481Y278720D01*
X651476Y278760D01*
X651466Y278805D01*
X651456Y278845D01*
X651411Y278965D01*
X651371Y279045D01*
X651346Y279080D01*
X651326Y279115D01*
X651296Y279150D01*
X651271Y279185D01*
X651241Y279215D01*
Y281640D01*
X651231Y281765D01*
X651191Y281890D01*
X651131Y282000D01*
X651051Y282100D01*
X650951Y282180D01*
X650841Y282240D01*
X650716Y282280D01*
X650591Y282290D01*
G37*
G36*
G01X664764D02*
X664639Y282280D01*
X664514Y282240D01*
X664404Y282180D01*
X664304Y282100D01*
X664224Y282000D01*
X664164Y281890D01*
X664124Y281765D01*
X664114Y281640D01*
Y279210D01*
X664084Y279180D01*
X663984Y279040D01*
X663964Y279000D01*
X663949Y278965D01*
X663929Y278925D01*
X663914Y278885D01*
X663904Y278845D01*
X663889Y278800D01*
X663884Y278760D01*
X663874Y278720D01*
X663869Y278675D01*
Y278635D01*
X663864Y278590D01*
X663869Y278545D01*
Y278505D01*
X663874Y278460D01*
X663884Y278420D01*
X663889Y278380D01*
X663904Y278335D01*
X663914Y278295D01*
X663929Y278255D01*
X663949Y278215D01*
X663964Y278180D01*
X663984Y278140D01*
X664084Y278000D01*
X664114Y277970D01*
Y275840D01*
X664124Y275715D01*
X664164Y275590D01*
X664224Y275480D01*
X664304Y275380D01*
X664404Y275300D01*
X664514Y275240D01*
X664639Y275200D01*
X664764Y275190D01*
X664889Y275200D01*
X665014Y275240D01*
X665124Y275300D01*
X665224Y275380D01*
X665304Y275480D01*
X665364Y275590D01*
X665404Y275715D01*
X665414Y275840D01*
Y277965D01*
X665444Y277995D01*
X665469Y278030D01*
X665499Y278065D01*
X665519Y278100D01*
X665544Y278135D01*
X665584Y278215D01*
X665629Y278335D01*
X665639Y278375D01*
X665649Y278420D01*
X665654Y278460D01*
X665664Y278505D01*
Y278675D01*
X665654Y278720D01*
X665649Y278760D01*
X665639Y278805D01*
X665629Y278845D01*
X665584Y278965D01*
X665544Y279045D01*
X665519Y279080D01*
X665499Y279115D01*
X665469Y279150D01*
X665444Y279185D01*
X665414Y279215D01*
Y281640D01*
X665404Y281765D01*
X665364Y281890D01*
X665304Y282000D01*
X665224Y282100D01*
X665124Y282180D01*
X665014Y282240D01*
X664889Y282280D01*
X664764Y282290D01*
G37*
G36*
G01X669488D02*
X669363Y282280D01*
X669238Y282240D01*
X669128Y282180D01*
X669028Y282100D01*
X668948Y282000D01*
X668888Y281890D01*
X668848Y281765D01*
X668838Y281640D01*
Y279210D01*
X668808Y279180D01*
X668708Y279040D01*
X668688Y279000D01*
X668673Y278965D01*
X668653Y278925D01*
X668638Y278885D01*
X668628Y278845D01*
X668613Y278800D01*
X668608Y278760D01*
X668598Y278720D01*
X668593Y278675D01*
Y278635D01*
X668588Y278590D01*
X668593Y278545D01*
Y278505D01*
X668598Y278460D01*
X668608Y278420D01*
X668613Y278380D01*
X668628Y278335D01*
X668638Y278295D01*
X668653Y278255D01*
X668673Y278215D01*
X668688Y278180D01*
X668708Y278140D01*
X668808Y278000D01*
X668838Y277970D01*
Y275840D01*
X668848Y275715D01*
X668888Y275590D01*
X668948Y275480D01*
X669028Y275380D01*
X669128Y275300D01*
X669238Y275240D01*
X669363Y275200D01*
X669488Y275190D01*
X669613Y275200D01*
X669738Y275240D01*
X669848Y275300D01*
X669948Y275380D01*
X670028Y275480D01*
X670088Y275590D01*
X670128Y275715D01*
X670138Y275840D01*
Y277965D01*
X670168Y277995D01*
X670193Y278030D01*
X670223Y278065D01*
X670243Y278100D01*
X670268Y278135D01*
X670308Y278215D01*
X670353Y278335D01*
X670363Y278375D01*
X670373Y278420D01*
X670378Y278460D01*
X670388Y278505D01*
Y278675D01*
X670378Y278720D01*
X670373Y278760D01*
X670363Y278805D01*
X670353Y278845D01*
X670308Y278965D01*
X670268Y279045D01*
X670243Y279080D01*
X670223Y279115D01*
X670193Y279150D01*
X670168Y279185D01*
X670138Y279215D01*
Y281640D01*
X670128Y281765D01*
X670088Y281890D01*
X670028Y282000D01*
X669948Y282100D01*
X669848Y282180D01*
X669738Y282240D01*
X669613Y282280D01*
X669488Y282290D01*
G37*
G36*
G01X674213D02*
X674088Y282280D01*
X673963Y282240D01*
X673853Y282180D01*
X673753Y282100D01*
X673673Y282000D01*
X673613Y281890D01*
X673573Y281765D01*
X673563Y281640D01*
Y279210D01*
X673533Y279180D01*
X673433Y279040D01*
X673413Y279000D01*
X673398Y278965D01*
X673378Y278925D01*
X673363Y278885D01*
X673353Y278845D01*
X673338Y278800D01*
X673333Y278760D01*
X673323Y278720D01*
X673318Y278675D01*
Y278635D01*
X673313Y278590D01*
X673318Y278545D01*
Y278505D01*
X673323Y278460D01*
X673333Y278420D01*
X673338Y278380D01*
X673353Y278335D01*
X673363Y278295D01*
X673378Y278255D01*
X673398Y278215D01*
X673413Y278180D01*
X673433Y278140D01*
X673533Y278000D01*
X673563Y277970D01*
Y275840D01*
X673573Y275715D01*
X673613Y275590D01*
X673673Y275480D01*
X673753Y275380D01*
X673853Y275300D01*
X673963Y275240D01*
X674088Y275200D01*
X674213Y275190D01*
X674338Y275200D01*
X674463Y275240D01*
X674573Y275300D01*
X674673Y275380D01*
X674753Y275480D01*
X674813Y275590D01*
X674853Y275715D01*
X674863Y275840D01*
Y277965D01*
X674893Y277995D01*
X674918Y278030D01*
X674948Y278065D01*
X674968Y278100D01*
X674993Y278135D01*
X675033Y278215D01*
X675078Y278335D01*
X675088Y278375D01*
X675098Y278420D01*
X675103Y278460D01*
X675113Y278505D01*
Y278675D01*
X675103Y278720D01*
X675098Y278760D01*
X675088Y278805D01*
X675078Y278845D01*
X675033Y278965D01*
X674993Y279045D01*
X674968Y279080D01*
X674948Y279115D01*
X674918Y279150D01*
X674893Y279185D01*
X674863Y279215D01*
Y281640D01*
X674853Y281765D01*
X674813Y281890D01*
X674753Y282000D01*
X674673Y282100D01*
X674573Y282180D01*
X674463Y282240D01*
X674338Y282280D01*
X674213Y282290D01*
G37*
G36*
G01X678937D02*
X678812Y282280D01*
X678687Y282240D01*
X678577Y282180D01*
X678477Y282100D01*
X678397Y282000D01*
X678337Y281890D01*
X678297Y281765D01*
X678287Y281640D01*
Y279210D01*
X678257Y279180D01*
X678157Y279040D01*
X678137Y279000D01*
X678122Y278965D01*
X678102Y278925D01*
X678087Y278885D01*
X678077Y278845D01*
X678062Y278800D01*
X678057Y278760D01*
X678047Y278720D01*
X678042Y278675D01*
Y278635D01*
X678037Y278590D01*
X678042Y278545D01*
Y278505D01*
X678047Y278460D01*
X678057Y278420D01*
X678062Y278380D01*
X678077Y278335D01*
X678087Y278295D01*
X678102Y278255D01*
X678122Y278215D01*
X678137Y278180D01*
X678157Y278140D01*
X678257Y278000D01*
X678287Y277970D01*
Y275840D01*
X678297Y275715D01*
X678337Y275590D01*
X678397Y275480D01*
X678477Y275380D01*
X678577Y275300D01*
X678687Y275240D01*
X678812Y275200D01*
X678937Y275190D01*
X679062Y275200D01*
X679187Y275240D01*
X679297Y275300D01*
X679397Y275380D01*
X679477Y275480D01*
X679537Y275590D01*
X679577Y275715D01*
X679587Y275840D01*
Y277965D01*
X679617Y277995D01*
X679642Y278030D01*
X679672Y278065D01*
X679692Y278100D01*
X679717Y278135D01*
X679757Y278215D01*
X679802Y278335D01*
X679812Y278375D01*
X679822Y278420D01*
X679827Y278460D01*
X679837Y278505D01*
Y278675D01*
X679827Y278720D01*
X679822Y278760D01*
X679812Y278805D01*
X679802Y278845D01*
X679757Y278965D01*
X679717Y279045D01*
X679692Y279080D01*
X679672Y279115D01*
X679642Y279150D01*
X679617Y279185D01*
X679587Y279215D01*
Y281640D01*
X679577Y281765D01*
X679537Y281890D01*
X679477Y282000D01*
X679397Y282100D01*
X679297Y282180D01*
X679187Y282240D01*
X679062Y282280D01*
X678937Y282290D01*
G37*
G36*
G01X683662D02*
X683537Y282280D01*
X683412Y282240D01*
X683302Y282180D01*
X683202Y282100D01*
X683122Y282000D01*
X683062Y281890D01*
X683022Y281765D01*
X683012Y281640D01*
Y279210D01*
X682982Y279180D01*
X682882Y279040D01*
X682862Y279000D01*
X682847Y278965D01*
X682827Y278925D01*
X682812Y278885D01*
X682802Y278845D01*
X682787Y278800D01*
X682782Y278760D01*
X682772Y278720D01*
X682767Y278675D01*
Y278635D01*
X682762Y278590D01*
X682767Y278545D01*
Y278505D01*
X682772Y278460D01*
X682782Y278420D01*
X682787Y278380D01*
X682802Y278335D01*
X682812Y278295D01*
X682827Y278255D01*
X682847Y278215D01*
X682862Y278180D01*
X682882Y278140D01*
X682982Y278000D01*
X683012Y277970D01*
Y275840D01*
X683022Y275715D01*
X683062Y275590D01*
X683122Y275480D01*
X683202Y275380D01*
X683302Y275300D01*
X683412Y275240D01*
X683537Y275200D01*
X683662Y275190D01*
X683787Y275200D01*
X683912Y275240D01*
X684022Y275300D01*
X684122Y275380D01*
X684202Y275480D01*
X684262Y275590D01*
X684302Y275715D01*
X684312Y275840D01*
Y277965D01*
X684342Y277995D01*
X684367Y278030D01*
X684397Y278065D01*
X684417Y278100D01*
X684442Y278135D01*
X684482Y278215D01*
X684527Y278335D01*
X684537Y278375D01*
X684547Y278420D01*
X684552Y278460D01*
X684562Y278505D01*
Y278675D01*
X684552Y278720D01*
X684547Y278760D01*
X684537Y278805D01*
X684527Y278845D01*
X684482Y278965D01*
X684442Y279045D01*
X684417Y279080D01*
X684397Y279115D01*
X684367Y279150D01*
X684342Y279185D01*
X684312Y279215D01*
Y281640D01*
X684302Y281765D01*
X684262Y281890D01*
X684202Y282000D01*
X684122Y282100D01*
X684022Y282180D01*
X683912Y282240D01*
X683787Y282280D01*
X683662Y282290D01*
G37*
G36*
G01X688386D02*
X688261Y282280D01*
X688136Y282240D01*
X688026Y282180D01*
X687926Y282100D01*
X687846Y282000D01*
X687786Y281890D01*
X687746Y281765D01*
X687736Y281640D01*
Y279210D01*
X687706Y279180D01*
X687606Y279040D01*
X687586Y279000D01*
X687571Y278965D01*
X687551Y278925D01*
X687536Y278885D01*
X687526Y278845D01*
X687511Y278800D01*
X687506Y278760D01*
X687496Y278720D01*
X687491Y278675D01*
Y278635D01*
X687486Y278590D01*
X687491Y278545D01*
Y278505D01*
X687496Y278460D01*
X687506Y278420D01*
X687511Y278380D01*
X687526Y278335D01*
X687536Y278295D01*
X687551Y278255D01*
X687571Y278215D01*
X687586Y278180D01*
X687606Y278140D01*
X687706Y278000D01*
X687736Y277970D01*
Y275840D01*
X687746Y275715D01*
X687786Y275590D01*
X687846Y275480D01*
X687926Y275380D01*
X688026Y275300D01*
X688136Y275240D01*
X688261Y275200D01*
X688386Y275190D01*
X688511Y275200D01*
X688636Y275240D01*
X688746Y275300D01*
X688846Y275380D01*
X688926Y275480D01*
X688986Y275590D01*
X689026Y275715D01*
X689036Y275840D01*
Y277965D01*
X689066Y277995D01*
X689091Y278030D01*
X689121Y278065D01*
X689141Y278100D01*
X689166Y278135D01*
X689206Y278215D01*
X689251Y278335D01*
X689261Y278375D01*
X689271Y278420D01*
X689276Y278460D01*
X689286Y278505D01*
Y278675D01*
X689276Y278720D01*
X689271Y278760D01*
X689261Y278805D01*
X689251Y278845D01*
X689206Y278965D01*
X689166Y279045D01*
X689141Y279080D01*
X689121Y279115D01*
X689091Y279150D01*
X689066Y279185D01*
X689036Y279215D01*
Y281640D01*
X689026Y281765D01*
X688986Y281890D01*
X688926Y282000D01*
X688846Y282100D01*
X688746Y282180D01*
X688636Y282240D01*
X688511Y282280D01*
X688386Y282290D01*
G37*
G36*
G01X693110D02*
X692985Y282280D01*
X692860Y282240D01*
X692750Y282180D01*
X692650Y282100D01*
X692570Y282000D01*
X692510Y281890D01*
X692470Y281765D01*
X692460Y281640D01*
Y279210D01*
X692430Y279180D01*
X692330Y279040D01*
X692310Y279000D01*
X692295Y278965D01*
X692275Y278925D01*
X692260Y278885D01*
X692250Y278845D01*
X692235Y278800D01*
X692230Y278760D01*
X692220Y278720D01*
X692215Y278675D01*
Y278635D01*
X692210Y278590D01*
X692215Y278545D01*
Y278505D01*
X692220Y278460D01*
X692230Y278420D01*
X692235Y278380D01*
X692250Y278335D01*
X692260Y278295D01*
X692275Y278255D01*
X692295Y278215D01*
X692310Y278180D01*
X692330Y278140D01*
X692430Y278000D01*
X692460Y277970D01*
Y275840D01*
X692470Y275715D01*
X692510Y275590D01*
X692570Y275480D01*
X692650Y275380D01*
X692750Y275300D01*
X692860Y275240D01*
X692985Y275200D01*
X693110Y275190D01*
X693235Y275200D01*
X693360Y275240D01*
X693470Y275300D01*
X693570Y275380D01*
X693650Y275480D01*
X693710Y275590D01*
X693750Y275715D01*
X693760Y275840D01*
Y277965D01*
X693790Y277995D01*
X693815Y278030D01*
X693845Y278065D01*
X693865Y278100D01*
X693890Y278135D01*
X693930Y278215D01*
X693975Y278335D01*
X693985Y278375D01*
X693995Y278420D01*
X694000Y278460D01*
X694010Y278505D01*
Y278675D01*
X694000Y278720D01*
X693995Y278760D01*
X693985Y278805D01*
X693975Y278845D01*
X693930Y278965D01*
X693890Y279045D01*
X693865Y279080D01*
X693845Y279115D01*
X693815Y279150D01*
X693790Y279185D01*
X693760Y279215D01*
Y281640D01*
X693750Y281765D01*
X693710Y281890D01*
X693650Y282000D01*
X693570Y282100D01*
X693470Y282180D01*
X693360Y282240D01*
X693235Y282280D01*
X693110Y282290D01*
G37*
G36*
G01X697835D02*
X697710Y282280D01*
X697585Y282240D01*
X697475Y282180D01*
X697375Y282100D01*
X697295Y282000D01*
X697235Y281890D01*
X697195Y281765D01*
X697185Y281640D01*
Y279210D01*
X697155Y279180D01*
X697055Y279040D01*
X697035Y279000D01*
X697020Y278965D01*
X697000Y278925D01*
X696985Y278885D01*
X696975Y278845D01*
X696960Y278800D01*
X696955Y278760D01*
X696945Y278720D01*
X696940Y278675D01*
Y278635D01*
X696935Y278590D01*
X696940Y278545D01*
Y278505D01*
X696945Y278460D01*
X696955Y278420D01*
X696960Y278380D01*
X696975Y278335D01*
X696985Y278295D01*
X697000Y278255D01*
X697020Y278215D01*
X697035Y278180D01*
X697055Y278140D01*
X697155Y278000D01*
X697185Y277970D01*
Y275840D01*
X697195Y275715D01*
X697235Y275590D01*
X697295Y275480D01*
X697375Y275380D01*
X697475Y275300D01*
X697585Y275240D01*
X697710Y275200D01*
X697835Y275190D01*
X697960Y275200D01*
X698085Y275240D01*
X698195Y275300D01*
X698295Y275380D01*
X698375Y275480D01*
X698435Y275590D01*
X698475Y275715D01*
X698485Y275840D01*
Y277965D01*
X698515Y277995D01*
X698540Y278030D01*
X698570Y278065D01*
X698590Y278100D01*
X698615Y278135D01*
X698655Y278215D01*
X698700Y278335D01*
X698710Y278375D01*
X698720Y278420D01*
X698725Y278460D01*
X698735Y278505D01*
Y278675D01*
X698725Y278720D01*
X698720Y278760D01*
X698710Y278805D01*
X698700Y278845D01*
X698655Y278965D01*
X698615Y279045D01*
X698590Y279080D01*
X698570Y279115D01*
X698540Y279150D01*
X698515Y279185D01*
X698485Y279215D01*
Y281640D01*
X698475Y281765D01*
X698435Y281890D01*
X698375Y282000D01*
X698295Y282100D01*
X698195Y282180D01*
X698085Y282240D01*
X697960Y282280D01*
X697835Y282290D01*
G37*
G36*
G01X702559D02*
X702434Y282280D01*
X702309Y282240D01*
X702199Y282180D01*
X702099Y282100D01*
X702019Y282000D01*
X701959Y281890D01*
X701919Y281765D01*
X701909Y281640D01*
Y279210D01*
X701879Y279180D01*
X701779Y279040D01*
X701759Y279000D01*
X701744Y278965D01*
X701724Y278925D01*
X701709Y278885D01*
X701699Y278845D01*
X701684Y278800D01*
X701679Y278760D01*
X701669Y278720D01*
X701664Y278675D01*
Y278635D01*
X701659Y278590D01*
X701664Y278545D01*
Y278505D01*
X701669Y278460D01*
X701679Y278420D01*
X701684Y278380D01*
X701699Y278335D01*
X701709Y278295D01*
X701724Y278255D01*
X701744Y278215D01*
X701759Y278180D01*
X701779Y278140D01*
X701879Y278000D01*
X701909Y277970D01*
Y275840D01*
X701919Y275715D01*
X701959Y275590D01*
X702019Y275480D01*
X702099Y275380D01*
X702199Y275300D01*
X702309Y275240D01*
X702434Y275200D01*
X702559Y275190D01*
X702684Y275200D01*
X702809Y275240D01*
X702919Y275300D01*
X703019Y275380D01*
X703099Y275480D01*
X703159Y275590D01*
X703199Y275715D01*
X703209Y275840D01*
Y277965D01*
X703239Y277995D01*
X703264Y278030D01*
X703294Y278065D01*
X703314Y278100D01*
X703339Y278135D01*
X703379Y278215D01*
X703424Y278335D01*
X703434Y278375D01*
X703444Y278420D01*
X703449Y278460D01*
X703459Y278505D01*
Y278675D01*
X703449Y278720D01*
X703444Y278760D01*
X703434Y278805D01*
X703424Y278845D01*
X703379Y278965D01*
X703339Y279045D01*
X703314Y279080D01*
X703294Y279115D01*
X703264Y279150D01*
X703239Y279185D01*
X703209Y279215D01*
Y281640D01*
X703199Y281765D01*
X703159Y281890D01*
X703099Y282000D01*
X703019Y282100D01*
X702919Y282180D01*
X702809Y282240D01*
X702684Y282280D01*
X702559Y282290D01*
G37*
G36*
G01X707284D02*
X707159Y282280D01*
X707034Y282240D01*
X706924Y282180D01*
X706824Y282100D01*
X706744Y282000D01*
X706684Y281890D01*
X706644Y281765D01*
X706634Y281640D01*
Y279210D01*
X706604Y279180D01*
X706504Y279040D01*
X706484Y279000D01*
X706469Y278965D01*
X706449Y278925D01*
X706434Y278885D01*
X706424Y278845D01*
X706409Y278800D01*
X706404Y278760D01*
X706394Y278720D01*
X706389Y278675D01*
Y278635D01*
X706384Y278590D01*
X706389Y278545D01*
Y278505D01*
X706394Y278460D01*
X706404Y278420D01*
X706409Y278380D01*
X706424Y278335D01*
X706434Y278295D01*
X706449Y278255D01*
X706469Y278215D01*
X706484Y278180D01*
X706504Y278140D01*
X706604Y278000D01*
X706634Y277970D01*
Y275840D01*
X706644Y275715D01*
X706684Y275590D01*
X706744Y275480D01*
X706824Y275380D01*
X706924Y275300D01*
X707034Y275240D01*
X707159Y275200D01*
X707284Y275190D01*
X707409Y275200D01*
X707534Y275240D01*
X707644Y275300D01*
X707744Y275380D01*
X707824Y275480D01*
X707884Y275590D01*
X707924Y275715D01*
X707934Y275840D01*
Y277965D01*
X707964Y277995D01*
X707989Y278030D01*
X708019Y278065D01*
X708039Y278100D01*
X708064Y278135D01*
X708104Y278215D01*
X708149Y278335D01*
X708159Y278375D01*
X708169Y278420D01*
X708174Y278460D01*
X708184Y278505D01*
Y278675D01*
X708174Y278720D01*
X708169Y278760D01*
X708159Y278805D01*
X708149Y278845D01*
X708104Y278965D01*
X708064Y279045D01*
X708039Y279080D01*
X708019Y279115D01*
X707989Y279150D01*
X707964Y279185D01*
X707934Y279215D01*
Y281640D01*
X707924Y281765D01*
X707884Y281890D01*
X707824Y282000D01*
X707744Y282100D01*
X707644Y282180D01*
X707534Y282240D01*
X707409Y282280D01*
X707284Y282290D01*
G37*
G36*
G01X712008D02*
X711883Y282280D01*
X711758Y282240D01*
X711648Y282180D01*
X711548Y282100D01*
X711468Y282000D01*
X711408Y281890D01*
X711368Y281765D01*
X711358Y281640D01*
Y279210D01*
X711328Y279180D01*
X711228Y279040D01*
X711208Y279000D01*
X711193Y278965D01*
X711173Y278925D01*
X711158Y278885D01*
X711148Y278845D01*
X711133Y278800D01*
X711128Y278760D01*
X711118Y278720D01*
X711113Y278675D01*
Y278635D01*
X711108Y278590D01*
X711113Y278545D01*
Y278505D01*
X711118Y278460D01*
X711128Y278420D01*
X711133Y278380D01*
X711148Y278335D01*
X711158Y278295D01*
X711173Y278255D01*
X711193Y278215D01*
X711208Y278180D01*
X711228Y278140D01*
X711328Y278000D01*
X711358Y277970D01*
Y275840D01*
X711368Y275715D01*
X711408Y275590D01*
X711468Y275480D01*
X711548Y275380D01*
X711648Y275300D01*
X711758Y275240D01*
X711883Y275200D01*
X712008Y275190D01*
X712133Y275200D01*
X712258Y275240D01*
X712368Y275300D01*
X712468Y275380D01*
X712548Y275480D01*
X712608Y275590D01*
X712648Y275715D01*
X712658Y275840D01*
Y277965D01*
X712688Y277995D01*
X712713Y278030D01*
X712743Y278065D01*
X712763Y278100D01*
X712788Y278135D01*
X712828Y278215D01*
X712873Y278335D01*
X712883Y278375D01*
X712893Y278420D01*
X712898Y278460D01*
X712908Y278505D01*
Y278675D01*
X712898Y278720D01*
X712893Y278760D01*
X712883Y278805D01*
X712873Y278845D01*
X712828Y278965D01*
X712788Y279045D01*
X712763Y279080D01*
X712743Y279115D01*
X712713Y279150D01*
X712688Y279185D01*
X712658Y279215D01*
Y281640D01*
X712648Y281765D01*
X712608Y281890D01*
X712548Y282000D01*
X712468Y282100D01*
X712368Y282180D01*
X712258Y282240D01*
X712133Y282280D01*
X712008Y282290D01*
G37*
G36*
G01X716733D02*
X716608Y282280D01*
X716483Y282240D01*
X716373Y282180D01*
X716273Y282100D01*
X716193Y282000D01*
X716133Y281890D01*
X716093Y281765D01*
X716083Y281640D01*
Y279210D01*
X716053Y279180D01*
X715953Y279040D01*
X715933Y279000D01*
X715918Y278965D01*
X715898Y278925D01*
X715883Y278885D01*
X715873Y278845D01*
X715858Y278800D01*
X715853Y278760D01*
X715843Y278720D01*
X715838Y278675D01*
Y278635D01*
X715833Y278590D01*
X715838Y278545D01*
Y278505D01*
X715843Y278460D01*
X715853Y278420D01*
X715858Y278380D01*
X715873Y278335D01*
X715883Y278295D01*
X715898Y278255D01*
X715918Y278215D01*
X715933Y278180D01*
X715953Y278140D01*
X716053Y278000D01*
X716083Y277970D01*
Y275840D01*
X716093Y275715D01*
X716133Y275590D01*
X716193Y275480D01*
X716273Y275380D01*
X716373Y275300D01*
X716483Y275240D01*
X716608Y275200D01*
X716733Y275190D01*
X716858Y275200D01*
X716983Y275240D01*
X717093Y275300D01*
X717193Y275380D01*
X717273Y275480D01*
X717333Y275590D01*
X717373Y275715D01*
X717383Y275840D01*
Y277965D01*
X717413Y277995D01*
X717438Y278030D01*
X717468Y278065D01*
X717488Y278100D01*
X717513Y278135D01*
X717553Y278215D01*
X717598Y278335D01*
X717608Y278375D01*
X717618Y278420D01*
X717623Y278460D01*
X717633Y278505D01*
Y278675D01*
X717623Y278720D01*
X717618Y278760D01*
X717608Y278805D01*
X717598Y278845D01*
X717553Y278965D01*
X717513Y279045D01*
X717488Y279080D01*
X717468Y279115D01*
X717438Y279150D01*
X717413Y279185D01*
X717383Y279215D01*
Y281640D01*
X717373Y281765D01*
X717333Y281890D01*
X717273Y282000D01*
X717193Y282100D01*
X717093Y282180D01*
X716983Y282240D01*
X716858Y282280D01*
X716733Y282290D01*
G37*
G36*
G01X721457D02*
X721332Y282280D01*
X721207Y282240D01*
X721097Y282180D01*
X720997Y282100D01*
X720917Y282000D01*
X720857Y281890D01*
X720817Y281765D01*
X720807Y281640D01*
Y279210D01*
X720777Y279180D01*
X720677Y279040D01*
X720657Y279000D01*
X720642Y278965D01*
X720622Y278925D01*
X720607Y278885D01*
X720597Y278845D01*
X720582Y278800D01*
X720577Y278760D01*
X720567Y278720D01*
X720562Y278675D01*
Y278635D01*
X720557Y278590D01*
X720562Y278545D01*
Y278505D01*
X720567Y278460D01*
X720577Y278420D01*
X720582Y278380D01*
X720597Y278335D01*
X720607Y278295D01*
X720622Y278255D01*
X720642Y278215D01*
X720657Y278180D01*
X720677Y278140D01*
X720777Y278000D01*
X720807Y277970D01*
Y275840D01*
X720817Y275715D01*
X720857Y275590D01*
X720917Y275480D01*
X720997Y275380D01*
X721097Y275300D01*
X721207Y275240D01*
X721332Y275200D01*
X721457Y275190D01*
X721582Y275200D01*
X721707Y275240D01*
X721817Y275300D01*
X721917Y275380D01*
X721997Y275480D01*
X722057Y275590D01*
X722097Y275715D01*
X722107Y275840D01*
Y277965D01*
X722137Y277995D01*
X722162Y278030D01*
X722192Y278065D01*
X722212Y278100D01*
X722237Y278135D01*
X722277Y278215D01*
X722322Y278335D01*
X722332Y278375D01*
X722342Y278420D01*
X722347Y278460D01*
X722357Y278505D01*
Y278675D01*
X722347Y278720D01*
X722342Y278760D01*
X722332Y278805D01*
X722322Y278845D01*
X722277Y278965D01*
X722237Y279045D01*
X722212Y279080D01*
X722192Y279115D01*
X722162Y279150D01*
X722137Y279185D01*
X722107Y279215D01*
Y281640D01*
X722097Y281765D01*
X722057Y281890D01*
X721997Y282000D01*
X721917Y282100D01*
X721817Y282180D01*
X721707Y282240D01*
X721582Y282280D01*
X721457Y282290D01*
G37*
G36*
G01X726181D02*
X726056Y282280D01*
X725931Y282240D01*
X725821Y282180D01*
X725721Y282100D01*
X725641Y282000D01*
X725581Y281890D01*
X725541Y281765D01*
X725531Y281640D01*
Y279210D01*
X725501Y279180D01*
X725401Y279040D01*
X725381Y279000D01*
X725366Y278965D01*
X725346Y278925D01*
X725331Y278885D01*
X725321Y278845D01*
X725306Y278800D01*
X725301Y278760D01*
X725291Y278720D01*
X725286Y278675D01*
Y278635D01*
X725281Y278590D01*
X725286Y278545D01*
Y278505D01*
X725291Y278460D01*
X725301Y278420D01*
X725306Y278380D01*
X725321Y278335D01*
X725331Y278295D01*
X725346Y278255D01*
X725366Y278215D01*
X725381Y278180D01*
X725401Y278140D01*
X725501Y278000D01*
X725531Y277970D01*
Y275840D01*
X725541Y275715D01*
X725581Y275590D01*
X725641Y275480D01*
X725721Y275380D01*
X725821Y275300D01*
X725931Y275240D01*
X726056Y275200D01*
X726181Y275190D01*
X726306Y275200D01*
X726431Y275240D01*
X726541Y275300D01*
X726641Y275380D01*
X726721Y275480D01*
X726781Y275590D01*
X726821Y275715D01*
X726831Y275840D01*
Y277965D01*
X726861Y277995D01*
X726886Y278030D01*
X726916Y278065D01*
X726936Y278100D01*
X726961Y278135D01*
X727001Y278215D01*
X727046Y278335D01*
X727056Y278375D01*
X727066Y278420D01*
X727071Y278460D01*
X727081Y278505D01*
Y278675D01*
X727071Y278720D01*
X727066Y278760D01*
X727056Y278805D01*
X727046Y278845D01*
X727001Y278965D01*
X726961Y279045D01*
X726936Y279080D01*
X726916Y279115D01*
X726886Y279150D01*
X726861Y279185D01*
X726831Y279215D01*
Y281640D01*
X726821Y281765D01*
X726781Y281890D01*
X726721Y282000D01*
X726641Y282100D01*
X726541Y282180D01*
X726431Y282240D01*
X726306Y282280D01*
X726181Y282290D01*
G37*
G36*
G01X730906D02*
X730781Y282280D01*
X730656Y282240D01*
X730546Y282180D01*
X730446Y282100D01*
X730366Y282000D01*
X730306Y281890D01*
X730266Y281765D01*
X730256Y281640D01*
Y279210D01*
X730226Y279180D01*
X730126Y279040D01*
X730106Y279000D01*
X730091Y278965D01*
X730071Y278925D01*
X730056Y278885D01*
X730046Y278845D01*
X730031Y278800D01*
X730026Y278760D01*
X730016Y278720D01*
X730011Y278675D01*
Y278635D01*
X730006Y278590D01*
X730011Y278545D01*
Y278505D01*
X730016Y278460D01*
X730026Y278420D01*
X730031Y278380D01*
X730046Y278335D01*
X730056Y278295D01*
X730071Y278255D01*
X730091Y278215D01*
X730106Y278180D01*
X730126Y278140D01*
X730226Y278000D01*
X730256Y277970D01*
Y275840D01*
X730266Y275715D01*
X730306Y275590D01*
X730366Y275480D01*
X730446Y275380D01*
X730546Y275300D01*
X730656Y275240D01*
X730781Y275200D01*
X730906Y275190D01*
X731031Y275200D01*
X731156Y275240D01*
X731266Y275300D01*
X731366Y275380D01*
X731446Y275480D01*
X731506Y275590D01*
X731546Y275715D01*
X731556Y275840D01*
Y277965D01*
X731586Y277995D01*
X731611Y278030D01*
X731641Y278065D01*
X731661Y278100D01*
X731686Y278135D01*
X731726Y278215D01*
X731771Y278335D01*
X731781Y278375D01*
X731791Y278420D01*
X731796Y278460D01*
X731806Y278505D01*
Y278675D01*
X731796Y278720D01*
X731791Y278760D01*
X731781Y278805D01*
X731771Y278845D01*
X731726Y278965D01*
X731686Y279045D01*
X731661Y279080D01*
X731641Y279115D01*
X731611Y279150D01*
X731586Y279185D01*
X731556Y279215D01*
Y281640D01*
X731546Y281765D01*
X731506Y281890D01*
X731446Y282000D01*
X731366Y282100D01*
X731266Y282180D01*
X731156Y282240D01*
X731031Y282280D01*
X730906Y282290D01*
G37*
G36*
G01X735630D02*
X735505Y282280D01*
X735380Y282240D01*
X735270Y282180D01*
X735170Y282100D01*
X735090Y282000D01*
X735030Y281890D01*
X734990Y281765D01*
X734980Y281640D01*
Y279210D01*
X734950Y279180D01*
X734850Y279040D01*
X734830Y279000D01*
X734815Y278965D01*
X734795Y278925D01*
X734780Y278885D01*
X734770Y278845D01*
X734755Y278800D01*
X734750Y278760D01*
X734740Y278720D01*
X734735Y278675D01*
Y278635D01*
X734730Y278590D01*
X734735Y278545D01*
Y278505D01*
X734740Y278460D01*
X734750Y278420D01*
X734755Y278380D01*
X734770Y278335D01*
X734780Y278295D01*
X734795Y278255D01*
X734815Y278215D01*
X734830Y278180D01*
X734850Y278140D01*
X734950Y278000D01*
X734980Y277970D01*
Y275840D01*
X734990Y275715D01*
X735030Y275590D01*
X735090Y275480D01*
X735170Y275380D01*
X735270Y275300D01*
X735380Y275240D01*
X735505Y275200D01*
X735630Y275190D01*
X735755Y275200D01*
X735880Y275240D01*
X735990Y275300D01*
X736090Y275380D01*
X736170Y275480D01*
X736230Y275590D01*
X736270Y275715D01*
X736280Y275840D01*
Y277965D01*
X736310Y277995D01*
X736335Y278030D01*
X736365Y278065D01*
X736385Y278100D01*
X736410Y278135D01*
X736450Y278215D01*
X736495Y278335D01*
X736505Y278375D01*
X736515Y278420D01*
X736520Y278460D01*
X736530Y278505D01*
Y278675D01*
X736520Y278720D01*
X736515Y278760D01*
X736505Y278805D01*
X736495Y278845D01*
X736450Y278965D01*
X736410Y279045D01*
X736385Y279080D01*
X736365Y279115D01*
X736335Y279150D01*
X736310Y279185D01*
X736280Y279215D01*
Y281640D01*
X736270Y281765D01*
X736230Y281890D01*
X736170Y282000D01*
X736090Y282100D01*
X735990Y282180D01*
X735880Y282240D01*
X735755Y282280D01*
X735630Y282290D01*
G37*
G36*
G01X740355D02*
X740230Y282280D01*
X740105Y282240D01*
X739995Y282180D01*
X739895Y282100D01*
X739815Y282000D01*
X739755Y281890D01*
X739715Y281765D01*
X739705Y281640D01*
Y279210D01*
X739675Y279180D01*
X739575Y279040D01*
X739555Y279000D01*
X739540Y278965D01*
X739520Y278925D01*
X739505Y278885D01*
X739495Y278845D01*
X739480Y278800D01*
X739475Y278760D01*
X739465Y278720D01*
X739460Y278675D01*
Y278635D01*
X739455Y278590D01*
X739460Y278545D01*
Y278505D01*
X739465Y278460D01*
X739475Y278420D01*
X739480Y278380D01*
X739495Y278335D01*
X739505Y278295D01*
X739520Y278255D01*
X739540Y278215D01*
X739555Y278180D01*
X739575Y278140D01*
X739675Y278000D01*
X739705Y277970D01*
Y275840D01*
X739715Y275715D01*
X739755Y275590D01*
X739815Y275480D01*
X739895Y275380D01*
X739995Y275300D01*
X740105Y275240D01*
X740230Y275200D01*
X740355Y275190D01*
X740480Y275200D01*
X740605Y275240D01*
X740715Y275300D01*
X740815Y275380D01*
X740895Y275480D01*
X740955Y275590D01*
X740995Y275715D01*
X741005Y275840D01*
Y277965D01*
X741035Y277995D01*
X741060Y278030D01*
X741090Y278065D01*
X741110Y278100D01*
X741135Y278135D01*
X741175Y278215D01*
X741220Y278335D01*
X741230Y278375D01*
X741240Y278420D01*
X741245Y278460D01*
X741255Y278505D01*
Y278675D01*
X741245Y278720D01*
X741240Y278760D01*
X741230Y278805D01*
X741220Y278845D01*
X741175Y278965D01*
X741135Y279045D01*
X741110Y279080D01*
X741090Y279115D01*
X741060Y279150D01*
X741035Y279185D01*
X741005Y279215D01*
Y281640D01*
X740995Y281765D01*
X740955Y281890D01*
X740895Y282000D01*
X740815Y282100D01*
X740715Y282180D01*
X740605Y282240D01*
X740480Y282280D01*
X740355Y282290D01*
G37*
G36*
G01X745079D02*
X744954Y282280D01*
X744829Y282240D01*
X744719Y282180D01*
X744619Y282100D01*
X744539Y282000D01*
X744479Y281890D01*
X744439Y281765D01*
X744429Y281640D01*
Y279210D01*
X744399Y279180D01*
X744299Y279040D01*
X744279Y279000D01*
X744264Y278965D01*
X744244Y278925D01*
X744229Y278885D01*
X744219Y278845D01*
X744204Y278800D01*
X744199Y278760D01*
X744189Y278720D01*
X744184Y278675D01*
Y278635D01*
X744179Y278590D01*
X744184Y278545D01*
Y278505D01*
X744189Y278460D01*
X744199Y278420D01*
X744204Y278380D01*
X744219Y278335D01*
X744229Y278295D01*
X744244Y278255D01*
X744264Y278215D01*
X744279Y278180D01*
X744299Y278140D01*
X744399Y278000D01*
X744429Y277970D01*
Y275840D01*
X744439Y275715D01*
X744479Y275590D01*
X744539Y275480D01*
X744619Y275380D01*
X744719Y275300D01*
X744829Y275240D01*
X744954Y275200D01*
X745079Y275190D01*
X745204Y275200D01*
X745329Y275240D01*
X745439Y275300D01*
X745539Y275380D01*
X745619Y275480D01*
X745679Y275590D01*
X745719Y275715D01*
X745729Y275840D01*
Y277965D01*
X745759Y277995D01*
X745784Y278030D01*
X745814Y278065D01*
X745834Y278100D01*
X745859Y278135D01*
X745899Y278215D01*
X745944Y278335D01*
X745954Y278375D01*
X745964Y278420D01*
X745969Y278460D01*
X745979Y278505D01*
Y278675D01*
X745969Y278720D01*
X745964Y278760D01*
X745954Y278805D01*
X745944Y278845D01*
X745899Y278965D01*
X745859Y279045D01*
X745834Y279080D01*
X745814Y279115D01*
X745784Y279150D01*
X745759Y279185D01*
X745729Y279215D01*
Y281640D01*
X745719Y281765D01*
X745679Y281890D01*
X745619Y282000D01*
X745539Y282100D01*
X745439Y282180D01*
X745329Y282240D01*
X745204Y282280D01*
X745079Y282290D01*
G37*
G54D93*
X804400Y212800D03*
X794600D03*
G54D48*
X196800Y62600D03*
X199600Y160100D03*
X239300Y196800D03*
X502500Y6200D03*
X538300Y15200D03*
X699000Y162255D03*
X756400Y110500D03*
X786500Y13500D03*
X784000Y31000D03*
X782000Y137000D03*
X790500Y11000D03*
X799000Y121500D03*
Y125500D03*
X800400Y158500D03*
X799900Y168800D03*
X811000Y130000D03*
Y134000D03*
X809000Y149200D03*
X811000Y138000D03*
X811200Y141600D03*
X809500Y156900D03*
X809600Y160500D03*
X809700Y164300D03*
G54D94*
G01X17301Y212401D02*
X21949D01*
G01X16400Y224212D02*
X21949D01*
G01Y218307D02*
X17300D01*
G01X21949Y236023D02*
X16300D01*
G01X21949Y241929D02*
X16899D01*
G01X21949Y247834D02*
X16899D01*
G01X21949Y253740D02*
X16899D01*
G01X21949Y259645D02*
X16899D01*
G01X21949Y265551D02*
X16899D01*
G01X25700Y131500D02*
Y135000D01*
G01D02*
X26300Y135600D01*
Y138500D01*
G01D02*
X29000Y141200D01*
X29700D01*
G01D02*
X35000Y135900D01*
Y129800D01*
X40500Y124300D01*
G01X35500Y87300D02*
X41312D01*
X44200Y90188D01*
Y98100D01*
X41500Y100800D01*
G01X35300Y99000D02*
X39700D01*
X41500Y100800D01*
G01X35200Y96000D02*
Y98900D01*
X35300Y99000D01*
G01X52500Y139500D02*
X60200D01*
X61000Y138700D01*
G01X63800Y239700D02*
Y222200D01*
X67000Y219000D01*
G01X75700Y97500D02*
X79000D01*
X80000Y96500D01*
G01X79000Y106400D02*
X78800Y106600D01*
Y110000D01*
G01D02*
Y111800D01*
X80500Y113500D01*
G01X93867Y57700D02*
Y58367D01*
X96200Y60700D01*
G01X90500Y101000D02*
Y96800D01*
X88200Y94500D01*
X82000D01*
X80000Y96500D01*
G01X88800Y110000D02*
Y111200D01*
X86500Y113500D01*
G01X125000Y178000D02*
X125800Y177200D01*
Y175000D01*
G01X124300Y205600D02*
X124878Y205022D01*
Y200662D01*
G01X124300Y205600D02*
X124000Y205900D01*
Y209300D01*
G01D02*
X124100Y209200D01*
X127000D01*
G01X124000Y212700D02*
Y213500D01*
X125700Y215200D01*
X135927D01*
X140700Y210427D01*
Y206000D01*
X142700Y204000D01*
Y201000D01*
G01X124000Y212700D02*
X121000D01*
G01X136469Y89902D02*
X139100Y87271D01*
Y83600D01*
X140500Y82200D01*
G01X126100Y121000D02*
X130000D01*
G01X125800Y175000D02*
X128800D01*
G01X140000Y195500D02*
X142700Y198200D01*
Y201000D01*
G01X140000Y195500D02*
X141000Y194500D01*
X143800D01*
G01X132700Y201000D02*
Y204069D01*
X131003Y205766D01*
G01X127000Y212800D02*
X130004D01*
X133941Y208863D01*
G01X153300Y57500D02*
Y55815D01*
X154615Y54500D01*
G01X143500Y82200D02*
Y85800D01*
G01X147300Y106000D02*
X148100Y106800D01*
X150700D01*
G01X154000Y118200D02*
X155500D01*
X156518Y119218D01*
X157229D01*
G01X161485Y101750D02*
Y104715D01*
X160100Y106100D01*
X158400D01*
X156100Y108400D01*
X153500D01*
X151900Y106800D01*
X150700D01*
G01X154000Y121800D02*
X151170D01*
X150670Y122300D01*
G01X154000Y121800D02*
X157900D01*
X161400Y118300D01*
Y113200D01*
G01X154200Y162000D02*
X158320D01*
X158500Y161820D01*
G01X150500Y183000D02*
Y180300D01*
G01X156100Y181900D02*
X157900Y183700D01*
X160100D01*
G01X153800Y168000D02*
X155806D01*
X157000Y169194D01*
G01X143800Y194500D02*
Y191400D01*
X142900Y190500D01*
G01X160100Y187300D02*
X156300D01*
X156100Y187100D01*
G01X163700Y57500D02*
X167300Y61100D01*
Y61300D01*
G01X169365Y73450D02*
Y70000D01*
X168700Y69335D01*
Y69200D01*
X167500Y68000D01*
G01X167300Y61300D02*
Y67800D01*
X167500Y68000D01*
G01X167395Y73450D02*
Y79000D01*
X168995Y80600D01*
X178600D01*
X180700Y78500D01*
G01X193485Y83724D02*
X187876D01*
X183375Y88225D01*
X166655D01*
X158105Y96775D01*
G01X159515Y101750D02*
Y98185D01*
X158105Y96775D01*
G01X157545Y101750D02*
Y97335D01*
X158105Y96775D01*
G01X171335Y101750D02*
Y104686D01*
X170200Y105821D01*
Y108333D01*
X170876Y109009D01*
Y112676D01*
X171400Y113200D01*
G01X169365Y98814D02*
Y101750D01*
G01Y98814D02*
X167951Y97400D01*
X162899D01*
X161485Y98814D01*
Y101750D01*
G01X173000Y97000D02*
X171179D01*
X169365Y98814D01*
G01X160000Y164700D02*
Y163320D01*
X158500Y161820D01*
G01X160000Y168300D02*
X157894D01*
X157000Y169194D01*
G01X161000Y202700D02*
Y202500D01*
X166000Y197500D01*
G01X165700Y203400D02*
X162800Y206300D01*
X161000D01*
G01X157000Y207100D02*
X157800Y206300D01*
X161000D01*
G01Y202700D02*
X157800D01*
X157000Y201900D01*
G01X175758Y52879D02*
Y57833D01*
X177300Y59375D01*
Y61300D01*
G01X182800Y57500D02*
X179000Y61300D01*
X177300D01*
G01X185125Y73450D02*
Y77675D01*
X184300Y78500D01*
G01X183155Y73450D02*
Y76545D01*
X181200Y78500D01*
X180700D01*
G01X185125Y101750D02*
Y95837D01*
X183344Y94056D01*
G01D02*
X181288Y92000D01*
X178000D01*
X173000Y97000D01*
G01X184600Y113200D02*
Y113400D01*
X187337Y116137D01*
X188363D01*
G01X181500Y170500D02*
X180700D01*
X178000Y167800D01*
G01X186300Y172400D02*
Y169900D01*
X185000Y168600D01*
G01X177500Y209500D02*
X178300Y210300D01*
Y213000D01*
G01D02*
X174700D01*
G01X198915Y73450D02*
Y70015D01*
X197600Y68700D01*
G01D02*
X196900D01*
G01X200885Y73450D02*
Y69415D01*
X201500Y68800D01*
G01D02*
X204500D01*
G01X193485Y83724D02*
X198424D01*
X198500Y83800D01*
G01X200885Y101750D02*
Y98615D01*
X202500Y97000D01*
G01X207400Y94500D02*
X205000D01*
X202500Y97000D01*
G01X204500Y68800D02*
X205200Y69500D01*
Y78742D01*
X209700Y83242D01*
Y93405D01*
X209800Y93505D01*
Y95756D01*
X208656Y96900D01*
X205995D01*
X202855Y100040D01*
Y101750D01*
G01X198100Y110200D02*
X200870Y107430D01*
X201930D01*
X201931Y107429D01*
X202122D01*
G01X202855Y101750D02*
Y106696D01*
X202122Y107429D01*
G01X195000Y169300D02*
Y169100D01*
X192600Y166700D01*
G01X203700Y195000D02*
X202900Y194200D01*
Y191500D01*
X202800Y191400D01*
G01X192000Y234000D02*
X195000D01*
G01X216085Y37649D02*
Y38265D01*
X226640Y48820D01*
G01X213558Y98500D02*
X214814Y97244D01*
X219502D01*
G01X211800Y206500D02*
X205000D01*
G01X237000Y60600D02*
X238000Y61600D01*
Y66000D01*
X237800Y66200D01*
Y66495D01*
X231148Y73148D01*
Y77648D01*
X233500Y80000D01*
X237430D01*
X240130Y77300D01*
G01X230200Y60000D02*
X231000D01*
X234150Y63150D01*
X235150D01*
X235400Y63400D01*
G01X222588Y75201D02*
X225699D01*
X235400Y65500D01*
Y63400D01*
G01X219502Y119291D02*
X224791D01*
X231611Y126111D01*
Y138336D01*
G01X226452Y147300D02*
X225900Y147852D01*
Y163594D01*
X222959Y166535D01*
X219502D01*
G01X264189Y98252D02*
Y98264D01*
X267025Y101100D01*
X270000D01*
G01X260500Y206000D02*
Y196753D01*
X256900Y193153D01*
Y173947D01*
X258777Y172070D01*
X260177Y170669D01*
Y162511D01*
X260000Y162334D01*
Y144102D01*
X263775Y140327D01*
G01X261200Y209700D02*
X260500Y209000D01*
Y206000D01*
G01X274047Y84205D02*
Y82318D01*
X275565Y80800D01*
X276070D01*
X277300Y79570D01*
Y77543D01*
X276016Y76259D01*
Y73795D01*
G01X276700Y92200D02*
X276500D01*
X273100Y88800D01*
Y87151D01*
X274047Y86204D01*
Y84205D01*
G01X278500Y104100D02*
X279700Y102900D01*
X280322D01*
X283722Y99500D01*
X288100D01*
G01X281800Y95000D02*
X279900Y96900D01*
X277700D01*
G01D02*
X276700Y95900D01*
Y92200D01*
G01X269440Y145320D02*
Y143040D01*
X268300Y141900D01*
Y141869D01*
G01X271500Y141400D02*
X269000D01*
X268531Y141869D01*
X268300D01*
G01X274560Y152680D02*
Y152160D01*
X272300Y149900D01*
G01X278100Y153200D02*
X275080D01*
X274560Y152680D01*
G01X274100Y163300D02*
X276100Y165300D01*
X284900D01*
X286600Y163600D01*
G01X268260Y168291D02*
Y169606D01*
X272813Y174159D01*
X273806D01*
X274550Y174903D01*
Y178547D01*
X272797Y180300D01*
X271000D01*
G01D02*
X270200D01*
X268900Y181600D01*
Y187402D01*
X269772Y188274D01*
G01X277400Y177800D02*
X278278Y176922D01*
Y173322D01*
X278300Y173300D01*
G01X277500Y212200D02*
X277300D01*
X274500Y215000D01*
G01X278450Y216800D02*
X276300D01*
X274500Y215000D01*
G01X275500Y241200D02*
X272500D01*
G01D02*
X269900D01*
X269500Y240800D01*
G01X285000Y261700D02*
X284994D01*
X283500Y260206D01*
Y251600D01*
X285375Y249725D01*
Y244024D01*
X280251Y238900D01*
X279800D01*
X278700Y237800D01*
G01X272500Y241200D02*
Y237400D01*
X274200Y235700D01*
X276600D01*
X278700Y237800D01*
G01X287250Y269250D02*
X277159D01*
X271400Y263491D01*
Y252483D01*
X272000Y251883D01*
Y248700D01*
X270800Y247500D01*
G01X292300Y97600D02*
X290400Y99500D01*
X288100D01*
G01X281500Y142100D02*
X285000Y145600D01*
Y149900D01*
X281700Y153200D01*
G01X281500Y142100D02*
X282000Y141600D01*
Y139800D01*
X283300Y138500D01*
G01X289800Y141500D02*
X289000Y140700D01*
X285500D01*
X283300Y138500D01*
G01X289700Y160500D02*
X289644D01*
X287400Y158256D01*
Y149900D01*
X289800Y147500D01*
G01D02*
Y144500D01*
G01X293700Y164000D02*
X296950D01*
X297250Y163700D01*
G01X293200Y154400D02*
X290200D01*
G01X293200D02*
X295700D01*
X295900Y154200D01*
G01X290200Y154400D02*
X290300Y154500D01*
Y157500D01*
G01X289700Y160500D02*
X290300D01*
G01X286600Y163600D02*
X289700Y160500D01*
G01X290300Y177500D02*
Y174000D01*
G01Y168000D02*
Y171000D01*
G01Y174000D02*
X288200D01*
X287354Y173154D01*
X287071D01*
G01X290300Y171000D02*
Y174000D01*
G01X293300Y196500D02*
Y193500D01*
G01X290100Y190900D02*
X287485D01*
X286500Y191885D01*
X286300D01*
G01X293300Y193500D02*
Y193300D01*
X291000Y191000D01*
X290200D01*
X290100Y190900D01*
G01X297000Y208600D02*
Y208700D01*
X293300Y212400D01*
G01X295300Y238100D02*
X297800Y235600D01*
X300677D01*
X302200Y237123D01*
Y239278D01*
X302000Y239478D01*
Y241800D01*
G01X281599Y261799D02*
X281100Y261300D01*
Y245400D01*
X282100Y244400D01*
G01X307200Y88300D02*
Y89500D01*
X306100Y90600D01*
G01X301629Y90500D02*
X303229Y92100D01*
X304000D01*
X306700Y94800D01*
X309000D01*
G01Y91400D02*
Y90100D01*
X310800Y88300D01*
G01X312000Y94800D02*
X309000D01*
G01X311000Y141731D02*
X309269D01*
X307700Y143300D01*
Y144200D01*
G01X304500Y144300D02*
X304600Y144200D01*
X307700D01*
G01X304500Y218700D02*
X311600Y211600D01*
Y207600D01*
G01X304500Y222300D02*
Y224800D01*
X304400Y224900D01*
G01X305000Y241800D02*
X302000D01*
G01X295500Y253500D02*
X297586Y255586D01*
X301474D01*
X301688Y255800D01*
X310344D01*
X315244Y260700D01*
X315500D01*
G01X298500Y245200D02*
Y246000D01*
X301100Y248600D01*
G01X302600Y253600D02*
Y250100D01*
X301100Y248600D01*
G01X310800Y88300D02*
Y86100D01*
X312100Y84800D01*
G01D02*
X314639Y82261D01*
Y76761D01*
G01X315950Y98650D02*
X316030D01*
X317463Y100083D01*
Y102737D01*
X316700Y103500D01*
G01X318300Y106500D02*
X316700Y104900D01*
Y103500D01*
G01X325100Y109900D02*
Y112100D01*
X325300Y112300D01*
G01X317700Y129200D02*
X319021D01*
X320321Y130500D01*
Y130528D01*
G01X319000Y260700D02*
X322500D01*
G01X315500D02*
X319000D01*
G01X330300Y254000D02*
Y262800D01*
X326100Y267000D01*
G01D02*
X324500Y265400D01*
Y262700D01*
X322500Y260700D01*
G01X333125Y74202D02*
X337000D01*
G01X340200Y71400D02*
X340800Y72000D01*
G01D02*
Y78500D01*
G01X340700Y81500D02*
Y78600D01*
X340800Y78500D01*
G01X326500Y250100D02*
Y250200D01*
X330300Y254000D01*
G01X353000Y149800D02*
X353290Y149510D01*
X355460D01*
G01D02*
X355870Y149100D01*
X359000D01*
G01X353000Y143800D02*
Y146200D01*
G01D02*
X355119D01*
X355447Y146528D01*
G01D02*
X356475Y145500D01*
X359000D01*
G01X347500Y139300D02*
X352000Y143800D01*
X353000D01*
G01Y156200D02*
X355263D01*
X355413Y156050D01*
G01X352800Y159400D02*
X353900Y158300D01*
X356000D01*
G01D02*
X357477D01*
X358477Y159300D01*
G01X344700Y181000D02*
Y179562D01*
X345562Y178700D01*
G01X352500Y173700D02*
Y172100D01*
X352200Y171800D01*
G01X356000Y179700D02*
X359000D01*
G01X365000Y149800D02*
X365100Y149700D01*
X368008D01*
X368026Y149718D01*
G01X367900Y152550D02*
X368026Y152424D01*
Y149718D01*
G01X365000Y146200D02*
X362049D01*
X361700Y146549D01*
G01Y151900D02*
X363874D01*
X364687Y152713D01*
X364700D01*
G01X361600Y159250D02*
X361300Y159550D01*
Y161900D01*
G01X359000Y167700D02*
X360500D01*
X361300Y168500D01*
X361500D01*
G01X359000Y177300D02*
X361300Y175000D01*
X361500D01*
G01X359000Y177300D02*
Y179700D01*
G01D02*
X360000D01*
X361200Y178500D01*
G01X371500Y190900D02*
Y195807D01*
X371299Y196008D01*
G01X414827Y238668D02*
X409259Y233100D01*
X380300D01*
X366460Y219260D01*
Y210870D01*
X369230Y208100D01*
G01D02*
X371500D01*
G01X376200Y77500D02*
Y78200D01*
X373800Y80600D01*
G01X383567Y137096D02*
Y133477D01*
X382293Y132203D01*
Y129335D01*
X381210Y128252D01*
X380352D01*
X379650Y127550D01*
Y119457D01*
X375950Y115757D01*
Y98650D01*
X373800Y96500D01*
Y80600D01*
G01X386708Y137118D02*
Y134008D01*
X383893Y131193D01*
Y128672D01*
X383500Y128279D01*
Y116733D01*
X382317Y115550D01*
X380750D01*
X379668Y114468D01*
Y110768D01*
X377600Y108700D01*
Y102483D01*
X381500Y98583D01*
Y81000D01*
X383700Y78800D01*
X391500D01*
X392000Y78300D01*
G01X389500Y150163D02*
X388977Y149640D01*
X386853D01*
G01X386777Y159005D02*
X387335Y159563D01*
X389500D01*
G01X373600Y175650D02*
Y171200D01*
X373700Y171100D01*
G01X378220Y173840D02*
X376830Y175230D01*
Y175640D01*
G01D02*
X376820Y175650D01*
X373600D01*
G01X380477Y171605D02*
Y174598D01*
X378650Y176425D01*
Y192100D01*
X379561Y193011D01*
Y197939D01*
G01X386600Y174900D02*
X387900Y176200D01*
Y178300D01*
G01X390000Y171800D02*
X389700D01*
X386600Y174900D01*
G01X376800Y178600D02*
Y181466D01*
X376742Y181524D01*
G01X376580Y184610D02*
Y181686D01*
X376742Y181524D01*
G01X378220Y170240D02*
X378760D01*
X380500Y168500D01*
G01X379561Y197939D02*
X376500Y201000D01*
Y202900D01*
G01X385500Y200400D02*
X386534Y199366D01*
Y189219D01*
X387400Y188353D01*
Y184700D01*
G01D02*
X387900Y184200D01*
Y178300D01*
G01X376390Y190950D02*
Y193090D01*
X376800Y193500D01*
G01X381500Y202900D02*
X383100D01*
X385500Y200500D01*
Y200400D01*
G01Y204000D02*
Y205138D01*
X384644Y205994D01*
G01X389500Y275300D02*
X387574Y273374D01*
Y270311D01*
G01X395500Y78300D02*
X400296D01*
G01X392000D02*
X395500D01*
G01X400296D02*
X401892Y76704D01*
X412604D01*
X414000Y78100D01*
G01X393042Y143124D02*
Y140310D01*
X393000Y140268D01*
G01X398300Y177500D02*
X397400D01*
X396000Y178900D01*
Y179000D01*
G01X417000Y258000D02*
X409300Y250300D01*
X395500D01*
X395000Y249800D01*
G01X387574Y256531D02*
X389169D01*
X391499Y254201D01*
Y253169D01*
G01X398000Y252700D02*
X395500D01*
X395000Y253200D01*
G01D02*
X394900Y253300D01*
X394769Y253169D01*
X391499D01*
G01X395000Y270800D02*
X394200D01*
X389700Y275300D01*
X389500D01*
G01X396000Y274092D02*
X398000Y272092D01*
Y270700D01*
G01X396000Y274092D02*
X395092Y275000D01*
X393000D01*
G01X410200Y55500D02*
Y59420D01*
X410180Y59440D01*
G01X406500Y68200D02*
Y63120D01*
X410180Y59440D01*
G01X414500Y64200D02*
X415700Y63000D01*
X415839D01*
X426850Y51989D01*
Y40226D01*
X422336Y35712D01*
Y21303D01*
X423631Y20008D01*
X428095D01*
X429588Y21500D01*
X430000D01*
G01X434000Y54200D02*
X432300D01*
X418300Y68200D01*
X406500D01*
G01X414827Y238668D02*
X420000Y243841D01*
Y244000D01*
G01X433700Y17500D02*
X433200Y17000D01*
X430500D01*
G01X433500Y20800D02*
X432799Y21500D01*
X430000D01*
G01X441500Y62500D02*
X434000Y55000D01*
Y54200D01*
G01X616100Y197400D02*
X615787D01*
X613687Y199500D01*
X468955D01*
X433129Y235326D01*
Y245783D01*
G01X444060Y32180D02*
Y29174D01*
X444783Y28451D01*
G01X438940Y24640D02*
Y24820D01*
G01X437300Y17500D02*
Y23000D01*
X438940Y24640D01*
G01X461520Y20060D02*
X459998D01*
X453713Y13775D01*
X441025D01*
X437300Y17500D01*
G01X495400Y183500D02*
Y154264D01*
X482750Y141614D01*
Y126600D01*
X449900Y93750D01*
Y70600D01*
X441800Y62500D01*
X441500D01*
G01X435700Y243250D02*
X435766Y243184D01*
Y236084D01*
X467500Y204350D01*
X505325D01*
X510675Y209700D01*
G01X463200Y24000D02*
X464500Y25300D01*
Y25339D01*
X469500Y30339D01*
Y85364D01*
X475934Y91798D01*
X503245D01*
X504750Y90293D01*
Y83818D01*
X511818Y76750D01*
X637532D01*
X646973Y86191D01*
Y98019D01*
X660854Y111900D01*
X670500D01*
G01X461520Y20060D02*
X468880D01*
G01X463200Y24000D02*
X461520Y22320D01*
Y20060D01*
G01X464240Y259791D02*
Y257060D01*
X466500Y254800D01*
X468500D01*
G01X464240Y259791D02*
X470539Y266090D01*
X472101D01*
G01X467200Y4400D02*
Y13260D01*
X468880Y14940D01*
G01D02*
X470076D01*
X471480Y16344D01*
Y21216D01*
X468696Y24000D01*
X466800D01*
G01X468500Y254800D02*
X472000D01*
G01X511700Y126000D02*
X499701D01*
X493000Y119299D01*
G01X504400Y183400D02*
Y153900D01*
X490800Y140300D01*
Y118387D01*
X492088Y117099D01*
X505599D01*
X508000Y119500D01*
G01X495400Y183500D02*
Y186180D01*
X506120Y196900D01*
X568900D01*
G01X507677Y38940D02*
Y33984D01*
X506500Y32807D01*
G01X508000Y119500D02*
X510430Y117070D01*
X529065D01*
X530700Y118705D01*
Y120312D01*
X550388Y140000D01*
X582100D01*
G01X538150Y183600D02*
X535950Y181400D01*
X533659D01*
X532450Y182609D01*
Y184357D01*
X530925Y185882D01*
X524118D01*
X521600Y188400D01*
X509400D01*
X504400Y183400D01*
G01X712700Y155978D02*
Y162200D01*
X694500Y180400D01*
Y185046D01*
X684546Y195000D01*
X660788D01*
X659738Y196050D01*
X623880D01*
X614505Y205425D01*
X601888D01*
X598513Y202050D01*
X518325D01*
X510675Y209700D01*
G01X505315Y246456D02*
Y243185D01*
X507250Y241250D01*
G01X504000Y253000D02*
X505315Y251685D01*
Y246456D01*
G01X499410Y278740D02*
Y276110D01*
X498700Y275400D01*
X497002D01*
G01X508859Y278740D02*
Y273181D01*
X509244Y272796D01*
G01X524212Y38940D02*
Y35695D01*
X526700Y33207D01*
G01X524200Y110500D02*
X613900D01*
X618375Y114975D01*
X651975D01*
X661500Y124500D01*
X703128D01*
X716000Y137372D01*
Y152678D01*
X712700Y155978D01*
G01X524200Y107500D02*
Y110500D01*
G01X524700Y119500D02*
Y122500D01*
G01X515300D02*
Y119570D01*
X515000Y119270D01*
G01X511500Y119500D02*
X511700Y119700D01*
Y122500D01*
G01X515300Y126000D02*
Y122500D01*
G01X524700D02*
Y125500D01*
G01X511700Y126000D02*
Y122500D01*
G01X524700Y145041D02*
Y148500D01*
G01D02*
Y151500D01*
G01X541757Y158048D02*
X521100Y178705D01*
Y184100D01*
X519200Y186000D01*
X516000D01*
X514800Y184800D01*
Y183400D01*
G01X538386Y38940D02*
Y34393D01*
X537200Y33207D01*
G01X531299Y38940D02*
Y35537D01*
X532542Y34294D01*
Y33307D01*
G01X542950Y89400D02*
X542559D01*
X540569Y91390D01*
X538579D01*
X536589Y89400D01*
X533501D01*
X533267Y89634D01*
G01X539574Y88990D02*
Y87426D01*
X543400Y83600D01*
X582187D01*
X587500Y88913D01*
G01X528100Y119500D02*
X528300Y119700D01*
Y122500D01*
G01Y125500D02*
Y122500D01*
G01X656642Y151430D02*
X609865D01*
X603995Y157300D01*
X549200D01*
X536634Y169866D01*
G01X656477Y148033D02*
X609867D01*
X603400Y154500D01*
X545305D01*
X541757Y158048D01*
G01X527200Y179000D02*
Y176000D01*
G01X526600Y183500D02*
X526800Y183300D01*
Y179400D01*
X527200Y179000D01*
G01X536634Y169866D02*
X530800Y175700D01*
Y176000D01*
G01D02*
Y179000D01*
G01D02*
X529900Y179900D01*
Y183167D01*
X530214Y183481D01*
G01X538150Y183600D02*
Y183550D01*
X541200Y180500D01*
Y179000D01*
G01D02*
Y178300D01*
X548400Y171100D01*
X582400D01*
X584702Y173402D01*
G01X539567Y278740D02*
Y273359D01*
X539937Y272989D01*
G01X530118Y278740D02*
Y275199D01*
X528330Y273411D01*
Y273140D01*
G01X537205Y278740D02*
Y275355D01*
X535060Y273210D01*
X535018D01*
X534905Y273097D01*
G01X546349Y89512D02*
X546300Y89561D01*
Y93000D01*
G01X542700D02*
X542950Y92750D01*
Y89400D01*
G01X546300Y93000D02*
Y96000D01*
G01X542700D02*
Y93000D01*
G01X544954Y183600D02*
X544800Y183446D01*
Y179000D01*
G01D02*
X547200D01*
G01X550800D02*
Y180400D01*
X548354Y182846D01*
Y183600D01*
G01X573500Y175300D02*
X571700Y173500D01*
X554000D01*
X550800Y176700D01*
Y179000D01*
G01X553740Y278740D02*
Y273956D01*
X554067Y273629D01*
Y273281D01*
X554434Y272914D01*
G01X546654Y278740D02*
Y273346D01*
X546900Y273100D01*
G01X570715Y89100D02*
X570300Y89515D01*
Y92500D01*
G01X566700D02*
Y89800D01*
X566000Y89100D01*
G01X570300Y92500D02*
X573300D01*
G01X557200Y179000D02*
X560200D01*
G01X558915Y183603D02*
X560200Y182318D01*
Y179000D01*
G01X566800Y176000D02*
Y179000D01*
G01Y176000D02*
X561600D01*
X560200Y177400D01*
Y179000D01*
G01X564398Y183481D02*
Y182276D01*
X563800Y181678D01*
Y179000D01*
G01X564398Y183481D02*
Y185000D01*
X563700Y185698D01*
Y187000D01*
G01D02*
X566900D01*
G01Y190000D02*
Y187000D01*
G01X568900Y196900D02*
X569100Y197100D01*
X612692D01*
X617892Y191900D01*
X649100D01*
X654394Y186606D01*
X685906D01*
X686700Y187400D01*
G01X560827Y278740D02*
Y275249D01*
X559600Y274022D01*
Y272900D01*
G01X638500Y94000D02*
Y96112D01*
X631912Y102700D01*
X601158D01*
X587500Y89042D01*
Y88913D01*
G01X595700Y142000D02*
X593700Y140000D01*
X582100D01*
G01X573500Y175300D02*
X576500D01*
G01X588475Y183300D02*
Y179975D01*
X587700Y179200D01*
Y179000D01*
G01X584702Y173402D02*
X587700Y176400D01*
Y179000D01*
G01X578544Y246456D02*
Y251944D01*
X578800Y252200D01*
G01X603346Y6656D02*
Y9957D01*
X600896Y12407D01*
G01X599803Y38940D02*
Y33844D01*
X600360Y33287D01*
G01X590898Y89045D02*
X599753Y97900D01*
X607900D01*
G01X599200Y145000D02*
X599300Y144900D01*
Y142000D01*
G01D02*
X601700D01*
G01X595744Y145041D02*
X595700Y144997D01*
Y142000D01*
G01X590975Y183275D02*
Y179325D01*
X591300Y179000D01*
G01X603347Y278740D02*
Y274078D01*
X602450Y273181D01*
Y272900D01*
G01X593898Y278740D02*
Y274502D01*
X595079Y273321D01*
Y273239D01*
X595386Y272932D01*
G01X612000Y17407D02*
X612750Y16657D01*
Y13267D01*
X612902Y13115D01*
Y11499D01*
X612795Y11392D01*
Y6656D01*
G01X605700Y12407D02*
Y12207D01*
X605708Y12199D01*
Y6656D01*
G01X615157D02*
Y10992D01*
X614600Y11549D01*
Y14007D01*
X614700Y14107D01*
G01X606890Y38940D02*
Y34167D01*
X607544Y33513D01*
Y33340D01*
G01X607900Y97900D02*
X628100D01*
X630700Y100500D01*
G01X605300Y142000D02*
X605410D01*
X608300Y144890D01*
G01X610433Y278740D02*
Y275181D01*
X611896Y273718D01*
Y273523D01*
X612393Y273026D01*
G01X634055Y6656D02*
Y11851D01*
X633500Y12406D01*
G01X624606Y6656D02*
Y11800D01*
X624000Y12406D01*
G01X619882Y278740D02*
Y273545D01*
X620437Y272990D01*
G01X629937D02*
X629331Y273596D01*
Y278740D01*
G01D02*
Y283800D01*
X630531Y285000D01*
X634800D01*
G01X643504Y6656D02*
Y10215D01*
X642041Y11678D01*
Y12071D01*
X641745Y12367D01*
G01X647047Y246456D02*
Y250600D01*
X647800Y251353D01*
Y252300D01*
G01X648291Y273140D02*
Y273429D01*
X648229Y273491D01*
Y278740D01*
G01X638780D02*
Y275420D01*
X639337Y274863D01*
Y268963D01*
X639500Y268800D01*
G01X641142Y278740D02*
Y274123D01*
X640937Y273918D01*
Y272103D01*
X641300Y271740D01*
Y270210D01*
X644110Y267400D01*
X644320D01*
X644550Y267170D01*
G01X648229Y278740D02*
Y283271D01*
X646500Y285000D01*
X644800D01*
G01X641200D02*
X638200D01*
G01X641200D02*
X641142Y284942D01*
Y278740D01*
G01X660039Y6656D02*
Y10362D01*
X657897Y12504D01*
G01X650590Y6656D02*
Y11318D01*
X650872Y11600D01*
Y11916D01*
X651316Y12360D01*
G01X654134Y246456D02*
Y251596D01*
X653600Y252130D01*
G01X650591Y278740D02*
Y275439D01*
X653041Y272989D01*
G01X670500Y111900D02*
X680200D01*
X682600Y114300D01*
G01X680118Y246456D02*
Y250718D01*
X681900Y252500D01*
G01X681299Y278740D02*
Y273999D01*
X680400Y273100D01*
G01X667126Y278740D02*
Y273764D01*
X668000Y272890D01*
G01X674213Y278740D02*
Y275287D01*
X675400Y274100D01*
Y273100D01*
G01X694000Y163900D02*
Y159500D01*
X694500Y159000D01*
G01X687205Y246456D02*
X687206Y246457D01*
Y250576D01*
X688720Y252090D01*
G01X694292Y246456D02*
Y251778D01*
X693860Y252210D01*
G01X695473Y278740D02*
Y273127D01*
X695500Y273100D01*
G01X688386Y278740D02*
Y273489D01*
X687786Y272889D01*
X687682D01*
G01X698000Y165800D02*
Y163255D01*
X699000Y162255D01*
G01X708465Y246456D02*
Y249859D01*
X707528Y250796D01*
Y252272D01*
X707490Y252310D01*
G01X697835Y278740D02*
Y275565D01*
X700300Y273100D01*
G01X733000Y185100D02*
Y188000D01*
X725500Y195500D01*
G01D02*
Y204700D01*
X731000Y210200D01*
G01X719095Y278740D02*
Y275400D01*
X721395Y273100D01*
G01X726181Y278740D02*
Y275174D01*
X727800Y273555D01*
Y272800D01*
G01X716733Y278740D02*
Y273093D01*
X716737Y273089D01*
Y272989D01*
G01X712008Y278740D02*
Y275287D01*
X713100Y274195D01*
Y273000D01*
G01X739300Y112300D02*
Y114700D01*
X739500Y114900D01*
G01X733000Y176200D02*
Y185100D01*
G01X739173Y246456D02*
Y252223D01*
X739750Y252800D01*
G01X736811Y246456D02*
Y251226D01*
X734937Y253100D01*
G01X733268Y278740D02*
Y275287D01*
X734400Y274155D01*
Y273220D01*
X734510Y273110D01*
G01X740355Y278740D02*
Y273936D01*
X739838Y273419D01*
Y272813D01*
G01X750100Y16100D02*
X749500Y16700D01*
Y34129D01*
X748622Y35007D01*
Y38940D01*
G01D02*
Y42385D01*
X744900Y46107D01*
Y46507D01*
G01X744700Y50007D02*
Y46707D01*
X744900Y46507D01*
G01X746260Y246456D02*
Y249960D01*
X748500Y252200D01*
X749000D01*
G01X747441Y278740D02*
Y273593D01*
X746737Y272889D01*
G01X753000Y272100D02*
X755290Y269810D01*
X770990D01*
X774800Y266000D01*
G01X771791Y279740D02*
X778101Y286050D01*
X809550D01*
G01X774800Y266000D02*
Y263000D01*
G01Y260000D02*
Y263000D01*
G01X793000Y174500D02*
X792123Y175377D01*
Y177595D01*
G01X809550Y286050D02*
X809700Y285900D01*
G54D76*
X482480Y70042D03*
X476575Y215354D03*
X777362Y70042D03*
X771457Y215354D03*
G54D49*
X198100Y110200D03*
X192900D03*
X198100Y120200D03*
X192900D03*
X276700Y92200D03*
X271500D03*
X290900Y86600D03*
X296100D03*
X364196Y203763D03*
X358996D03*
X387900Y178300D03*
X393100D03*
X426600Y78500D03*
X421400D03*
X472600Y238500D03*
X467400D03*
X472600Y233000D03*
X467400D03*
X780000Y244300D03*
X774800D03*
X780000Y254300D03*
X774800D03*
X780000Y249300D03*
X774800D03*
G54D67*
X372376Y246689D03*
Y270311D03*
X387624Y246689D03*
Y270311D03*
G36*
G01X501772Y282290D02*
X501647Y282280D01*
X501522Y282240D01*
X501412Y282180D01*
X501312Y282100D01*
X501232Y282000D01*
X501172Y281890D01*
X501132Y281765D01*
X501122Y281640D01*
Y278210D01*
X501092Y278180D01*
X500992Y278040D01*
X500972Y278000D01*
X500957Y277965D01*
X500937Y277925D01*
X500922Y277885D01*
X500912Y277845D01*
X500897Y277800D01*
X500892Y277760D01*
X500882Y277720D01*
X500877Y277675D01*
Y277635D01*
X500872Y277590D01*
X500877Y277545D01*
Y277505D01*
X500882Y277460D01*
X500892Y277420D01*
X500897Y277380D01*
X500912Y277335D01*
X500922Y277295D01*
X500937Y277255D01*
X500957Y277215D01*
X500972Y277180D01*
X500992Y277140D01*
X501092Y277000D01*
X501122Y276970D01*
Y275840D01*
X501132Y275715D01*
X501172Y275590D01*
X501232Y275480D01*
X501312Y275380D01*
X501412Y275300D01*
X501522Y275240D01*
X501647Y275200D01*
X501772Y275190D01*
X501897Y275200D01*
X502022Y275240D01*
X502132Y275300D01*
X502232Y275380D01*
X502312Y275480D01*
X502372Y275590D01*
X502412Y275715D01*
X502422Y275840D01*
Y276970D01*
X502452Y277000D01*
X502552Y277140D01*
X502572Y277180D01*
X502587Y277215D01*
X502607Y277255D01*
X502622Y277295D01*
X502632Y277335D01*
X502647Y277380D01*
X502652Y277420D01*
X502662Y277460D01*
X502667Y277505D01*
Y277545D01*
X502672Y277590D01*
X502667Y277635D01*
Y277675D01*
X502662Y277720D01*
X502652Y277760D01*
X502647Y277800D01*
X502632Y277845D01*
X502622Y277885D01*
X502607Y277925D01*
X502587Y277965D01*
X502572Y278000D01*
X502552Y278040D01*
X502452Y278180D01*
X502422Y278210D01*
Y281640D01*
X502412Y281765D01*
X502372Y281890D01*
X502312Y282000D01*
X502232Y282100D01*
X502132Y282180D01*
X502022Y282240D01*
X501897Y282280D01*
X501772Y282290D01*
G37*
G36*
G01X506496D02*
X506371Y282280D01*
X506246Y282240D01*
X506136Y282180D01*
X506036Y282100D01*
X505956Y282000D01*
X505896Y281890D01*
X505856Y281765D01*
X505846Y281640D01*
Y278210D01*
X505816Y278180D01*
X505716Y278040D01*
X505696Y278000D01*
X505681Y277965D01*
X505661Y277925D01*
X505646Y277885D01*
X505636Y277845D01*
X505621Y277800D01*
X505616Y277760D01*
X505606Y277720D01*
X505601Y277675D01*
Y277635D01*
X505596Y277590D01*
X505601Y277545D01*
Y277505D01*
X505606Y277460D01*
X505616Y277420D01*
X505621Y277380D01*
X505636Y277335D01*
X505646Y277295D01*
X505661Y277255D01*
X505681Y277215D01*
X505696Y277180D01*
X505716Y277140D01*
X505816Y277000D01*
X505846Y276970D01*
Y275840D01*
X505856Y275715D01*
X505896Y275590D01*
X505956Y275480D01*
X506036Y275380D01*
X506136Y275300D01*
X506246Y275240D01*
X506371Y275200D01*
X506496Y275190D01*
X506621Y275200D01*
X506746Y275240D01*
X506856Y275300D01*
X506956Y275380D01*
X507036Y275480D01*
X507096Y275590D01*
X507136Y275715D01*
X507146Y275840D01*
Y276970D01*
X507176Y277000D01*
X507276Y277140D01*
X507296Y277180D01*
X507311Y277215D01*
X507331Y277255D01*
X507346Y277295D01*
X507356Y277335D01*
X507371Y277380D01*
X507376Y277420D01*
X507386Y277460D01*
X507391Y277505D01*
Y277545D01*
X507396Y277590D01*
X507391Y277635D01*
Y277675D01*
X507386Y277720D01*
X507376Y277760D01*
X507371Y277800D01*
X507356Y277845D01*
X507346Y277885D01*
X507331Y277925D01*
X507311Y277965D01*
X507296Y278000D01*
X507276Y278040D01*
X507176Y278180D01*
X507146Y278210D01*
Y281640D01*
X507136Y281765D01*
X507096Y281890D01*
X507036Y282000D01*
X506956Y282100D01*
X506856Y282180D01*
X506746Y282240D01*
X506621Y282280D01*
X506496Y282290D01*
G37*
G36*
G01X511221D02*
X511096Y282280D01*
X510971Y282240D01*
X510861Y282180D01*
X510761Y282100D01*
X510681Y282000D01*
X510621Y281890D01*
X510581Y281765D01*
X510571Y281640D01*
Y278210D01*
X510541Y278180D01*
X510441Y278040D01*
X510421Y278000D01*
X510406Y277965D01*
X510386Y277925D01*
X510371Y277885D01*
X510361Y277845D01*
X510346Y277800D01*
X510341Y277760D01*
X510331Y277720D01*
X510326Y277675D01*
Y277635D01*
X510321Y277590D01*
X510326Y277545D01*
Y277505D01*
X510331Y277460D01*
X510341Y277420D01*
X510346Y277380D01*
X510361Y277335D01*
X510371Y277295D01*
X510386Y277255D01*
X510406Y277215D01*
X510421Y277180D01*
X510441Y277140D01*
X510541Y277000D01*
X510571Y276970D01*
Y275840D01*
X510581Y275715D01*
X510621Y275590D01*
X510681Y275480D01*
X510761Y275380D01*
X510861Y275300D01*
X510971Y275240D01*
X511096Y275200D01*
X511221Y275190D01*
X511346Y275200D01*
X511471Y275240D01*
X511581Y275300D01*
X511681Y275380D01*
X511761Y275480D01*
X511821Y275590D01*
X511861Y275715D01*
X511871Y275840D01*
Y276970D01*
X511901Y277000D01*
X512001Y277140D01*
X512021Y277180D01*
X512036Y277215D01*
X512056Y277255D01*
X512071Y277295D01*
X512081Y277335D01*
X512096Y277380D01*
X512101Y277420D01*
X512111Y277460D01*
X512116Y277505D01*
Y277545D01*
X512121Y277590D01*
X512116Y277635D01*
Y277675D01*
X512111Y277720D01*
X512101Y277760D01*
X512096Y277800D01*
X512081Y277845D01*
X512071Y277885D01*
X512056Y277925D01*
X512036Y277965D01*
X512021Y278000D01*
X512001Y278040D01*
X511901Y278180D01*
X511871Y278210D01*
Y281640D01*
X511861Y281765D01*
X511821Y281890D01*
X511761Y282000D01*
X511681Y282100D01*
X511581Y282180D01*
X511471Y282240D01*
X511346Y282280D01*
X511221Y282290D01*
G37*
G36*
G01X515945D02*
X515820Y282280D01*
X515695Y282240D01*
X515585Y282180D01*
X515485Y282100D01*
X515405Y282000D01*
X515345Y281890D01*
X515305Y281765D01*
X515295Y281640D01*
Y278210D01*
X515265Y278180D01*
X515165Y278040D01*
X515145Y278000D01*
X515130Y277965D01*
X515110Y277925D01*
X515095Y277885D01*
X515085Y277845D01*
X515070Y277800D01*
X515065Y277760D01*
X515055Y277720D01*
X515050Y277675D01*
Y277635D01*
X515045Y277590D01*
X515050Y277545D01*
Y277505D01*
X515055Y277460D01*
X515065Y277420D01*
X515070Y277380D01*
X515085Y277335D01*
X515095Y277295D01*
X515110Y277255D01*
X515130Y277215D01*
X515145Y277180D01*
X515165Y277140D01*
X515265Y277000D01*
X515295Y276970D01*
Y275840D01*
X515305Y275715D01*
X515345Y275590D01*
X515405Y275480D01*
X515485Y275380D01*
X515585Y275300D01*
X515695Y275240D01*
X515820Y275200D01*
X515945Y275190D01*
X516070Y275200D01*
X516195Y275240D01*
X516305Y275300D01*
X516405Y275380D01*
X516485Y275480D01*
X516545Y275590D01*
X516585Y275715D01*
X516595Y275840D01*
Y276970D01*
X516625Y277000D01*
X516725Y277140D01*
X516745Y277180D01*
X516760Y277215D01*
X516780Y277255D01*
X516795Y277295D01*
X516805Y277335D01*
X516820Y277380D01*
X516825Y277420D01*
X516835Y277460D01*
X516840Y277505D01*
Y277545D01*
X516845Y277590D01*
X516840Y277635D01*
Y277675D01*
X516835Y277720D01*
X516825Y277760D01*
X516820Y277800D01*
X516805Y277845D01*
X516795Y277885D01*
X516780Y277925D01*
X516760Y277965D01*
X516745Y278000D01*
X516725Y278040D01*
X516625Y278180D01*
X516595Y278210D01*
Y281640D01*
X516585Y281765D01*
X516545Y281890D01*
X516485Y282000D01*
X516405Y282100D01*
X516305Y282180D01*
X516195Y282240D01*
X516070Y282280D01*
X515945Y282290D01*
G37*
G36*
G01X520670D02*
X520545Y282280D01*
X520420Y282240D01*
X520310Y282180D01*
X520210Y282100D01*
X520130Y282000D01*
X520070Y281890D01*
X520030Y281765D01*
X520020Y281640D01*
Y278210D01*
X519990Y278180D01*
X519890Y278040D01*
X519870Y278000D01*
X519855Y277965D01*
X519835Y277925D01*
X519820Y277885D01*
X519810Y277845D01*
X519795Y277800D01*
X519790Y277760D01*
X519780Y277720D01*
X519775Y277675D01*
Y277635D01*
X519770Y277590D01*
X519775Y277545D01*
Y277505D01*
X519780Y277460D01*
X519790Y277420D01*
X519795Y277380D01*
X519810Y277335D01*
X519820Y277295D01*
X519835Y277255D01*
X519855Y277215D01*
X519870Y277180D01*
X519890Y277140D01*
X519990Y277000D01*
X520020Y276970D01*
Y275840D01*
X520030Y275715D01*
X520070Y275590D01*
X520130Y275480D01*
X520210Y275380D01*
X520310Y275300D01*
X520420Y275240D01*
X520545Y275200D01*
X520670Y275190D01*
X520795Y275200D01*
X520920Y275240D01*
X521030Y275300D01*
X521130Y275380D01*
X521210Y275480D01*
X521270Y275590D01*
X521310Y275715D01*
X521320Y275840D01*
Y276970D01*
X521350Y277000D01*
X521450Y277140D01*
X521470Y277180D01*
X521485Y277215D01*
X521505Y277255D01*
X521520Y277295D01*
X521530Y277335D01*
X521545Y277380D01*
X521550Y277420D01*
X521560Y277460D01*
X521565Y277505D01*
Y277545D01*
X521570Y277590D01*
X521565Y277635D01*
Y277675D01*
X521560Y277720D01*
X521550Y277760D01*
X521545Y277800D01*
X521530Y277845D01*
X521520Y277885D01*
X521505Y277925D01*
X521485Y277965D01*
X521470Y278000D01*
X521450Y278040D01*
X521350Y278180D01*
X521320Y278210D01*
Y281640D01*
X521310Y281765D01*
X521270Y281890D01*
X521210Y282000D01*
X521130Y282100D01*
X521030Y282180D01*
X520920Y282240D01*
X520795Y282280D01*
X520670Y282290D01*
G37*
G36*
G01X525394D02*
X525269Y282280D01*
X525144Y282240D01*
X525034Y282180D01*
X524934Y282100D01*
X524854Y282000D01*
X524794Y281890D01*
X524754Y281765D01*
X524744Y281640D01*
Y278210D01*
X524714Y278180D01*
X524614Y278040D01*
X524594Y278000D01*
X524579Y277965D01*
X524559Y277925D01*
X524544Y277885D01*
X524534Y277845D01*
X524519Y277800D01*
X524514Y277760D01*
X524504Y277720D01*
X524499Y277675D01*
Y277635D01*
X524494Y277590D01*
X524499Y277545D01*
Y277505D01*
X524504Y277460D01*
X524514Y277420D01*
X524519Y277380D01*
X524534Y277335D01*
X524544Y277295D01*
X524559Y277255D01*
X524579Y277215D01*
X524594Y277180D01*
X524614Y277140D01*
X524714Y277000D01*
X524744Y276970D01*
Y275840D01*
X524754Y275715D01*
X524794Y275590D01*
X524854Y275480D01*
X524934Y275380D01*
X525034Y275300D01*
X525144Y275240D01*
X525269Y275200D01*
X525394Y275190D01*
X525519Y275200D01*
X525644Y275240D01*
X525754Y275300D01*
X525854Y275380D01*
X525934Y275480D01*
X525994Y275590D01*
X526034Y275715D01*
X526044Y275840D01*
Y276970D01*
X526074Y277000D01*
X526174Y277140D01*
X526194Y277180D01*
X526209Y277215D01*
X526229Y277255D01*
X526244Y277295D01*
X526254Y277335D01*
X526269Y277380D01*
X526274Y277420D01*
X526284Y277460D01*
X526289Y277505D01*
Y277545D01*
X526294Y277590D01*
X526289Y277635D01*
Y277675D01*
X526284Y277720D01*
X526274Y277760D01*
X526269Y277800D01*
X526254Y277845D01*
X526244Y277885D01*
X526229Y277925D01*
X526209Y277965D01*
X526194Y278000D01*
X526174Y278040D01*
X526074Y278180D01*
X526044Y278210D01*
Y281640D01*
X526034Y281765D01*
X525994Y281890D01*
X525934Y282000D01*
X525854Y282100D01*
X525754Y282180D01*
X525644Y282240D01*
X525519Y282280D01*
X525394Y282290D01*
G37*
G36*
G01X530118D02*
X529993Y282280D01*
X529868Y282240D01*
X529758Y282180D01*
X529658Y282100D01*
X529578Y282000D01*
X529518Y281890D01*
X529478Y281765D01*
X529468Y281640D01*
Y278210D01*
X529438Y278180D01*
X529338Y278040D01*
X529318Y278000D01*
X529303Y277965D01*
X529283Y277925D01*
X529268Y277885D01*
X529258Y277845D01*
X529243Y277800D01*
X529238Y277760D01*
X529228Y277720D01*
X529223Y277675D01*
Y277635D01*
X529218Y277590D01*
X529223Y277545D01*
Y277505D01*
X529228Y277460D01*
X529238Y277420D01*
X529243Y277380D01*
X529258Y277335D01*
X529268Y277295D01*
X529283Y277255D01*
X529303Y277215D01*
X529318Y277180D01*
X529338Y277140D01*
X529438Y277000D01*
X529468Y276970D01*
Y275840D01*
X529478Y275715D01*
X529518Y275590D01*
X529578Y275480D01*
X529658Y275380D01*
X529758Y275300D01*
X529868Y275240D01*
X529993Y275200D01*
X530118Y275190D01*
X530243Y275200D01*
X530368Y275240D01*
X530478Y275300D01*
X530578Y275380D01*
X530658Y275480D01*
X530718Y275590D01*
X530758Y275715D01*
X530768Y275840D01*
Y276970D01*
X530798Y277000D01*
X530898Y277140D01*
X530918Y277180D01*
X530933Y277215D01*
X530953Y277255D01*
X530968Y277295D01*
X530978Y277335D01*
X530993Y277380D01*
X530998Y277420D01*
X531008Y277460D01*
X531013Y277505D01*
Y277545D01*
X531018Y277590D01*
X531013Y277635D01*
Y277675D01*
X531008Y277720D01*
X530998Y277760D01*
X530993Y277800D01*
X530978Y277845D01*
X530968Y277885D01*
X530953Y277925D01*
X530933Y277965D01*
X530918Y278000D01*
X530898Y278040D01*
X530798Y278180D01*
X530768Y278210D01*
Y281640D01*
X530758Y281765D01*
X530718Y281890D01*
X530658Y282000D01*
X530578Y282100D01*
X530478Y282180D01*
X530368Y282240D01*
X530243Y282280D01*
X530118Y282290D01*
G37*
G36*
G01X534843D02*
X534718Y282280D01*
X534593Y282240D01*
X534483Y282180D01*
X534383Y282100D01*
X534303Y282000D01*
X534243Y281890D01*
X534203Y281765D01*
X534193Y281640D01*
Y278210D01*
X534163Y278180D01*
X534063Y278040D01*
X534043Y278000D01*
X534028Y277965D01*
X534008Y277925D01*
X533993Y277885D01*
X533983Y277845D01*
X533968Y277800D01*
X533963Y277760D01*
X533953Y277720D01*
X533948Y277675D01*
Y277635D01*
X533943Y277590D01*
X533948Y277545D01*
Y277505D01*
X533953Y277460D01*
X533963Y277420D01*
X533968Y277380D01*
X533983Y277335D01*
X533993Y277295D01*
X534008Y277255D01*
X534028Y277215D01*
X534043Y277180D01*
X534063Y277140D01*
X534163Y277000D01*
X534193Y276970D01*
Y275840D01*
X534203Y275715D01*
X534243Y275590D01*
X534303Y275480D01*
X534383Y275380D01*
X534483Y275300D01*
X534593Y275240D01*
X534718Y275200D01*
X534843Y275190D01*
X534968Y275200D01*
X535093Y275240D01*
X535203Y275300D01*
X535303Y275380D01*
X535383Y275480D01*
X535443Y275590D01*
X535483Y275715D01*
X535493Y275840D01*
Y276970D01*
X535523Y277000D01*
X535623Y277140D01*
X535643Y277180D01*
X535658Y277215D01*
X535678Y277255D01*
X535693Y277295D01*
X535703Y277335D01*
X535718Y277380D01*
X535723Y277420D01*
X535733Y277460D01*
X535738Y277505D01*
Y277545D01*
X535743Y277590D01*
X535738Y277635D01*
Y277675D01*
X535733Y277720D01*
X535723Y277760D01*
X535718Y277800D01*
X535703Y277845D01*
X535693Y277885D01*
X535678Y277925D01*
X535658Y277965D01*
X535643Y278000D01*
X535623Y278040D01*
X535523Y278180D01*
X535493Y278210D01*
Y281640D01*
X535483Y281765D01*
X535443Y281890D01*
X535383Y282000D01*
X535303Y282100D01*
X535203Y282180D01*
X535093Y282240D01*
X534968Y282280D01*
X534843Y282290D01*
G37*
G36*
G01X539567D02*
X539442Y282280D01*
X539317Y282240D01*
X539207Y282180D01*
X539107Y282100D01*
X539027Y282000D01*
X538967Y281890D01*
X538927Y281765D01*
X538917Y281640D01*
Y278210D01*
X538887Y278180D01*
X538787Y278040D01*
X538767Y278000D01*
X538752Y277965D01*
X538732Y277925D01*
X538717Y277885D01*
X538707Y277845D01*
X538692Y277800D01*
X538687Y277760D01*
X538677Y277720D01*
X538672Y277675D01*
Y277635D01*
X538667Y277590D01*
X538672Y277545D01*
Y277505D01*
X538677Y277460D01*
X538687Y277420D01*
X538692Y277380D01*
X538707Y277335D01*
X538717Y277295D01*
X538732Y277255D01*
X538752Y277215D01*
X538767Y277180D01*
X538787Y277140D01*
X538887Y277000D01*
X538917Y276970D01*
Y275840D01*
X538927Y275715D01*
X538967Y275590D01*
X539027Y275480D01*
X539107Y275380D01*
X539207Y275300D01*
X539317Y275240D01*
X539442Y275200D01*
X539567Y275190D01*
X539692Y275200D01*
X539817Y275240D01*
X539927Y275300D01*
X540027Y275380D01*
X540107Y275480D01*
X540167Y275590D01*
X540207Y275715D01*
X540217Y275840D01*
Y276970D01*
X540247Y277000D01*
X540347Y277140D01*
X540367Y277180D01*
X540382Y277215D01*
X540402Y277255D01*
X540417Y277295D01*
X540427Y277335D01*
X540442Y277380D01*
X540447Y277420D01*
X540457Y277460D01*
X540462Y277505D01*
Y277545D01*
X540467Y277590D01*
X540462Y277635D01*
Y277675D01*
X540457Y277720D01*
X540447Y277760D01*
X540442Y277800D01*
X540427Y277845D01*
X540417Y277885D01*
X540402Y277925D01*
X540382Y277965D01*
X540367Y278000D01*
X540347Y278040D01*
X540247Y278180D01*
X540217Y278210D01*
Y281640D01*
X540207Y281765D01*
X540167Y281890D01*
X540107Y282000D01*
X540027Y282100D01*
X539927Y282180D01*
X539817Y282240D01*
X539692Y282280D01*
X539567Y282290D01*
G37*
G36*
G01X544292D02*
X544167Y282280D01*
X544042Y282240D01*
X543932Y282180D01*
X543832Y282100D01*
X543752Y282000D01*
X543692Y281890D01*
X543652Y281765D01*
X543642Y281640D01*
Y278210D01*
X543612Y278180D01*
X543512Y278040D01*
X543492Y278000D01*
X543477Y277965D01*
X543457Y277925D01*
X543442Y277885D01*
X543432Y277845D01*
X543417Y277800D01*
X543412Y277760D01*
X543402Y277720D01*
X543397Y277675D01*
Y277635D01*
X543392Y277590D01*
X543397Y277545D01*
Y277505D01*
X543402Y277460D01*
X543412Y277420D01*
X543417Y277380D01*
X543432Y277335D01*
X543442Y277295D01*
X543457Y277255D01*
X543477Y277215D01*
X543492Y277180D01*
X543512Y277140D01*
X543612Y277000D01*
X543642Y276970D01*
Y275840D01*
X543652Y275715D01*
X543692Y275590D01*
X543752Y275480D01*
X543832Y275380D01*
X543932Y275300D01*
X544042Y275240D01*
X544167Y275200D01*
X544292Y275190D01*
X544417Y275200D01*
X544542Y275240D01*
X544652Y275300D01*
X544752Y275380D01*
X544832Y275480D01*
X544892Y275590D01*
X544932Y275715D01*
X544942Y275840D01*
Y276970D01*
X544972Y277000D01*
X545072Y277140D01*
X545092Y277180D01*
X545107Y277215D01*
X545127Y277255D01*
X545142Y277295D01*
X545152Y277335D01*
X545167Y277380D01*
X545172Y277420D01*
X545182Y277460D01*
X545187Y277505D01*
Y277545D01*
X545192Y277590D01*
X545187Y277635D01*
Y277675D01*
X545182Y277720D01*
X545172Y277760D01*
X545167Y277800D01*
X545152Y277845D01*
X545142Y277885D01*
X545127Y277925D01*
X545107Y277965D01*
X545092Y278000D01*
X545072Y278040D01*
X544972Y278180D01*
X544942Y278210D01*
Y281640D01*
X544932Y281765D01*
X544892Y281890D01*
X544832Y282000D01*
X544752Y282100D01*
X544652Y282180D01*
X544542Y282240D01*
X544417Y282280D01*
X544292Y282290D01*
G37*
G36*
G01X549016D02*
X548891Y282280D01*
X548766Y282240D01*
X548656Y282180D01*
X548556Y282100D01*
X548476Y282000D01*
X548416Y281890D01*
X548376Y281765D01*
X548366Y281640D01*
Y278210D01*
X548336Y278180D01*
X548236Y278040D01*
X548216Y278000D01*
X548201Y277965D01*
X548181Y277925D01*
X548166Y277885D01*
X548156Y277845D01*
X548141Y277800D01*
X548136Y277760D01*
X548126Y277720D01*
X548121Y277675D01*
Y277635D01*
X548116Y277590D01*
X548121Y277545D01*
Y277505D01*
X548126Y277460D01*
X548136Y277420D01*
X548141Y277380D01*
X548156Y277335D01*
X548166Y277295D01*
X548181Y277255D01*
X548201Y277215D01*
X548216Y277180D01*
X548236Y277140D01*
X548336Y277000D01*
X548366Y276970D01*
Y275840D01*
X548376Y275715D01*
X548416Y275590D01*
X548476Y275480D01*
X548556Y275380D01*
X548656Y275300D01*
X548766Y275240D01*
X548891Y275200D01*
X549016Y275190D01*
X549141Y275200D01*
X549266Y275240D01*
X549376Y275300D01*
X549476Y275380D01*
X549556Y275480D01*
X549616Y275590D01*
X549656Y275715D01*
X549666Y275840D01*
Y276970D01*
X549696Y277000D01*
X549796Y277140D01*
X549816Y277180D01*
X549831Y277215D01*
X549851Y277255D01*
X549866Y277295D01*
X549876Y277335D01*
X549891Y277380D01*
X549896Y277420D01*
X549906Y277460D01*
X549911Y277505D01*
Y277545D01*
X549916Y277590D01*
X549911Y277635D01*
Y277675D01*
X549906Y277720D01*
X549896Y277760D01*
X549891Y277800D01*
X549876Y277845D01*
X549866Y277885D01*
X549851Y277925D01*
X549831Y277965D01*
X549816Y278000D01*
X549796Y278040D01*
X549696Y278180D01*
X549666Y278210D01*
Y281640D01*
X549656Y281765D01*
X549616Y281890D01*
X549556Y282000D01*
X549476Y282100D01*
X549376Y282180D01*
X549266Y282240D01*
X549141Y282280D01*
X549016Y282290D01*
G37*
G36*
G01X553740D02*
X553615Y282280D01*
X553490Y282240D01*
X553380Y282180D01*
X553280Y282100D01*
X553200Y282000D01*
X553140Y281890D01*
X553100Y281765D01*
X553090Y281640D01*
Y278210D01*
X553060Y278180D01*
X552960Y278040D01*
X552940Y278000D01*
X552925Y277965D01*
X552905Y277925D01*
X552890Y277885D01*
X552880Y277845D01*
X552865Y277800D01*
X552860Y277760D01*
X552850Y277720D01*
X552845Y277675D01*
Y277635D01*
X552840Y277590D01*
X552845Y277545D01*
Y277505D01*
X552850Y277460D01*
X552860Y277420D01*
X552865Y277380D01*
X552880Y277335D01*
X552890Y277295D01*
X552905Y277255D01*
X552925Y277215D01*
X552940Y277180D01*
X552960Y277140D01*
X553060Y277000D01*
X553090Y276970D01*
Y275840D01*
X553100Y275715D01*
X553140Y275590D01*
X553200Y275480D01*
X553280Y275380D01*
X553380Y275300D01*
X553490Y275240D01*
X553615Y275200D01*
X553740Y275190D01*
X553865Y275200D01*
X553990Y275240D01*
X554100Y275300D01*
X554200Y275380D01*
X554280Y275480D01*
X554340Y275590D01*
X554380Y275715D01*
X554390Y275840D01*
Y276970D01*
X554420Y277000D01*
X554520Y277140D01*
X554540Y277180D01*
X554555Y277215D01*
X554575Y277255D01*
X554590Y277295D01*
X554600Y277335D01*
X554615Y277380D01*
X554620Y277420D01*
X554630Y277460D01*
X554635Y277505D01*
Y277545D01*
X554640Y277590D01*
X554635Y277635D01*
Y277675D01*
X554630Y277720D01*
X554620Y277760D01*
X554615Y277800D01*
X554600Y277845D01*
X554590Y277885D01*
X554575Y277925D01*
X554555Y277965D01*
X554540Y278000D01*
X554520Y278040D01*
X554420Y278180D01*
X554390Y278210D01*
Y281640D01*
X554380Y281765D01*
X554340Y281890D01*
X554280Y282000D01*
X554200Y282100D01*
X554100Y282180D01*
X553990Y282240D01*
X553865Y282280D01*
X553740Y282290D01*
G37*
G36*
G01X558465D02*
X558340Y282280D01*
X558215Y282240D01*
X558105Y282180D01*
X558005Y282100D01*
X557925Y282000D01*
X557865Y281890D01*
X557825Y281765D01*
X557815Y281640D01*
Y278210D01*
X557785Y278180D01*
X557685Y278040D01*
X557665Y278000D01*
X557650Y277965D01*
X557630Y277925D01*
X557615Y277885D01*
X557605Y277845D01*
X557590Y277800D01*
X557585Y277760D01*
X557575Y277720D01*
X557570Y277675D01*
Y277635D01*
X557565Y277590D01*
X557570Y277545D01*
Y277505D01*
X557575Y277460D01*
X557585Y277420D01*
X557590Y277380D01*
X557605Y277335D01*
X557615Y277295D01*
X557630Y277255D01*
X557650Y277215D01*
X557665Y277180D01*
X557685Y277140D01*
X557785Y277000D01*
X557815Y276970D01*
Y275840D01*
X557825Y275715D01*
X557865Y275590D01*
X557925Y275480D01*
X558005Y275380D01*
X558105Y275300D01*
X558215Y275240D01*
X558340Y275200D01*
X558465Y275190D01*
X558590Y275200D01*
X558715Y275240D01*
X558825Y275300D01*
X558925Y275380D01*
X559005Y275480D01*
X559065Y275590D01*
X559105Y275715D01*
X559115Y275840D01*
Y276970D01*
X559145Y277000D01*
X559245Y277140D01*
X559265Y277180D01*
X559280Y277215D01*
X559300Y277255D01*
X559315Y277295D01*
X559325Y277335D01*
X559340Y277380D01*
X559345Y277420D01*
X559355Y277460D01*
X559360Y277505D01*
Y277545D01*
X559365Y277590D01*
X559360Y277635D01*
Y277675D01*
X559355Y277720D01*
X559345Y277760D01*
X559340Y277800D01*
X559325Y277845D01*
X559315Y277885D01*
X559300Y277925D01*
X559280Y277965D01*
X559265Y278000D01*
X559245Y278040D01*
X559145Y278180D01*
X559115Y278210D01*
Y281640D01*
X559105Y281765D01*
X559065Y281890D01*
X559005Y282000D01*
X558925Y282100D01*
X558825Y282180D01*
X558715Y282240D01*
X558590Y282280D01*
X558465Y282290D01*
G37*
G36*
G01X563189D02*
X563064Y282280D01*
X562939Y282240D01*
X562829Y282180D01*
X562729Y282100D01*
X562649Y282000D01*
X562589Y281890D01*
X562549Y281765D01*
X562539Y281640D01*
Y278210D01*
X562509Y278180D01*
X562409Y278040D01*
X562389Y278000D01*
X562374Y277965D01*
X562354Y277925D01*
X562339Y277885D01*
X562329Y277845D01*
X562314Y277800D01*
X562309Y277760D01*
X562299Y277720D01*
X562294Y277675D01*
Y277635D01*
X562289Y277590D01*
X562294Y277545D01*
Y277505D01*
X562299Y277460D01*
X562309Y277420D01*
X562314Y277380D01*
X562329Y277335D01*
X562339Y277295D01*
X562354Y277255D01*
X562374Y277215D01*
X562389Y277180D01*
X562409Y277140D01*
X562509Y277000D01*
X562539Y276970D01*
Y275840D01*
X562549Y275715D01*
X562589Y275590D01*
X562649Y275480D01*
X562729Y275380D01*
X562829Y275300D01*
X562939Y275240D01*
X563064Y275200D01*
X563189Y275190D01*
X563314Y275200D01*
X563439Y275240D01*
X563549Y275300D01*
X563649Y275380D01*
X563729Y275480D01*
X563789Y275590D01*
X563829Y275715D01*
X563839Y275840D01*
Y276970D01*
X563869Y277000D01*
X563969Y277140D01*
X563989Y277180D01*
X564004Y277215D01*
X564024Y277255D01*
X564039Y277295D01*
X564049Y277335D01*
X564064Y277380D01*
X564069Y277420D01*
X564079Y277460D01*
X564084Y277505D01*
Y277545D01*
X564089Y277590D01*
X564084Y277635D01*
Y277675D01*
X564079Y277720D01*
X564069Y277760D01*
X564064Y277800D01*
X564049Y277845D01*
X564039Y277885D01*
X564024Y277925D01*
X564004Y277965D01*
X563989Y278000D01*
X563969Y278040D01*
X563869Y278180D01*
X563839Y278210D01*
Y281640D01*
X563829Y281765D01*
X563789Y281890D01*
X563729Y282000D01*
X563649Y282100D01*
X563549Y282180D01*
X563439Y282240D01*
X563314Y282280D01*
X563189Y282290D01*
G37*
G36*
G01X567914D02*
X567789Y282280D01*
X567664Y282240D01*
X567554Y282180D01*
X567454Y282100D01*
X567374Y282000D01*
X567314Y281890D01*
X567274Y281765D01*
X567264Y281640D01*
Y278210D01*
X567234Y278180D01*
X567134Y278040D01*
X567114Y278000D01*
X567099Y277965D01*
X567079Y277925D01*
X567064Y277885D01*
X567054Y277845D01*
X567039Y277800D01*
X567034Y277760D01*
X567024Y277720D01*
X567019Y277675D01*
Y277635D01*
X567014Y277590D01*
X567019Y277545D01*
Y277505D01*
X567024Y277460D01*
X567034Y277420D01*
X567039Y277380D01*
X567054Y277335D01*
X567064Y277295D01*
X567079Y277255D01*
X567099Y277215D01*
X567114Y277180D01*
X567134Y277140D01*
X567234Y277000D01*
X567264Y276970D01*
Y275840D01*
X567274Y275715D01*
X567314Y275590D01*
X567374Y275480D01*
X567454Y275380D01*
X567554Y275300D01*
X567664Y275240D01*
X567789Y275200D01*
X567914Y275190D01*
X568039Y275200D01*
X568164Y275240D01*
X568274Y275300D01*
X568374Y275380D01*
X568454Y275480D01*
X568514Y275590D01*
X568554Y275715D01*
X568564Y275840D01*
Y276970D01*
X568594Y277000D01*
X568694Y277140D01*
X568714Y277180D01*
X568729Y277215D01*
X568749Y277255D01*
X568764Y277295D01*
X568774Y277335D01*
X568789Y277380D01*
X568794Y277420D01*
X568804Y277460D01*
X568809Y277505D01*
Y277545D01*
X568814Y277590D01*
X568809Y277635D01*
Y277675D01*
X568804Y277720D01*
X568794Y277760D01*
X568789Y277800D01*
X568774Y277845D01*
X568764Y277885D01*
X568749Y277925D01*
X568729Y277965D01*
X568714Y278000D01*
X568694Y278040D01*
X568594Y278180D01*
X568564Y278210D01*
Y281640D01*
X568554Y281765D01*
X568514Y281890D01*
X568454Y282000D01*
X568374Y282100D01*
X568274Y282180D01*
X568164Y282240D01*
X568039Y282280D01*
X567914Y282290D01*
G37*
G36*
G01X572638D02*
X572513Y282280D01*
X572388Y282240D01*
X572278Y282180D01*
X572178Y282100D01*
X572098Y282000D01*
X572038Y281890D01*
X571998Y281765D01*
X571988Y281640D01*
Y278210D01*
X571958Y278180D01*
X571858Y278040D01*
X571838Y278000D01*
X571823Y277965D01*
X571803Y277925D01*
X571788Y277885D01*
X571778Y277845D01*
X571763Y277800D01*
X571758Y277760D01*
X571748Y277720D01*
X571743Y277675D01*
Y277635D01*
X571738Y277590D01*
X571743Y277545D01*
Y277505D01*
X571748Y277460D01*
X571758Y277420D01*
X571763Y277380D01*
X571778Y277335D01*
X571788Y277295D01*
X571803Y277255D01*
X571823Y277215D01*
X571838Y277180D01*
X571858Y277140D01*
X571958Y277000D01*
X571988Y276970D01*
Y275840D01*
X571998Y275715D01*
X572038Y275590D01*
X572098Y275480D01*
X572178Y275380D01*
X572278Y275300D01*
X572388Y275240D01*
X572513Y275200D01*
X572638Y275190D01*
X572763Y275200D01*
X572888Y275240D01*
X572998Y275300D01*
X573098Y275380D01*
X573178Y275480D01*
X573238Y275590D01*
X573278Y275715D01*
X573288Y275840D01*
Y276970D01*
X573318Y277000D01*
X573418Y277140D01*
X573438Y277180D01*
X573453Y277215D01*
X573473Y277255D01*
X573488Y277295D01*
X573498Y277335D01*
X573513Y277380D01*
X573518Y277420D01*
X573528Y277460D01*
X573533Y277505D01*
Y277545D01*
X573538Y277590D01*
X573533Y277635D01*
Y277675D01*
X573528Y277720D01*
X573518Y277760D01*
X573513Y277800D01*
X573498Y277845D01*
X573488Y277885D01*
X573473Y277925D01*
X573453Y277965D01*
X573438Y278000D01*
X573418Y278040D01*
X573318Y278180D01*
X573288Y278210D01*
Y281640D01*
X573278Y281765D01*
X573238Y281890D01*
X573178Y282000D01*
X573098Y282100D01*
X572998Y282180D01*
X572888Y282240D01*
X572763Y282280D01*
X572638Y282290D01*
G37*
G36*
G01X577362D02*
X577237Y282280D01*
X577112Y282240D01*
X577002Y282180D01*
X576902Y282100D01*
X576822Y282000D01*
X576762Y281890D01*
X576722Y281765D01*
X576712Y281640D01*
Y278210D01*
X576682Y278180D01*
X576582Y278040D01*
X576562Y278000D01*
X576547Y277965D01*
X576527Y277925D01*
X576512Y277885D01*
X576502Y277845D01*
X576487Y277800D01*
X576482Y277760D01*
X576472Y277720D01*
X576467Y277675D01*
Y277635D01*
X576462Y277590D01*
X576467Y277545D01*
Y277505D01*
X576472Y277460D01*
X576482Y277420D01*
X576487Y277380D01*
X576502Y277335D01*
X576512Y277295D01*
X576527Y277255D01*
X576547Y277215D01*
X576562Y277180D01*
X576582Y277140D01*
X576682Y277000D01*
X576712Y276970D01*
Y275840D01*
X576722Y275715D01*
X576762Y275590D01*
X576822Y275480D01*
X576902Y275380D01*
X577002Y275300D01*
X577112Y275240D01*
X577237Y275200D01*
X577362Y275190D01*
X577487Y275200D01*
X577612Y275240D01*
X577722Y275300D01*
X577822Y275380D01*
X577902Y275480D01*
X577962Y275590D01*
X578002Y275715D01*
X578012Y275840D01*
Y276970D01*
X578042Y277000D01*
X578142Y277140D01*
X578162Y277180D01*
X578177Y277215D01*
X578197Y277255D01*
X578212Y277295D01*
X578222Y277335D01*
X578237Y277380D01*
X578242Y277420D01*
X578252Y277460D01*
X578257Y277505D01*
Y277545D01*
X578262Y277590D01*
X578257Y277635D01*
Y277675D01*
X578252Y277720D01*
X578242Y277760D01*
X578237Y277800D01*
X578222Y277845D01*
X578212Y277885D01*
X578197Y277925D01*
X578177Y277965D01*
X578162Y278000D01*
X578142Y278040D01*
X578042Y278180D01*
X578012Y278210D01*
Y281640D01*
X578002Y281765D01*
X577962Y281890D01*
X577902Y282000D01*
X577822Y282100D01*
X577722Y282180D01*
X577612Y282240D01*
X577487Y282280D01*
X577362Y282290D01*
G37*
G36*
G01X582087D02*
X581962Y282280D01*
X581837Y282240D01*
X581727Y282180D01*
X581627Y282100D01*
X581547Y282000D01*
X581487Y281890D01*
X581447Y281765D01*
X581437Y281640D01*
Y278210D01*
X581407Y278180D01*
X581307Y278040D01*
X581287Y278000D01*
X581272Y277965D01*
X581252Y277925D01*
X581237Y277885D01*
X581227Y277845D01*
X581212Y277800D01*
X581207Y277760D01*
X581197Y277720D01*
X581192Y277675D01*
Y277635D01*
X581187Y277590D01*
X581192Y277545D01*
Y277505D01*
X581197Y277460D01*
X581207Y277420D01*
X581212Y277380D01*
X581227Y277335D01*
X581237Y277295D01*
X581252Y277255D01*
X581272Y277215D01*
X581287Y277180D01*
X581307Y277140D01*
X581407Y277000D01*
X581437Y276970D01*
Y275840D01*
X581447Y275715D01*
X581487Y275590D01*
X581547Y275480D01*
X581627Y275380D01*
X581727Y275300D01*
X581837Y275240D01*
X581962Y275200D01*
X582087Y275190D01*
X582212Y275200D01*
X582337Y275240D01*
X582447Y275300D01*
X582547Y275380D01*
X582627Y275480D01*
X582687Y275590D01*
X582727Y275715D01*
X582737Y275840D01*
Y276970D01*
X582767Y277000D01*
X582867Y277140D01*
X582887Y277180D01*
X582902Y277215D01*
X582922Y277255D01*
X582937Y277295D01*
X582947Y277335D01*
X582962Y277380D01*
X582967Y277420D01*
X582977Y277460D01*
X582982Y277505D01*
Y277545D01*
X582987Y277590D01*
X582982Y277635D01*
Y277675D01*
X582977Y277720D01*
X582967Y277760D01*
X582962Y277800D01*
X582947Y277845D01*
X582937Y277885D01*
X582922Y277925D01*
X582902Y277965D01*
X582887Y278000D01*
X582867Y278040D01*
X582767Y278180D01*
X582737Y278210D01*
Y281640D01*
X582727Y281765D01*
X582687Y281890D01*
X582627Y282000D01*
X582547Y282100D01*
X582447Y282180D01*
X582337Y282240D01*
X582212Y282280D01*
X582087Y282290D01*
G37*
G36*
G01X586811D02*
X586686Y282280D01*
X586561Y282240D01*
X586451Y282180D01*
X586351Y282100D01*
X586271Y282000D01*
X586211Y281890D01*
X586171Y281765D01*
X586161Y281640D01*
Y278210D01*
X586131Y278180D01*
X586031Y278040D01*
X586011Y278000D01*
X585996Y277965D01*
X585976Y277925D01*
X585961Y277885D01*
X585951Y277845D01*
X585936Y277800D01*
X585931Y277760D01*
X585921Y277720D01*
X585916Y277675D01*
Y277635D01*
X585911Y277590D01*
X585916Y277545D01*
Y277505D01*
X585921Y277460D01*
X585931Y277420D01*
X585936Y277380D01*
X585951Y277335D01*
X585961Y277295D01*
X585976Y277255D01*
X585996Y277215D01*
X586011Y277180D01*
X586031Y277140D01*
X586131Y277000D01*
X586161Y276970D01*
Y275840D01*
X586171Y275715D01*
X586211Y275590D01*
X586271Y275480D01*
X586351Y275380D01*
X586451Y275300D01*
X586561Y275240D01*
X586686Y275200D01*
X586811Y275190D01*
X586936Y275200D01*
X587061Y275240D01*
X587171Y275300D01*
X587271Y275380D01*
X587351Y275480D01*
X587411Y275590D01*
X587451Y275715D01*
X587461Y275840D01*
Y276970D01*
X587491Y277000D01*
X587591Y277140D01*
X587611Y277180D01*
X587626Y277215D01*
X587646Y277255D01*
X587661Y277295D01*
X587671Y277335D01*
X587686Y277380D01*
X587691Y277420D01*
X587701Y277460D01*
X587706Y277505D01*
Y277545D01*
X587711Y277590D01*
X587706Y277635D01*
Y277675D01*
X587701Y277720D01*
X587691Y277760D01*
X587686Y277800D01*
X587671Y277845D01*
X587661Y277885D01*
X587646Y277925D01*
X587626Y277965D01*
X587611Y278000D01*
X587591Y278040D01*
X587491Y278180D01*
X587461Y278210D01*
Y281640D01*
X587451Y281765D01*
X587411Y281890D01*
X587351Y282000D01*
X587271Y282100D01*
X587171Y282180D01*
X587061Y282240D01*
X586936Y282280D01*
X586811Y282290D01*
G37*
G36*
G01X591536D02*
X591411Y282280D01*
X591286Y282240D01*
X591176Y282180D01*
X591076Y282100D01*
X590996Y282000D01*
X590936Y281890D01*
X590896Y281765D01*
X590886Y281640D01*
Y278210D01*
X590856Y278180D01*
X590756Y278040D01*
X590736Y278000D01*
X590721Y277965D01*
X590701Y277925D01*
X590686Y277885D01*
X590676Y277845D01*
X590661Y277800D01*
X590656Y277760D01*
X590646Y277720D01*
X590641Y277675D01*
Y277635D01*
X590636Y277590D01*
X590641Y277545D01*
Y277505D01*
X590646Y277460D01*
X590656Y277420D01*
X590661Y277380D01*
X590676Y277335D01*
X590686Y277295D01*
X590701Y277255D01*
X590721Y277215D01*
X590736Y277180D01*
X590756Y277140D01*
X590856Y277000D01*
X590886Y276970D01*
Y275840D01*
X590896Y275715D01*
X590936Y275590D01*
X590996Y275480D01*
X591076Y275380D01*
X591176Y275300D01*
X591286Y275240D01*
X591411Y275200D01*
X591536Y275190D01*
X591661Y275200D01*
X591786Y275240D01*
X591896Y275300D01*
X591996Y275380D01*
X592076Y275480D01*
X592136Y275590D01*
X592176Y275715D01*
X592186Y275840D01*
Y276970D01*
X592216Y277000D01*
X592316Y277140D01*
X592336Y277180D01*
X592351Y277215D01*
X592371Y277255D01*
X592386Y277295D01*
X592396Y277335D01*
X592411Y277380D01*
X592416Y277420D01*
X592426Y277460D01*
X592431Y277505D01*
Y277545D01*
X592436Y277590D01*
X592431Y277635D01*
Y277675D01*
X592426Y277720D01*
X592416Y277760D01*
X592411Y277800D01*
X592396Y277845D01*
X592386Y277885D01*
X592371Y277925D01*
X592351Y277965D01*
X592336Y278000D01*
X592316Y278040D01*
X592216Y278180D01*
X592186Y278210D01*
Y281640D01*
X592176Y281765D01*
X592136Y281890D01*
X592076Y282000D01*
X591996Y282100D01*
X591896Y282180D01*
X591786Y282240D01*
X591661Y282280D01*
X591536Y282290D01*
G37*
G36*
G01X596260D02*
X596135Y282280D01*
X596010Y282240D01*
X595900Y282180D01*
X595800Y282100D01*
X595720Y282000D01*
X595660Y281890D01*
X595620Y281765D01*
X595610Y281640D01*
Y278210D01*
X595580Y278180D01*
X595480Y278040D01*
X595460Y278000D01*
X595445Y277965D01*
X595425Y277925D01*
X595410Y277885D01*
X595400Y277845D01*
X595385Y277800D01*
X595380Y277760D01*
X595370Y277720D01*
X595365Y277675D01*
Y277635D01*
X595360Y277590D01*
X595365Y277545D01*
Y277505D01*
X595370Y277460D01*
X595380Y277420D01*
X595385Y277380D01*
X595400Y277335D01*
X595410Y277295D01*
X595425Y277255D01*
X595445Y277215D01*
X595460Y277180D01*
X595480Y277140D01*
X595580Y277000D01*
X595610Y276970D01*
Y275840D01*
X595620Y275715D01*
X595660Y275590D01*
X595720Y275480D01*
X595800Y275380D01*
X595900Y275300D01*
X596010Y275240D01*
X596135Y275200D01*
X596260Y275190D01*
X596385Y275200D01*
X596510Y275240D01*
X596620Y275300D01*
X596720Y275380D01*
X596800Y275480D01*
X596860Y275590D01*
X596900Y275715D01*
X596910Y275840D01*
Y276970D01*
X596940Y277000D01*
X597040Y277140D01*
X597060Y277180D01*
X597075Y277215D01*
X597095Y277255D01*
X597110Y277295D01*
X597120Y277335D01*
X597135Y277380D01*
X597140Y277420D01*
X597150Y277460D01*
X597155Y277505D01*
Y277545D01*
X597160Y277590D01*
X597155Y277635D01*
Y277675D01*
X597150Y277720D01*
X597140Y277760D01*
X597135Y277800D01*
X597120Y277845D01*
X597110Y277885D01*
X597095Y277925D01*
X597075Y277965D01*
X597060Y278000D01*
X597040Y278040D01*
X596940Y278180D01*
X596910Y278210D01*
Y281640D01*
X596900Y281765D01*
X596860Y281890D01*
X596800Y282000D01*
X596720Y282100D01*
X596620Y282180D01*
X596510Y282240D01*
X596385Y282280D01*
X596260Y282290D01*
G37*
G36*
G01X600985D02*
X600860Y282280D01*
X600735Y282240D01*
X600625Y282180D01*
X600525Y282100D01*
X600445Y282000D01*
X600385Y281890D01*
X600345Y281765D01*
X600335Y281640D01*
Y278210D01*
X600305Y278180D01*
X600205Y278040D01*
X600185Y278000D01*
X600170Y277965D01*
X600150Y277925D01*
X600135Y277885D01*
X600125Y277845D01*
X600110Y277800D01*
X600105Y277760D01*
X600095Y277720D01*
X600090Y277675D01*
Y277635D01*
X600085Y277590D01*
X600090Y277545D01*
Y277505D01*
X600095Y277460D01*
X600105Y277420D01*
X600110Y277380D01*
X600125Y277335D01*
X600135Y277295D01*
X600150Y277255D01*
X600170Y277215D01*
X600185Y277180D01*
X600205Y277140D01*
X600305Y277000D01*
X600335Y276970D01*
Y275840D01*
X600345Y275715D01*
X600385Y275590D01*
X600445Y275480D01*
X600525Y275380D01*
X600625Y275300D01*
X600735Y275240D01*
X600860Y275200D01*
X600985Y275190D01*
X601110Y275200D01*
X601235Y275240D01*
X601345Y275300D01*
X601445Y275380D01*
X601525Y275480D01*
X601585Y275590D01*
X601625Y275715D01*
X601635Y275840D01*
Y276970D01*
X601665Y277000D01*
X601765Y277140D01*
X601785Y277180D01*
X601800Y277215D01*
X601820Y277255D01*
X601835Y277295D01*
X601845Y277335D01*
X601860Y277380D01*
X601865Y277420D01*
X601875Y277460D01*
X601880Y277505D01*
Y277545D01*
X601885Y277590D01*
X601880Y277635D01*
Y277675D01*
X601875Y277720D01*
X601865Y277760D01*
X601860Y277800D01*
X601845Y277845D01*
X601835Y277885D01*
X601820Y277925D01*
X601800Y277965D01*
X601785Y278000D01*
X601765Y278040D01*
X601665Y278180D01*
X601635Y278210D01*
Y281640D01*
X601625Y281765D01*
X601585Y281890D01*
X601525Y282000D01*
X601445Y282100D01*
X601345Y282180D01*
X601235Y282240D01*
X601110Y282280D01*
X600985Y282290D01*
G37*
G36*
G01X605709D02*
X605584Y282280D01*
X605459Y282240D01*
X605349Y282180D01*
X605249Y282100D01*
X605169Y282000D01*
X605109Y281890D01*
X605069Y281765D01*
X605059Y281640D01*
Y278210D01*
X605029Y278180D01*
X604929Y278040D01*
X604909Y278000D01*
X604894Y277965D01*
X604874Y277925D01*
X604859Y277885D01*
X604849Y277845D01*
X604834Y277800D01*
X604829Y277760D01*
X604819Y277720D01*
X604814Y277675D01*
Y277635D01*
X604809Y277590D01*
X604814Y277545D01*
Y277505D01*
X604819Y277460D01*
X604829Y277420D01*
X604834Y277380D01*
X604849Y277335D01*
X604859Y277295D01*
X604874Y277255D01*
X604894Y277215D01*
X604909Y277180D01*
X604929Y277140D01*
X605029Y277000D01*
X605059Y276970D01*
Y275840D01*
X605069Y275715D01*
X605109Y275590D01*
X605169Y275480D01*
X605249Y275380D01*
X605349Y275300D01*
X605459Y275240D01*
X605584Y275200D01*
X605709Y275190D01*
X605834Y275200D01*
X605959Y275240D01*
X606069Y275300D01*
X606169Y275380D01*
X606249Y275480D01*
X606309Y275590D01*
X606349Y275715D01*
X606359Y275840D01*
Y276970D01*
X606389Y277000D01*
X606489Y277140D01*
X606509Y277180D01*
X606524Y277215D01*
X606544Y277255D01*
X606559Y277295D01*
X606569Y277335D01*
X606584Y277380D01*
X606589Y277420D01*
X606599Y277460D01*
X606604Y277505D01*
Y277545D01*
X606609Y277590D01*
X606604Y277635D01*
Y277675D01*
X606599Y277720D01*
X606589Y277760D01*
X606584Y277800D01*
X606569Y277845D01*
X606559Y277885D01*
X606544Y277925D01*
X606524Y277965D01*
X606509Y278000D01*
X606489Y278040D01*
X606389Y278180D01*
X606359Y278210D01*
Y281640D01*
X606349Y281765D01*
X606309Y281890D01*
X606249Y282000D01*
X606169Y282100D01*
X606069Y282180D01*
X605959Y282240D01*
X605834Y282280D01*
X605709Y282290D01*
G37*
G36*
G01X610433D02*
X610308Y282280D01*
X610183Y282240D01*
X610073Y282180D01*
X609973Y282100D01*
X609893Y282000D01*
X609833Y281890D01*
X609793Y281765D01*
X609783Y281640D01*
Y278210D01*
X609753Y278180D01*
X609653Y278040D01*
X609633Y278000D01*
X609618Y277965D01*
X609598Y277925D01*
X609583Y277885D01*
X609573Y277845D01*
X609558Y277800D01*
X609553Y277760D01*
X609543Y277720D01*
X609538Y277675D01*
Y277635D01*
X609533Y277590D01*
X609538Y277545D01*
Y277505D01*
X609543Y277460D01*
X609553Y277420D01*
X609558Y277380D01*
X609573Y277335D01*
X609583Y277295D01*
X609598Y277255D01*
X609618Y277215D01*
X609633Y277180D01*
X609653Y277140D01*
X609753Y277000D01*
X609783Y276970D01*
Y275840D01*
X609793Y275715D01*
X609833Y275590D01*
X609893Y275480D01*
X609973Y275380D01*
X610073Y275300D01*
X610183Y275240D01*
X610308Y275200D01*
X610433Y275190D01*
X610558Y275200D01*
X610683Y275240D01*
X610793Y275300D01*
X610893Y275380D01*
X610973Y275480D01*
X611033Y275590D01*
X611073Y275715D01*
X611083Y275840D01*
Y276970D01*
X611113Y277000D01*
X611213Y277140D01*
X611233Y277180D01*
X611248Y277215D01*
X611268Y277255D01*
X611283Y277295D01*
X611293Y277335D01*
X611308Y277380D01*
X611313Y277420D01*
X611323Y277460D01*
X611328Y277505D01*
Y277545D01*
X611333Y277590D01*
X611328Y277635D01*
Y277675D01*
X611323Y277720D01*
X611313Y277760D01*
X611308Y277800D01*
X611293Y277845D01*
X611283Y277885D01*
X611268Y277925D01*
X611248Y277965D01*
X611233Y278000D01*
X611213Y278040D01*
X611113Y278180D01*
X611083Y278210D01*
Y281640D01*
X611073Y281765D01*
X611033Y281890D01*
X610973Y282000D01*
X610893Y282100D01*
X610793Y282180D01*
X610683Y282240D01*
X610558Y282280D01*
X610433Y282290D01*
G37*
G36*
G01X615158D02*
X615033Y282280D01*
X614908Y282240D01*
X614798Y282180D01*
X614698Y282100D01*
X614618Y282000D01*
X614558Y281890D01*
X614518Y281765D01*
X614508Y281640D01*
Y278210D01*
X614478Y278180D01*
X614378Y278040D01*
X614358Y278000D01*
X614343Y277965D01*
X614323Y277925D01*
X614308Y277885D01*
X614298Y277845D01*
X614283Y277800D01*
X614278Y277760D01*
X614268Y277720D01*
X614263Y277675D01*
Y277635D01*
X614258Y277590D01*
X614263Y277545D01*
Y277505D01*
X614268Y277460D01*
X614278Y277420D01*
X614283Y277380D01*
X614298Y277335D01*
X614308Y277295D01*
X614323Y277255D01*
X614343Y277215D01*
X614358Y277180D01*
X614378Y277140D01*
X614478Y277000D01*
X614508Y276970D01*
Y275840D01*
X614518Y275715D01*
X614558Y275590D01*
X614618Y275480D01*
X614698Y275380D01*
X614798Y275300D01*
X614908Y275240D01*
X615033Y275200D01*
X615158Y275190D01*
X615283Y275200D01*
X615408Y275240D01*
X615518Y275300D01*
X615618Y275380D01*
X615698Y275480D01*
X615758Y275590D01*
X615798Y275715D01*
X615808Y275840D01*
Y276970D01*
X615838Y277000D01*
X615938Y277140D01*
X615958Y277180D01*
X615973Y277215D01*
X615993Y277255D01*
X616008Y277295D01*
X616018Y277335D01*
X616033Y277380D01*
X616038Y277420D01*
X616048Y277460D01*
X616053Y277505D01*
Y277545D01*
X616058Y277590D01*
X616053Y277635D01*
Y277675D01*
X616048Y277720D01*
X616038Y277760D01*
X616033Y277800D01*
X616018Y277845D01*
X616008Y277885D01*
X615993Y277925D01*
X615973Y277965D01*
X615958Y278000D01*
X615938Y278040D01*
X615838Y278180D01*
X615808Y278210D01*
Y281640D01*
X615798Y281765D01*
X615758Y281890D01*
X615698Y282000D01*
X615618Y282100D01*
X615518Y282180D01*
X615408Y282240D01*
X615283Y282280D01*
X615158Y282290D01*
G37*
G36*
G01X619882D02*
X619757Y282280D01*
X619632Y282240D01*
X619522Y282180D01*
X619422Y282100D01*
X619342Y282000D01*
X619282Y281890D01*
X619242Y281765D01*
X619232Y281640D01*
Y278210D01*
X619202Y278180D01*
X619102Y278040D01*
X619082Y278000D01*
X619067Y277965D01*
X619047Y277925D01*
X619032Y277885D01*
X619022Y277845D01*
X619007Y277800D01*
X619002Y277760D01*
X618992Y277720D01*
X618987Y277675D01*
Y277635D01*
X618982Y277590D01*
X618987Y277545D01*
Y277505D01*
X618992Y277460D01*
X619002Y277420D01*
X619007Y277380D01*
X619022Y277335D01*
X619032Y277295D01*
X619047Y277255D01*
X619067Y277215D01*
X619082Y277180D01*
X619102Y277140D01*
X619202Y277000D01*
X619232Y276970D01*
Y275840D01*
X619242Y275715D01*
X619282Y275590D01*
X619342Y275480D01*
X619422Y275380D01*
X619522Y275300D01*
X619632Y275240D01*
X619757Y275200D01*
X619882Y275190D01*
X620007Y275200D01*
X620132Y275240D01*
X620242Y275300D01*
X620342Y275380D01*
X620422Y275480D01*
X620482Y275590D01*
X620522Y275715D01*
X620532Y275840D01*
Y276970D01*
X620562Y277000D01*
X620662Y277140D01*
X620682Y277180D01*
X620697Y277215D01*
X620717Y277255D01*
X620732Y277295D01*
X620742Y277335D01*
X620757Y277380D01*
X620762Y277420D01*
X620772Y277460D01*
X620777Y277505D01*
Y277545D01*
X620782Y277590D01*
X620777Y277635D01*
Y277675D01*
X620772Y277720D01*
X620762Y277760D01*
X620757Y277800D01*
X620742Y277845D01*
X620732Y277885D01*
X620717Y277925D01*
X620697Y277965D01*
X620682Y278000D01*
X620662Y278040D01*
X620562Y278180D01*
X620532Y278210D01*
Y281640D01*
X620522Y281765D01*
X620482Y281890D01*
X620422Y282000D01*
X620342Y282100D01*
X620242Y282180D01*
X620132Y282240D01*
X620007Y282280D01*
X619882Y282290D01*
G37*
G36*
G01X624607D02*
X624482Y282280D01*
X624357Y282240D01*
X624247Y282180D01*
X624147Y282100D01*
X624067Y282000D01*
X624007Y281890D01*
X623967Y281765D01*
X623957Y281640D01*
Y278210D01*
X623927Y278180D01*
X623827Y278040D01*
X623807Y278000D01*
X623792Y277965D01*
X623772Y277925D01*
X623757Y277885D01*
X623747Y277845D01*
X623732Y277800D01*
X623727Y277760D01*
X623717Y277720D01*
X623712Y277675D01*
Y277635D01*
X623707Y277590D01*
X623712Y277545D01*
Y277505D01*
X623717Y277460D01*
X623727Y277420D01*
X623732Y277380D01*
X623747Y277335D01*
X623757Y277295D01*
X623772Y277255D01*
X623792Y277215D01*
X623807Y277180D01*
X623827Y277140D01*
X623927Y277000D01*
X623957Y276970D01*
Y275840D01*
X623967Y275715D01*
X624007Y275590D01*
X624067Y275480D01*
X624147Y275380D01*
X624247Y275300D01*
X624357Y275240D01*
X624482Y275200D01*
X624607Y275190D01*
X624732Y275200D01*
X624857Y275240D01*
X624967Y275300D01*
X625067Y275380D01*
X625147Y275480D01*
X625207Y275590D01*
X625247Y275715D01*
X625257Y275840D01*
Y276970D01*
X625287Y277000D01*
X625387Y277140D01*
X625407Y277180D01*
X625422Y277215D01*
X625442Y277255D01*
X625457Y277295D01*
X625467Y277335D01*
X625482Y277380D01*
X625487Y277420D01*
X625497Y277460D01*
X625502Y277505D01*
Y277545D01*
X625507Y277590D01*
X625502Y277635D01*
Y277675D01*
X625497Y277720D01*
X625487Y277760D01*
X625482Y277800D01*
X625467Y277845D01*
X625457Y277885D01*
X625442Y277925D01*
X625422Y277965D01*
X625407Y278000D01*
X625387Y278040D01*
X625287Y278180D01*
X625257Y278210D01*
Y281640D01*
X625247Y281765D01*
X625207Y281890D01*
X625147Y282000D01*
X625067Y282100D01*
X624967Y282180D01*
X624857Y282240D01*
X624732Y282280D01*
X624607Y282290D01*
G37*
G36*
G01X629331D02*
X629206Y282280D01*
X629081Y282240D01*
X628971Y282180D01*
X628871Y282100D01*
X628791Y282000D01*
X628731Y281890D01*
X628691Y281765D01*
X628681Y281640D01*
Y278210D01*
X628651Y278180D01*
X628551Y278040D01*
X628531Y278000D01*
X628516Y277965D01*
X628496Y277925D01*
X628481Y277885D01*
X628471Y277845D01*
X628456Y277800D01*
X628451Y277760D01*
X628441Y277720D01*
X628436Y277675D01*
Y277635D01*
X628431Y277590D01*
X628436Y277545D01*
Y277505D01*
X628441Y277460D01*
X628451Y277420D01*
X628456Y277380D01*
X628471Y277335D01*
X628481Y277295D01*
X628496Y277255D01*
X628516Y277215D01*
X628531Y277180D01*
X628551Y277140D01*
X628651Y277000D01*
X628681Y276970D01*
Y275840D01*
X628691Y275715D01*
X628731Y275590D01*
X628791Y275480D01*
X628871Y275380D01*
X628971Y275300D01*
X629081Y275240D01*
X629206Y275200D01*
X629331Y275190D01*
X629456Y275200D01*
X629581Y275240D01*
X629691Y275300D01*
X629791Y275380D01*
X629871Y275480D01*
X629931Y275590D01*
X629971Y275715D01*
X629981Y275840D01*
Y276970D01*
X630011Y277000D01*
X630111Y277140D01*
X630131Y277180D01*
X630146Y277215D01*
X630166Y277255D01*
X630181Y277295D01*
X630191Y277335D01*
X630206Y277380D01*
X630211Y277420D01*
X630221Y277460D01*
X630226Y277505D01*
Y277545D01*
X630231Y277590D01*
X630226Y277635D01*
Y277675D01*
X630221Y277720D01*
X630211Y277760D01*
X630206Y277800D01*
X630191Y277845D01*
X630181Y277885D01*
X630166Y277925D01*
X630146Y277965D01*
X630131Y278000D01*
X630111Y278040D01*
X630011Y278180D01*
X629981Y278210D01*
Y281640D01*
X629971Y281765D01*
X629931Y281890D01*
X629871Y282000D01*
X629791Y282100D01*
X629691Y282180D01*
X629581Y282240D01*
X629456Y282280D01*
X629331Y282290D01*
G37*
G36*
G01X634055D02*
X633930Y282280D01*
X633805Y282240D01*
X633695Y282180D01*
X633595Y282100D01*
X633515Y282000D01*
X633455Y281890D01*
X633415Y281765D01*
X633405Y281640D01*
Y278210D01*
X633375Y278180D01*
X633275Y278040D01*
X633255Y278000D01*
X633240Y277965D01*
X633220Y277925D01*
X633205Y277885D01*
X633195Y277845D01*
X633180Y277800D01*
X633175Y277760D01*
X633165Y277720D01*
X633160Y277675D01*
Y277635D01*
X633155Y277590D01*
X633160Y277545D01*
Y277505D01*
X633165Y277460D01*
X633175Y277420D01*
X633180Y277380D01*
X633195Y277335D01*
X633205Y277295D01*
X633220Y277255D01*
X633240Y277215D01*
X633255Y277180D01*
X633275Y277140D01*
X633375Y277000D01*
X633405Y276970D01*
Y275840D01*
X633415Y275715D01*
X633455Y275590D01*
X633515Y275480D01*
X633595Y275380D01*
X633695Y275300D01*
X633805Y275240D01*
X633930Y275200D01*
X634055Y275190D01*
X634180Y275200D01*
X634305Y275240D01*
X634415Y275300D01*
X634515Y275380D01*
X634595Y275480D01*
X634655Y275590D01*
X634695Y275715D01*
X634705Y275840D01*
Y276970D01*
X634735Y277000D01*
X634835Y277140D01*
X634855Y277180D01*
X634870Y277215D01*
X634890Y277255D01*
X634905Y277295D01*
X634915Y277335D01*
X634930Y277380D01*
X634935Y277420D01*
X634945Y277460D01*
X634950Y277505D01*
Y277545D01*
X634955Y277590D01*
X634950Y277635D01*
Y277675D01*
X634945Y277720D01*
X634935Y277760D01*
X634930Y277800D01*
X634915Y277845D01*
X634905Y277885D01*
X634890Y277925D01*
X634870Y277965D01*
X634855Y278000D01*
X634835Y278040D01*
X634735Y278180D01*
X634705Y278210D01*
Y281640D01*
X634695Y281765D01*
X634655Y281890D01*
X634595Y282000D01*
X634515Y282100D01*
X634415Y282180D01*
X634305Y282240D01*
X634180Y282280D01*
X634055Y282290D01*
G37*
G36*
G01X638780D02*
X638655Y282280D01*
X638530Y282240D01*
X638420Y282180D01*
X638320Y282100D01*
X638240Y282000D01*
X638180Y281890D01*
X638140Y281765D01*
X638130Y281640D01*
Y278210D01*
X638100Y278180D01*
X638000Y278040D01*
X637980Y278000D01*
X637965Y277965D01*
X637945Y277925D01*
X637930Y277885D01*
X637920Y277845D01*
X637905Y277800D01*
X637900Y277760D01*
X637890Y277720D01*
X637885Y277675D01*
Y277635D01*
X637880Y277590D01*
X637885Y277545D01*
Y277505D01*
X637890Y277460D01*
X637900Y277420D01*
X637905Y277380D01*
X637920Y277335D01*
X637930Y277295D01*
X637945Y277255D01*
X637965Y277215D01*
X637980Y277180D01*
X638000Y277140D01*
X638100Y277000D01*
X638130Y276970D01*
Y275840D01*
X638140Y275715D01*
X638180Y275590D01*
X638240Y275480D01*
X638320Y275380D01*
X638420Y275300D01*
X638530Y275240D01*
X638655Y275200D01*
X638780Y275190D01*
X638905Y275200D01*
X639030Y275240D01*
X639140Y275300D01*
X639240Y275380D01*
X639320Y275480D01*
X639380Y275590D01*
X639420Y275715D01*
X639430Y275840D01*
Y276970D01*
X639460Y277000D01*
X639560Y277140D01*
X639580Y277180D01*
X639595Y277215D01*
X639615Y277255D01*
X639630Y277295D01*
X639640Y277335D01*
X639655Y277380D01*
X639660Y277420D01*
X639670Y277460D01*
X639675Y277505D01*
Y277545D01*
X639680Y277590D01*
X639675Y277635D01*
Y277675D01*
X639670Y277720D01*
X639660Y277760D01*
X639655Y277800D01*
X639640Y277845D01*
X639630Y277885D01*
X639615Y277925D01*
X639595Y277965D01*
X639580Y278000D01*
X639560Y278040D01*
X639460Y278180D01*
X639430Y278210D01*
Y281640D01*
X639420Y281765D01*
X639380Y281890D01*
X639320Y282000D01*
X639240Y282100D01*
X639140Y282180D01*
X639030Y282240D01*
X638905Y282280D01*
X638780Y282290D01*
G37*
G36*
G01X643504D02*
X643379Y282280D01*
X643254Y282240D01*
X643144Y282180D01*
X643044Y282100D01*
X642964Y282000D01*
X642904Y281890D01*
X642864Y281765D01*
X642854Y281640D01*
Y278210D01*
X642824Y278180D01*
X642724Y278040D01*
X642704Y278000D01*
X642689Y277965D01*
X642669Y277925D01*
X642654Y277885D01*
X642644Y277845D01*
X642629Y277800D01*
X642624Y277760D01*
X642614Y277720D01*
X642609Y277675D01*
Y277635D01*
X642604Y277590D01*
X642609Y277545D01*
Y277505D01*
X642614Y277460D01*
X642624Y277420D01*
X642629Y277380D01*
X642644Y277335D01*
X642654Y277295D01*
X642669Y277255D01*
X642689Y277215D01*
X642704Y277180D01*
X642724Y277140D01*
X642824Y277000D01*
X642854Y276970D01*
Y275840D01*
X642864Y275715D01*
X642904Y275590D01*
X642964Y275480D01*
X643044Y275380D01*
X643144Y275300D01*
X643254Y275240D01*
X643379Y275200D01*
X643504Y275190D01*
X643629Y275200D01*
X643754Y275240D01*
X643864Y275300D01*
X643964Y275380D01*
X644044Y275480D01*
X644104Y275590D01*
X644144Y275715D01*
X644154Y275840D01*
Y276970D01*
X644184Y277000D01*
X644284Y277140D01*
X644304Y277180D01*
X644319Y277215D01*
X644339Y277255D01*
X644354Y277295D01*
X644364Y277335D01*
X644379Y277380D01*
X644384Y277420D01*
X644394Y277460D01*
X644399Y277505D01*
Y277545D01*
X644404Y277590D01*
X644399Y277635D01*
Y277675D01*
X644394Y277720D01*
X644384Y277760D01*
X644379Y277800D01*
X644364Y277845D01*
X644354Y277885D01*
X644339Y277925D01*
X644319Y277965D01*
X644304Y278000D01*
X644284Y278040D01*
X644184Y278180D01*
X644154Y278210D01*
Y281640D01*
X644144Y281765D01*
X644104Y281890D01*
X644044Y282000D01*
X643964Y282100D01*
X643864Y282180D01*
X643754Y282240D01*
X643629Y282280D01*
X643504Y282290D01*
G37*
G36*
G01X648229D02*
X648104Y282280D01*
X647979Y282240D01*
X647869Y282180D01*
X647769Y282100D01*
X647689Y282000D01*
X647629Y281890D01*
X647589Y281765D01*
X647579Y281640D01*
Y278210D01*
X647549Y278180D01*
X647449Y278040D01*
X647429Y278000D01*
X647414Y277965D01*
X647394Y277925D01*
X647379Y277885D01*
X647369Y277845D01*
X647354Y277800D01*
X647349Y277760D01*
X647339Y277720D01*
X647334Y277675D01*
Y277635D01*
X647329Y277590D01*
X647334Y277545D01*
Y277505D01*
X647339Y277460D01*
X647349Y277420D01*
X647354Y277380D01*
X647369Y277335D01*
X647379Y277295D01*
X647394Y277255D01*
X647414Y277215D01*
X647429Y277180D01*
X647449Y277140D01*
X647549Y277000D01*
X647579Y276970D01*
Y275840D01*
X647589Y275715D01*
X647629Y275590D01*
X647689Y275480D01*
X647769Y275380D01*
X647869Y275300D01*
X647979Y275240D01*
X648104Y275200D01*
X648229Y275190D01*
X648354Y275200D01*
X648479Y275240D01*
X648589Y275300D01*
X648689Y275380D01*
X648769Y275480D01*
X648829Y275590D01*
X648869Y275715D01*
X648879Y275840D01*
Y276970D01*
X648909Y277000D01*
X649009Y277140D01*
X649029Y277180D01*
X649044Y277215D01*
X649064Y277255D01*
X649079Y277295D01*
X649089Y277335D01*
X649104Y277380D01*
X649109Y277420D01*
X649119Y277460D01*
X649124Y277505D01*
Y277545D01*
X649129Y277590D01*
X649124Y277635D01*
Y277675D01*
X649119Y277720D01*
X649109Y277760D01*
X649104Y277800D01*
X649089Y277845D01*
X649079Y277885D01*
X649064Y277925D01*
X649044Y277965D01*
X649029Y278000D01*
X649009Y278040D01*
X648909Y278180D01*
X648879Y278210D01*
Y281640D01*
X648869Y281765D01*
X648829Y281890D01*
X648769Y282000D01*
X648689Y282100D01*
X648589Y282180D01*
X648479Y282240D01*
X648354Y282280D01*
X648229Y282290D01*
G37*
G36*
G01X652953D02*
X652828Y282280D01*
X652703Y282240D01*
X652593Y282180D01*
X652493Y282100D01*
X652413Y282000D01*
X652353Y281890D01*
X652313Y281765D01*
X652303Y281640D01*
Y278210D01*
X652273Y278180D01*
X652173Y278040D01*
X652153Y278000D01*
X652138Y277965D01*
X652118Y277925D01*
X652103Y277885D01*
X652093Y277845D01*
X652078Y277800D01*
X652073Y277760D01*
X652063Y277720D01*
X652058Y277675D01*
Y277635D01*
X652053Y277590D01*
X652058Y277545D01*
Y277505D01*
X652063Y277460D01*
X652073Y277420D01*
X652078Y277380D01*
X652093Y277335D01*
X652103Y277295D01*
X652118Y277255D01*
X652138Y277215D01*
X652153Y277180D01*
X652173Y277140D01*
X652273Y277000D01*
X652303Y276970D01*
Y275840D01*
X652313Y275715D01*
X652353Y275590D01*
X652413Y275480D01*
X652493Y275380D01*
X652593Y275300D01*
X652703Y275240D01*
X652828Y275200D01*
X652953Y275190D01*
X653078Y275200D01*
X653203Y275240D01*
X653313Y275300D01*
X653413Y275380D01*
X653493Y275480D01*
X653553Y275590D01*
X653593Y275715D01*
X653603Y275840D01*
Y276970D01*
X653633Y277000D01*
X653733Y277140D01*
X653753Y277180D01*
X653768Y277215D01*
X653788Y277255D01*
X653803Y277295D01*
X653813Y277335D01*
X653828Y277380D01*
X653833Y277420D01*
X653843Y277460D01*
X653848Y277505D01*
Y277545D01*
X653853Y277590D01*
X653848Y277635D01*
Y277675D01*
X653843Y277720D01*
X653833Y277760D01*
X653828Y277800D01*
X653813Y277845D01*
X653803Y277885D01*
X653788Y277925D01*
X653768Y277965D01*
X653753Y278000D01*
X653733Y278040D01*
X653633Y278180D01*
X653603Y278210D01*
Y281640D01*
X653593Y281765D01*
X653553Y281890D01*
X653493Y282000D01*
X653413Y282100D01*
X653313Y282180D01*
X653203Y282240D01*
X653078Y282280D01*
X652953Y282290D01*
G37*
G36*
G01X667126D02*
X667001Y282280D01*
X666876Y282240D01*
X666766Y282180D01*
X666666Y282100D01*
X666586Y282000D01*
X666526Y281890D01*
X666486Y281765D01*
X666476Y281640D01*
Y278210D01*
X666446Y278180D01*
X666346Y278040D01*
X666326Y278000D01*
X666311Y277965D01*
X666291Y277925D01*
X666276Y277885D01*
X666266Y277845D01*
X666251Y277800D01*
X666246Y277760D01*
X666236Y277720D01*
X666231Y277675D01*
Y277635D01*
X666226Y277590D01*
X666231Y277545D01*
Y277505D01*
X666236Y277460D01*
X666246Y277420D01*
X666251Y277380D01*
X666266Y277335D01*
X666276Y277295D01*
X666291Y277255D01*
X666311Y277215D01*
X666326Y277180D01*
X666346Y277140D01*
X666446Y277000D01*
X666476Y276970D01*
Y275840D01*
X666486Y275715D01*
X666526Y275590D01*
X666586Y275480D01*
X666666Y275380D01*
X666766Y275300D01*
X666876Y275240D01*
X667001Y275200D01*
X667126Y275190D01*
X667251Y275200D01*
X667376Y275240D01*
X667486Y275300D01*
X667586Y275380D01*
X667666Y275480D01*
X667726Y275590D01*
X667766Y275715D01*
X667776Y275840D01*
Y276970D01*
X667806Y277000D01*
X667906Y277140D01*
X667926Y277180D01*
X667941Y277215D01*
X667961Y277255D01*
X667976Y277295D01*
X667986Y277335D01*
X668001Y277380D01*
X668006Y277420D01*
X668016Y277460D01*
X668021Y277505D01*
Y277545D01*
X668026Y277590D01*
X668021Y277635D01*
Y277675D01*
X668016Y277720D01*
X668006Y277760D01*
X668001Y277800D01*
X667986Y277845D01*
X667976Y277885D01*
X667961Y277925D01*
X667941Y277965D01*
X667926Y278000D01*
X667906Y278040D01*
X667806Y278180D01*
X667776Y278210D01*
Y281640D01*
X667766Y281765D01*
X667726Y281890D01*
X667666Y282000D01*
X667586Y282100D01*
X667486Y282180D01*
X667376Y282240D01*
X667251Y282280D01*
X667126Y282290D01*
G37*
G36*
G01X671851D02*
X671726Y282280D01*
X671601Y282240D01*
X671491Y282180D01*
X671391Y282100D01*
X671311Y282000D01*
X671251Y281890D01*
X671211Y281765D01*
X671201Y281640D01*
Y278210D01*
X671171Y278180D01*
X671071Y278040D01*
X671051Y278000D01*
X671036Y277965D01*
X671016Y277925D01*
X671001Y277885D01*
X670991Y277845D01*
X670976Y277800D01*
X670971Y277760D01*
X670961Y277720D01*
X670956Y277675D01*
Y277635D01*
X670951Y277590D01*
X670956Y277545D01*
Y277505D01*
X670961Y277460D01*
X670971Y277420D01*
X670976Y277380D01*
X670991Y277335D01*
X671001Y277295D01*
X671016Y277255D01*
X671036Y277215D01*
X671051Y277180D01*
X671071Y277140D01*
X671171Y277000D01*
X671201Y276970D01*
Y275840D01*
X671211Y275715D01*
X671251Y275590D01*
X671311Y275480D01*
X671391Y275380D01*
X671491Y275300D01*
X671601Y275240D01*
X671726Y275200D01*
X671851Y275190D01*
X671976Y275200D01*
X672101Y275240D01*
X672211Y275300D01*
X672311Y275380D01*
X672391Y275480D01*
X672451Y275590D01*
X672491Y275715D01*
X672501Y275840D01*
Y276970D01*
X672531Y277000D01*
X672631Y277140D01*
X672651Y277180D01*
X672666Y277215D01*
X672686Y277255D01*
X672701Y277295D01*
X672711Y277335D01*
X672726Y277380D01*
X672731Y277420D01*
X672741Y277460D01*
X672746Y277505D01*
Y277545D01*
X672751Y277590D01*
X672746Y277635D01*
Y277675D01*
X672741Y277720D01*
X672731Y277760D01*
X672726Y277800D01*
X672711Y277845D01*
X672701Y277885D01*
X672686Y277925D01*
X672666Y277965D01*
X672651Y278000D01*
X672631Y278040D01*
X672531Y278180D01*
X672501Y278210D01*
Y281640D01*
X672491Y281765D01*
X672451Y281890D01*
X672391Y282000D01*
X672311Y282100D01*
X672211Y282180D01*
X672101Y282240D01*
X671976Y282280D01*
X671851Y282290D01*
G37*
G36*
G01X676575D02*
X676450Y282280D01*
X676325Y282240D01*
X676215Y282180D01*
X676115Y282100D01*
X676035Y282000D01*
X675975Y281890D01*
X675935Y281765D01*
X675925Y281640D01*
Y278210D01*
X675895Y278180D01*
X675795Y278040D01*
X675775Y278000D01*
X675760Y277965D01*
X675740Y277925D01*
X675725Y277885D01*
X675715Y277845D01*
X675700Y277800D01*
X675695Y277760D01*
X675685Y277720D01*
X675680Y277675D01*
Y277635D01*
X675675Y277590D01*
X675680Y277545D01*
Y277505D01*
X675685Y277460D01*
X675695Y277420D01*
X675700Y277380D01*
X675715Y277335D01*
X675725Y277295D01*
X675740Y277255D01*
X675760Y277215D01*
X675775Y277180D01*
X675795Y277140D01*
X675895Y277000D01*
X675925Y276970D01*
Y275840D01*
X675935Y275715D01*
X675975Y275590D01*
X676035Y275480D01*
X676115Y275380D01*
X676215Y275300D01*
X676325Y275240D01*
X676450Y275200D01*
X676575Y275190D01*
X676700Y275200D01*
X676825Y275240D01*
X676935Y275300D01*
X677035Y275380D01*
X677115Y275480D01*
X677175Y275590D01*
X677215Y275715D01*
X677225Y275840D01*
Y276970D01*
X677255Y277000D01*
X677355Y277140D01*
X677375Y277180D01*
X677390Y277215D01*
X677410Y277255D01*
X677425Y277295D01*
X677435Y277335D01*
X677450Y277380D01*
X677455Y277420D01*
X677465Y277460D01*
X677470Y277505D01*
Y277545D01*
X677475Y277590D01*
X677470Y277635D01*
Y277675D01*
X677465Y277720D01*
X677455Y277760D01*
X677450Y277800D01*
X677435Y277845D01*
X677425Y277885D01*
X677410Y277925D01*
X677390Y277965D01*
X677375Y278000D01*
X677355Y278040D01*
X677255Y278180D01*
X677225Y278210D01*
Y281640D01*
X677215Y281765D01*
X677175Y281890D01*
X677115Y282000D01*
X677035Y282100D01*
X676935Y282180D01*
X676825Y282240D01*
X676700Y282280D01*
X676575Y282290D01*
G37*
G36*
G01X681299D02*
X681174Y282280D01*
X681049Y282240D01*
X680939Y282180D01*
X680839Y282100D01*
X680759Y282000D01*
X680699Y281890D01*
X680659Y281765D01*
X680649Y281640D01*
Y278210D01*
X680619Y278180D01*
X680519Y278040D01*
X680499Y278000D01*
X680484Y277965D01*
X680464Y277925D01*
X680449Y277885D01*
X680439Y277845D01*
X680424Y277800D01*
X680419Y277760D01*
X680409Y277720D01*
X680404Y277675D01*
Y277635D01*
X680399Y277590D01*
X680404Y277545D01*
Y277505D01*
X680409Y277460D01*
X680419Y277420D01*
X680424Y277380D01*
X680439Y277335D01*
X680449Y277295D01*
X680464Y277255D01*
X680484Y277215D01*
X680499Y277180D01*
X680519Y277140D01*
X680619Y277000D01*
X680649Y276970D01*
Y275840D01*
X680659Y275715D01*
X680699Y275590D01*
X680759Y275480D01*
X680839Y275380D01*
X680939Y275300D01*
X681049Y275240D01*
X681174Y275200D01*
X681299Y275190D01*
X681424Y275200D01*
X681549Y275240D01*
X681659Y275300D01*
X681759Y275380D01*
X681839Y275480D01*
X681899Y275590D01*
X681939Y275715D01*
X681949Y275840D01*
Y276970D01*
X681979Y277000D01*
X682079Y277140D01*
X682099Y277180D01*
X682114Y277215D01*
X682134Y277255D01*
X682149Y277295D01*
X682159Y277335D01*
X682174Y277380D01*
X682179Y277420D01*
X682189Y277460D01*
X682194Y277505D01*
Y277545D01*
X682199Y277590D01*
X682194Y277635D01*
Y277675D01*
X682189Y277720D01*
X682179Y277760D01*
X682174Y277800D01*
X682159Y277845D01*
X682149Y277885D01*
X682134Y277925D01*
X682114Y277965D01*
X682099Y278000D01*
X682079Y278040D01*
X681979Y278180D01*
X681949Y278210D01*
Y281640D01*
X681939Y281765D01*
X681899Y281890D01*
X681839Y282000D01*
X681759Y282100D01*
X681659Y282180D01*
X681549Y282240D01*
X681424Y282280D01*
X681299Y282290D01*
G37*
G36*
G01X686024D02*
X685899Y282280D01*
X685774Y282240D01*
X685664Y282180D01*
X685564Y282100D01*
X685484Y282000D01*
X685424Y281890D01*
X685384Y281765D01*
X685374Y281640D01*
Y278210D01*
X685344Y278180D01*
X685244Y278040D01*
X685224Y278000D01*
X685209Y277965D01*
X685189Y277925D01*
X685174Y277885D01*
X685164Y277845D01*
X685149Y277800D01*
X685144Y277760D01*
X685134Y277720D01*
X685129Y277675D01*
Y277635D01*
X685124Y277590D01*
X685129Y277545D01*
Y277505D01*
X685134Y277460D01*
X685144Y277420D01*
X685149Y277380D01*
X685164Y277335D01*
X685174Y277295D01*
X685189Y277255D01*
X685209Y277215D01*
X685224Y277180D01*
X685244Y277140D01*
X685344Y277000D01*
X685374Y276970D01*
Y275840D01*
X685384Y275715D01*
X685424Y275590D01*
X685484Y275480D01*
X685564Y275380D01*
X685664Y275300D01*
X685774Y275240D01*
X685899Y275200D01*
X686024Y275190D01*
X686149Y275200D01*
X686274Y275240D01*
X686384Y275300D01*
X686484Y275380D01*
X686564Y275480D01*
X686624Y275590D01*
X686664Y275715D01*
X686674Y275840D01*
Y276970D01*
X686704Y277000D01*
X686804Y277140D01*
X686824Y277180D01*
X686839Y277215D01*
X686859Y277255D01*
X686874Y277295D01*
X686884Y277335D01*
X686899Y277380D01*
X686904Y277420D01*
X686914Y277460D01*
X686919Y277505D01*
Y277545D01*
X686924Y277590D01*
X686919Y277635D01*
Y277675D01*
X686914Y277720D01*
X686904Y277760D01*
X686899Y277800D01*
X686884Y277845D01*
X686874Y277885D01*
X686859Y277925D01*
X686839Y277965D01*
X686824Y278000D01*
X686804Y278040D01*
X686704Y278180D01*
X686674Y278210D01*
Y281640D01*
X686664Y281765D01*
X686624Y281890D01*
X686564Y282000D01*
X686484Y282100D01*
X686384Y282180D01*
X686274Y282240D01*
X686149Y282280D01*
X686024Y282290D01*
G37*
G36*
G01X690748D02*
X690623Y282280D01*
X690498Y282240D01*
X690388Y282180D01*
X690288Y282100D01*
X690208Y282000D01*
X690148Y281890D01*
X690108Y281765D01*
X690098Y281640D01*
Y278210D01*
X690068Y278180D01*
X689968Y278040D01*
X689948Y278000D01*
X689933Y277965D01*
X689913Y277925D01*
X689898Y277885D01*
X689888Y277845D01*
X689873Y277800D01*
X689868Y277760D01*
X689858Y277720D01*
X689853Y277675D01*
Y277635D01*
X689848Y277590D01*
X689853Y277545D01*
Y277505D01*
X689858Y277460D01*
X689868Y277420D01*
X689873Y277380D01*
X689888Y277335D01*
X689898Y277295D01*
X689913Y277255D01*
X689933Y277215D01*
X689948Y277180D01*
X689968Y277140D01*
X690068Y277000D01*
X690098Y276970D01*
Y275840D01*
X690108Y275715D01*
X690148Y275590D01*
X690208Y275480D01*
X690288Y275380D01*
X690388Y275300D01*
X690498Y275240D01*
X690623Y275200D01*
X690748Y275190D01*
X690873Y275200D01*
X690998Y275240D01*
X691108Y275300D01*
X691208Y275380D01*
X691288Y275480D01*
X691348Y275590D01*
X691388Y275715D01*
X691398Y275840D01*
Y276970D01*
X691428Y277000D01*
X691528Y277140D01*
X691548Y277180D01*
X691563Y277215D01*
X691583Y277255D01*
X691598Y277295D01*
X691608Y277335D01*
X691623Y277380D01*
X691628Y277420D01*
X691638Y277460D01*
X691643Y277505D01*
Y277545D01*
X691648Y277590D01*
X691643Y277635D01*
Y277675D01*
X691638Y277720D01*
X691628Y277760D01*
X691623Y277800D01*
X691608Y277845D01*
X691598Y277885D01*
X691583Y277925D01*
X691563Y277965D01*
X691548Y278000D01*
X691528Y278040D01*
X691428Y278180D01*
X691398Y278210D01*
Y281640D01*
X691388Y281765D01*
X691348Y281890D01*
X691288Y282000D01*
X691208Y282100D01*
X691108Y282180D01*
X690998Y282240D01*
X690873Y282280D01*
X690748Y282290D01*
G37*
G36*
G01X695473D02*
X695348Y282280D01*
X695223Y282240D01*
X695113Y282180D01*
X695013Y282100D01*
X694933Y282000D01*
X694873Y281890D01*
X694833Y281765D01*
X694823Y281640D01*
Y278210D01*
X694793Y278180D01*
X694693Y278040D01*
X694673Y278000D01*
X694658Y277965D01*
X694638Y277925D01*
X694623Y277885D01*
X694613Y277845D01*
X694598Y277800D01*
X694593Y277760D01*
X694583Y277720D01*
X694578Y277675D01*
Y277635D01*
X694573Y277590D01*
X694578Y277545D01*
Y277505D01*
X694583Y277460D01*
X694593Y277420D01*
X694598Y277380D01*
X694613Y277335D01*
X694623Y277295D01*
X694638Y277255D01*
X694658Y277215D01*
X694673Y277180D01*
X694693Y277140D01*
X694793Y277000D01*
X694823Y276970D01*
Y275840D01*
X694833Y275715D01*
X694873Y275590D01*
X694933Y275480D01*
X695013Y275380D01*
X695113Y275300D01*
X695223Y275240D01*
X695348Y275200D01*
X695473Y275190D01*
X695598Y275200D01*
X695723Y275240D01*
X695833Y275300D01*
X695933Y275380D01*
X696013Y275480D01*
X696073Y275590D01*
X696113Y275715D01*
X696123Y275840D01*
Y276970D01*
X696153Y277000D01*
X696253Y277140D01*
X696273Y277180D01*
X696288Y277215D01*
X696308Y277255D01*
X696323Y277295D01*
X696333Y277335D01*
X696348Y277380D01*
X696353Y277420D01*
X696363Y277460D01*
X696368Y277505D01*
Y277545D01*
X696373Y277590D01*
X696368Y277635D01*
Y277675D01*
X696363Y277720D01*
X696353Y277760D01*
X696348Y277800D01*
X696333Y277845D01*
X696323Y277885D01*
X696308Y277925D01*
X696288Y277965D01*
X696273Y278000D01*
X696253Y278040D01*
X696153Y278180D01*
X696123Y278210D01*
Y281640D01*
X696113Y281765D01*
X696073Y281890D01*
X696013Y282000D01*
X695933Y282100D01*
X695833Y282180D01*
X695723Y282240D01*
X695598Y282280D01*
X695473Y282290D01*
G37*
G36*
G01X700197D02*
X700072Y282280D01*
X699947Y282240D01*
X699837Y282180D01*
X699737Y282100D01*
X699657Y282000D01*
X699597Y281890D01*
X699557Y281765D01*
X699547Y281640D01*
Y278210D01*
X699517Y278180D01*
X699417Y278040D01*
X699397Y278000D01*
X699382Y277965D01*
X699362Y277925D01*
X699347Y277885D01*
X699337Y277845D01*
X699322Y277800D01*
X699317Y277760D01*
X699307Y277720D01*
X699302Y277675D01*
Y277635D01*
X699297Y277590D01*
X699302Y277545D01*
Y277505D01*
X699307Y277460D01*
X699317Y277420D01*
X699322Y277380D01*
X699337Y277335D01*
X699347Y277295D01*
X699362Y277255D01*
X699382Y277215D01*
X699397Y277180D01*
X699417Y277140D01*
X699517Y277000D01*
X699547Y276970D01*
Y275840D01*
X699557Y275715D01*
X699597Y275590D01*
X699657Y275480D01*
X699737Y275380D01*
X699837Y275300D01*
X699947Y275240D01*
X700072Y275200D01*
X700197Y275190D01*
X700322Y275200D01*
X700447Y275240D01*
X700557Y275300D01*
X700657Y275380D01*
X700737Y275480D01*
X700797Y275590D01*
X700837Y275715D01*
X700847Y275840D01*
Y276970D01*
X700877Y277000D01*
X700977Y277140D01*
X700997Y277180D01*
X701012Y277215D01*
X701032Y277255D01*
X701047Y277295D01*
X701057Y277335D01*
X701072Y277380D01*
X701077Y277420D01*
X701087Y277460D01*
X701092Y277505D01*
Y277545D01*
X701097Y277590D01*
X701092Y277635D01*
Y277675D01*
X701087Y277720D01*
X701077Y277760D01*
X701072Y277800D01*
X701057Y277845D01*
X701047Y277885D01*
X701032Y277925D01*
X701012Y277965D01*
X700997Y278000D01*
X700977Y278040D01*
X700877Y278180D01*
X700847Y278210D01*
Y281640D01*
X700837Y281765D01*
X700797Y281890D01*
X700737Y282000D01*
X700657Y282100D01*
X700557Y282180D01*
X700447Y282240D01*
X700322Y282280D01*
X700197Y282290D01*
G37*
G36*
G01X704922D02*
X704797Y282280D01*
X704672Y282240D01*
X704562Y282180D01*
X704462Y282100D01*
X704382Y282000D01*
X704322Y281890D01*
X704282Y281765D01*
X704272Y281640D01*
Y278210D01*
X704242Y278180D01*
X704142Y278040D01*
X704122Y278000D01*
X704107Y277965D01*
X704087Y277925D01*
X704072Y277885D01*
X704062Y277845D01*
X704047Y277800D01*
X704042Y277760D01*
X704032Y277720D01*
X704027Y277675D01*
Y277635D01*
X704022Y277590D01*
X704027Y277545D01*
Y277505D01*
X704032Y277460D01*
X704042Y277420D01*
X704047Y277380D01*
X704062Y277335D01*
X704072Y277295D01*
X704087Y277255D01*
X704107Y277215D01*
X704122Y277180D01*
X704142Y277140D01*
X704242Y277000D01*
X704272Y276970D01*
Y275840D01*
X704282Y275715D01*
X704322Y275590D01*
X704382Y275480D01*
X704462Y275380D01*
X704562Y275300D01*
X704672Y275240D01*
X704797Y275200D01*
X704922Y275190D01*
X705047Y275200D01*
X705172Y275240D01*
X705282Y275300D01*
X705382Y275380D01*
X705462Y275480D01*
X705522Y275590D01*
X705562Y275715D01*
X705572Y275840D01*
Y276970D01*
X705602Y277000D01*
X705702Y277140D01*
X705722Y277180D01*
X705737Y277215D01*
X705757Y277255D01*
X705772Y277295D01*
X705782Y277335D01*
X705797Y277380D01*
X705802Y277420D01*
X705812Y277460D01*
X705817Y277505D01*
Y277545D01*
X705822Y277590D01*
X705817Y277635D01*
Y277675D01*
X705812Y277720D01*
X705802Y277760D01*
X705797Y277800D01*
X705782Y277845D01*
X705772Y277885D01*
X705757Y277925D01*
X705737Y277965D01*
X705722Y278000D01*
X705702Y278040D01*
X705602Y278180D01*
X705572Y278210D01*
Y281640D01*
X705562Y281765D01*
X705522Y281890D01*
X705462Y282000D01*
X705382Y282100D01*
X705282Y282180D01*
X705172Y282240D01*
X705047Y282280D01*
X704922Y282290D01*
G37*
G36*
G01X709646D02*
X709521Y282280D01*
X709396Y282240D01*
X709286Y282180D01*
X709186Y282100D01*
X709106Y282000D01*
X709046Y281890D01*
X709006Y281765D01*
X708996Y281640D01*
Y278210D01*
X708966Y278180D01*
X708866Y278040D01*
X708846Y278000D01*
X708831Y277965D01*
X708811Y277925D01*
X708796Y277885D01*
X708786Y277845D01*
X708771Y277800D01*
X708766Y277760D01*
X708756Y277720D01*
X708751Y277675D01*
Y277635D01*
X708746Y277590D01*
X708751Y277545D01*
Y277505D01*
X708756Y277460D01*
X708766Y277420D01*
X708771Y277380D01*
X708786Y277335D01*
X708796Y277295D01*
X708811Y277255D01*
X708831Y277215D01*
X708846Y277180D01*
X708866Y277140D01*
X708966Y277000D01*
X708996Y276970D01*
Y275840D01*
X709006Y275715D01*
X709046Y275590D01*
X709106Y275480D01*
X709186Y275380D01*
X709286Y275300D01*
X709396Y275240D01*
X709521Y275200D01*
X709646Y275190D01*
X709771Y275200D01*
X709896Y275240D01*
X710006Y275300D01*
X710106Y275380D01*
X710186Y275480D01*
X710246Y275590D01*
X710286Y275715D01*
X710296Y275840D01*
Y276970D01*
X710326Y277000D01*
X710426Y277140D01*
X710446Y277180D01*
X710461Y277215D01*
X710481Y277255D01*
X710496Y277295D01*
X710506Y277335D01*
X710521Y277380D01*
X710526Y277420D01*
X710536Y277460D01*
X710541Y277505D01*
Y277545D01*
X710546Y277590D01*
X710541Y277635D01*
Y277675D01*
X710536Y277720D01*
X710526Y277760D01*
X710521Y277800D01*
X710506Y277845D01*
X710496Y277885D01*
X710481Y277925D01*
X710461Y277965D01*
X710446Y278000D01*
X710426Y278040D01*
X710326Y278180D01*
X710296Y278210D01*
Y281640D01*
X710286Y281765D01*
X710246Y281890D01*
X710186Y282000D01*
X710106Y282100D01*
X710006Y282180D01*
X709896Y282240D01*
X709771Y282280D01*
X709646Y282290D01*
G37*
G36*
G01X714370D02*
X714245Y282280D01*
X714120Y282240D01*
X714010Y282180D01*
X713910Y282100D01*
X713830Y282000D01*
X713770Y281890D01*
X713730Y281765D01*
X713720Y281640D01*
Y278210D01*
X713690Y278180D01*
X713590Y278040D01*
X713570Y278000D01*
X713555Y277965D01*
X713535Y277925D01*
X713520Y277885D01*
X713510Y277845D01*
X713495Y277800D01*
X713490Y277760D01*
X713480Y277720D01*
X713475Y277675D01*
Y277635D01*
X713470Y277590D01*
X713475Y277545D01*
Y277505D01*
X713480Y277460D01*
X713490Y277420D01*
X713495Y277380D01*
X713510Y277335D01*
X713520Y277295D01*
X713535Y277255D01*
X713555Y277215D01*
X713570Y277180D01*
X713590Y277140D01*
X713690Y277000D01*
X713720Y276970D01*
Y275840D01*
X713730Y275715D01*
X713770Y275590D01*
X713830Y275480D01*
X713910Y275380D01*
X714010Y275300D01*
X714120Y275240D01*
X714245Y275200D01*
X714370Y275190D01*
X714495Y275200D01*
X714620Y275240D01*
X714730Y275300D01*
X714830Y275380D01*
X714910Y275480D01*
X714970Y275590D01*
X715010Y275715D01*
X715020Y275840D01*
Y276970D01*
X715050Y277000D01*
X715150Y277140D01*
X715170Y277180D01*
X715185Y277215D01*
X715205Y277255D01*
X715220Y277295D01*
X715230Y277335D01*
X715245Y277380D01*
X715250Y277420D01*
X715260Y277460D01*
X715265Y277505D01*
Y277545D01*
X715270Y277590D01*
X715265Y277635D01*
Y277675D01*
X715260Y277720D01*
X715250Y277760D01*
X715245Y277800D01*
X715230Y277845D01*
X715220Y277885D01*
X715205Y277925D01*
X715185Y277965D01*
X715170Y278000D01*
X715150Y278040D01*
X715050Y278180D01*
X715020Y278210D01*
Y281640D01*
X715010Y281765D01*
X714970Y281890D01*
X714910Y282000D01*
X714830Y282100D01*
X714730Y282180D01*
X714620Y282240D01*
X714495Y282280D01*
X714370Y282290D01*
G37*
G36*
G01X719095D02*
X718970Y282280D01*
X718845Y282240D01*
X718735Y282180D01*
X718635Y282100D01*
X718555Y282000D01*
X718495Y281890D01*
X718455Y281765D01*
X718445Y281640D01*
Y278210D01*
X718415Y278180D01*
X718315Y278040D01*
X718295Y278000D01*
X718280Y277965D01*
X718260Y277925D01*
X718245Y277885D01*
X718235Y277845D01*
X718220Y277800D01*
X718215Y277760D01*
X718205Y277720D01*
X718200Y277675D01*
Y277635D01*
X718195Y277590D01*
X718200Y277545D01*
Y277505D01*
X718205Y277460D01*
X718215Y277420D01*
X718220Y277380D01*
X718235Y277335D01*
X718245Y277295D01*
X718260Y277255D01*
X718280Y277215D01*
X718295Y277180D01*
X718315Y277140D01*
X718415Y277000D01*
X718445Y276970D01*
Y275840D01*
X718455Y275715D01*
X718495Y275590D01*
X718555Y275480D01*
X718635Y275380D01*
X718735Y275300D01*
X718845Y275240D01*
X718970Y275200D01*
X719095Y275190D01*
X719220Y275200D01*
X719345Y275240D01*
X719455Y275300D01*
X719555Y275380D01*
X719635Y275480D01*
X719695Y275590D01*
X719735Y275715D01*
X719745Y275840D01*
Y276970D01*
X719775Y277000D01*
X719875Y277140D01*
X719895Y277180D01*
X719910Y277215D01*
X719930Y277255D01*
X719945Y277295D01*
X719955Y277335D01*
X719970Y277380D01*
X719975Y277420D01*
X719985Y277460D01*
X719990Y277505D01*
Y277545D01*
X719995Y277590D01*
X719990Y277635D01*
Y277675D01*
X719985Y277720D01*
X719975Y277760D01*
X719970Y277800D01*
X719955Y277845D01*
X719945Y277885D01*
X719930Y277925D01*
X719910Y277965D01*
X719895Y278000D01*
X719875Y278040D01*
X719775Y278180D01*
X719745Y278210D01*
Y281640D01*
X719735Y281765D01*
X719695Y281890D01*
X719635Y282000D01*
X719555Y282100D01*
X719455Y282180D01*
X719345Y282240D01*
X719220Y282280D01*
X719095Y282290D01*
G37*
G36*
G01X723819D02*
X723694Y282280D01*
X723569Y282240D01*
X723459Y282180D01*
X723359Y282100D01*
X723279Y282000D01*
X723219Y281890D01*
X723179Y281765D01*
X723169Y281640D01*
Y278210D01*
X723139Y278180D01*
X723039Y278040D01*
X723019Y278000D01*
X723004Y277965D01*
X722984Y277925D01*
X722969Y277885D01*
X722959Y277845D01*
X722944Y277800D01*
X722939Y277760D01*
X722929Y277720D01*
X722924Y277675D01*
Y277635D01*
X722919Y277590D01*
X722924Y277545D01*
Y277505D01*
X722929Y277460D01*
X722939Y277420D01*
X722944Y277380D01*
X722959Y277335D01*
X722969Y277295D01*
X722984Y277255D01*
X723004Y277215D01*
X723019Y277180D01*
X723039Y277140D01*
X723139Y277000D01*
X723169Y276970D01*
Y275840D01*
X723179Y275715D01*
X723219Y275590D01*
X723279Y275480D01*
X723359Y275380D01*
X723459Y275300D01*
X723569Y275240D01*
X723694Y275200D01*
X723819Y275190D01*
X723944Y275200D01*
X724069Y275240D01*
X724179Y275300D01*
X724279Y275380D01*
X724359Y275480D01*
X724419Y275590D01*
X724459Y275715D01*
X724469Y275840D01*
Y276970D01*
X724499Y277000D01*
X724599Y277140D01*
X724619Y277180D01*
X724634Y277215D01*
X724654Y277255D01*
X724669Y277295D01*
X724679Y277335D01*
X724694Y277380D01*
X724699Y277420D01*
X724709Y277460D01*
X724714Y277505D01*
Y277545D01*
X724719Y277590D01*
X724714Y277635D01*
Y277675D01*
X724709Y277720D01*
X724699Y277760D01*
X724694Y277800D01*
X724679Y277845D01*
X724669Y277885D01*
X724654Y277925D01*
X724634Y277965D01*
X724619Y278000D01*
X724599Y278040D01*
X724499Y278180D01*
X724469Y278210D01*
Y281640D01*
X724459Y281765D01*
X724419Y281890D01*
X724359Y282000D01*
X724279Y282100D01*
X724179Y282180D01*
X724069Y282240D01*
X723944Y282280D01*
X723819Y282290D01*
G37*
G36*
G01X728544D02*
X728419Y282280D01*
X728294Y282240D01*
X728184Y282180D01*
X728084Y282100D01*
X728004Y282000D01*
X727944Y281890D01*
X727904Y281765D01*
X727894Y281640D01*
Y278210D01*
X727864Y278180D01*
X727764Y278040D01*
X727744Y278000D01*
X727729Y277965D01*
X727709Y277925D01*
X727694Y277885D01*
X727684Y277845D01*
X727669Y277800D01*
X727664Y277760D01*
X727654Y277720D01*
X727649Y277675D01*
Y277635D01*
X727644Y277590D01*
X727649Y277545D01*
Y277505D01*
X727654Y277460D01*
X727664Y277420D01*
X727669Y277380D01*
X727684Y277335D01*
X727694Y277295D01*
X727709Y277255D01*
X727729Y277215D01*
X727744Y277180D01*
X727764Y277140D01*
X727864Y277000D01*
X727894Y276970D01*
Y275840D01*
X727904Y275715D01*
X727944Y275590D01*
X728004Y275480D01*
X728084Y275380D01*
X728184Y275300D01*
X728294Y275240D01*
X728419Y275200D01*
X728544Y275190D01*
X728669Y275200D01*
X728794Y275240D01*
X728904Y275300D01*
X729004Y275380D01*
X729084Y275480D01*
X729144Y275590D01*
X729184Y275715D01*
X729194Y275840D01*
Y276970D01*
X729224Y277000D01*
X729324Y277140D01*
X729344Y277180D01*
X729359Y277215D01*
X729379Y277255D01*
X729394Y277295D01*
X729404Y277335D01*
X729419Y277380D01*
X729424Y277420D01*
X729434Y277460D01*
X729439Y277505D01*
Y277545D01*
X729444Y277590D01*
X729439Y277635D01*
Y277675D01*
X729434Y277720D01*
X729424Y277760D01*
X729419Y277800D01*
X729404Y277845D01*
X729394Y277885D01*
X729379Y277925D01*
X729359Y277965D01*
X729344Y278000D01*
X729324Y278040D01*
X729224Y278180D01*
X729194Y278210D01*
Y281640D01*
X729184Y281765D01*
X729144Y281890D01*
X729084Y282000D01*
X729004Y282100D01*
X728904Y282180D01*
X728794Y282240D01*
X728669Y282280D01*
X728544Y282290D01*
G37*
G36*
G01X733268D02*
X733143Y282280D01*
X733018Y282240D01*
X732908Y282180D01*
X732808Y282100D01*
X732728Y282000D01*
X732668Y281890D01*
X732628Y281765D01*
X732618Y281640D01*
Y278210D01*
X732588Y278180D01*
X732488Y278040D01*
X732468Y278000D01*
X732453Y277965D01*
X732433Y277925D01*
X732418Y277885D01*
X732408Y277845D01*
X732393Y277800D01*
X732388Y277760D01*
X732378Y277720D01*
X732373Y277675D01*
Y277635D01*
X732368Y277590D01*
X732373Y277545D01*
Y277505D01*
X732378Y277460D01*
X732388Y277420D01*
X732393Y277380D01*
X732408Y277335D01*
X732418Y277295D01*
X732433Y277255D01*
X732453Y277215D01*
X732468Y277180D01*
X732488Y277140D01*
X732588Y277000D01*
X732618Y276970D01*
Y275840D01*
X732628Y275715D01*
X732668Y275590D01*
X732728Y275480D01*
X732808Y275380D01*
X732908Y275300D01*
X733018Y275240D01*
X733143Y275200D01*
X733268Y275190D01*
X733393Y275200D01*
X733518Y275240D01*
X733628Y275300D01*
X733728Y275380D01*
X733808Y275480D01*
X733868Y275590D01*
X733908Y275715D01*
X733918Y275840D01*
Y276970D01*
X733948Y277000D01*
X734048Y277140D01*
X734068Y277180D01*
X734083Y277215D01*
X734103Y277255D01*
X734118Y277295D01*
X734128Y277335D01*
X734143Y277380D01*
X734148Y277420D01*
X734158Y277460D01*
X734163Y277505D01*
Y277545D01*
X734168Y277590D01*
X734163Y277635D01*
Y277675D01*
X734158Y277720D01*
X734148Y277760D01*
X734143Y277800D01*
X734128Y277845D01*
X734118Y277885D01*
X734103Y277925D01*
X734083Y277965D01*
X734068Y278000D01*
X734048Y278040D01*
X733948Y278180D01*
X733918Y278210D01*
Y281640D01*
X733908Y281765D01*
X733868Y281890D01*
X733808Y282000D01*
X733728Y282100D01*
X733628Y282180D01*
X733518Y282240D01*
X733393Y282280D01*
X733268Y282290D01*
G37*
G36*
G01X737992D02*
X737867Y282280D01*
X737742Y282240D01*
X737632Y282180D01*
X737532Y282100D01*
X737452Y282000D01*
X737392Y281890D01*
X737352Y281765D01*
X737342Y281640D01*
Y278210D01*
X737312Y278180D01*
X737212Y278040D01*
X737192Y278000D01*
X737177Y277965D01*
X737157Y277925D01*
X737142Y277885D01*
X737132Y277845D01*
X737117Y277800D01*
X737112Y277760D01*
X737102Y277720D01*
X737097Y277675D01*
Y277635D01*
X737092Y277590D01*
X737097Y277545D01*
Y277505D01*
X737102Y277460D01*
X737112Y277420D01*
X737117Y277380D01*
X737132Y277335D01*
X737142Y277295D01*
X737157Y277255D01*
X737177Y277215D01*
X737192Y277180D01*
X737212Y277140D01*
X737312Y277000D01*
X737342Y276970D01*
Y275840D01*
X737352Y275715D01*
X737392Y275590D01*
X737452Y275480D01*
X737532Y275380D01*
X737632Y275300D01*
X737742Y275240D01*
X737867Y275200D01*
X737992Y275190D01*
X738117Y275200D01*
X738242Y275240D01*
X738352Y275300D01*
X738452Y275380D01*
X738532Y275480D01*
X738592Y275590D01*
X738632Y275715D01*
X738642Y275840D01*
Y276970D01*
X738672Y277000D01*
X738772Y277140D01*
X738792Y277180D01*
X738807Y277215D01*
X738827Y277255D01*
X738842Y277295D01*
X738852Y277335D01*
X738867Y277380D01*
X738872Y277420D01*
X738882Y277460D01*
X738887Y277505D01*
Y277545D01*
X738892Y277590D01*
X738887Y277635D01*
Y277675D01*
X738882Y277720D01*
X738872Y277760D01*
X738867Y277800D01*
X738852Y277845D01*
X738842Y277885D01*
X738827Y277925D01*
X738807Y277965D01*
X738792Y278000D01*
X738772Y278040D01*
X738672Y278180D01*
X738642Y278210D01*
Y281640D01*
X738632Y281765D01*
X738592Y281890D01*
X738532Y282000D01*
X738452Y282100D01*
X738352Y282180D01*
X738242Y282240D01*
X738117Y282280D01*
X737992Y282290D01*
G37*
G36*
G01X742717D02*
X742592Y282280D01*
X742467Y282240D01*
X742357Y282180D01*
X742257Y282100D01*
X742177Y282000D01*
X742117Y281890D01*
X742077Y281765D01*
X742067Y281640D01*
Y278210D01*
X742037Y278180D01*
X741937Y278040D01*
X741917Y278000D01*
X741902Y277965D01*
X741882Y277925D01*
X741867Y277885D01*
X741857Y277845D01*
X741842Y277800D01*
X741837Y277760D01*
X741827Y277720D01*
X741822Y277675D01*
Y277635D01*
X741817Y277590D01*
X741822Y277545D01*
Y277505D01*
X741827Y277460D01*
X741837Y277420D01*
X741842Y277380D01*
X741857Y277335D01*
X741867Y277295D01*
X741882Y277255D01*
X741902Y277215D01*
X741917Y277180D01*
X741937Y277140D01*
X742037Y277000D01*
X742067Y276970D01*
Y275840D01*
X742077Y275715D01*
X742117Y275590D01*
X742177Y275480D01*
X742257Y275380D01*
X742357Y275300D01*
X742467Y275240D01*
X742592Y275200D01*
X742717Y275190D01*
X742842Y275200D01*
X742967Y275240D01*
X743077Y275300D01*
X743177Y275380D01*
X743257Y275480D01*
X743317Y275590D01*
X743357Y275715D01*
X743367Y275840D01*
Y276970D01*
X743397Y277000D01*
X743497Y277140D01*
X743517Y277180D01*
X743532Y277215D01*
X743552Y277255D01*
X743567Y277295D01*
X743577Y277335D01*
X743592Y277380D01*
X743597Y277420D01*
X743607Y277460D01*
X743612Y277505D01*
Y277545D01*
X743617Y277590D01*
X743612Y277635D01*
Y277675D01*
X743607Y277720D01*
X743597Y277760D01*
X743592Y277800D01*
X743577Y277845D01*
X743567Y277885D01*
X743552Y277925D01*
X743532Y277965D01*
X743517Y278000D01*
X743497Y278040D01*
X743397Y278180D01*
X743367Y278210D01*
Y281640D01*
X743357Y281765D01*
X743317Y281890D01*
X743257Y282000D01*
X743177Y282100D01*
X743077Y282180D01*
X742967Y282240D01*
X742842Y282280D01*
X742717Y282290D01*
G37*
G36*
G01X747441D02*
X747316Y282280D01*
X747191Y282240D01*
X747081Y282180D01*
X746981Y282100D01*
X746901Y282000D01*
X746841Y281890D01*
X746801Y281765D01*
X746791Y281640D01*
Y278210D01*
X746761Y278180D01*
X746661Y278040D01*
X746641Y278000D01*
X746626Y277965D01*
X746606Y277925D01*
X746591Y277885D01*
X746581Y277845D01*
X746566Y277800D01*
X746561Y277760D01*
X746551Y277720D01*
X746546Y277675D01*
Y277635D01*
X746541Y277590D01*
X746546Y277545D01*
Y277505D01*
X746551Y277460D01*
X746561Y277420D01*
X746566Y277380D01*
X746581Y277335D01*
X746591Y277295D01*
X746606Y277255D01*
X746626Y277215D01*
X746641Y277180D01*
X746661Y277140D01*
X746761Y277000D01*
X746791Y276970D01*
Y275840D01*
X746801Y275715D01*
X746841Y275590D01*
X746901Y275480D01*
X746981Y275380D01*
X747081Y275300D01*
X747191Y275240D01*
X747316Y275200D01*
X747441Y275190D01*
X747566Y275200D01*
X747691Y275240D01*
X747801Y275300D01*
X747901Y275380D01*
X747981Y275480D01*
X748041Y275590D01*
X748081Y275715D01*
X748091Y275840D01*
Y276970D01*
X748121Y277000D01*
X748221Y277140D01*
X748241Y277180D01*
X748256Y277215D01*
X748276Y277255D01*
X748291Y277295D01*
X748301Y277335D01*
X748316Y277380D01*
X748321Y277420D01*
X748331Y277460D01*
X748336Y277505D01*
Y277545D01*
X748341Y277590D01*
X748336Y277635D01*
Y277675D01*
X748331Y277720D01*
X748321Y277760D01*
X748316Y277800D01*
X748301Y277845D01*
X748291Y277885D01*
X748276Y277925D01*
X748256Y277965D01*
X748241Y278000D01*
X748221Y278040D01*
X748121Y278180D01*
X748091Y278210D01*
Y281640D01*
X748081Y281765D01*
X748041Y281890D01*
X747981Y282000D01*
X747901Y282100D01*
X747801Y282180D01*
X747691Y282240D01*
X747566Y282280D01*
X747441Y282290D01*
G37*
G54D58*
X276811Y263386D03*
X296811D03*
X457913Y45276D03*
X477913D03*
G54D95*
G01X122319Y182176D02*
Y178981D01*
X123300Y178000D01*
X125000D01*
G54D86*
X517000Y102100D03*
X513000D03*
X515000Y96900D03*
X770700Y149600D03*
X766700D03*
X768700Y144400D03*
G54D77*
X500787Y70042D03*
X494882Y215354D03*
X759055Y70042D03*
X753150Y215354D03*
G54D68*
X372426Y258500D03*
Y256531D03*
Y254563D03*
Y252594D03*
Y250626D03*
Y248657D03*
Y268343D03*
Y266374D03*
Y264406D03*
Y262437D03*
Y260469D03*
X387574Y248657D03*
Y250626D03*
Y252594D03*
Y254563D03*
Y256531D03*
Y258500D03*
Y260469D03*
Y262437D03*
Y264406D03*
Y266374D03*
Y268343D03*
G54D59*
X283279Y103321D03*
X297500Y118600D03*
X298500Y129500D03*
X317000Y139600D03*
X338000Y171500D03*
X370700Y165000D03*
X371700Y156440D03*
X375100Y118700D03*
X373500Y114063D03*
Y109063D03*
X375000Y123563D03*
X377700Y152300D03*
X386938Y146572D03*
X376300Y160900D03*
X379700Y157450D03*
X375300Y166545D03*
X384400Y156400D03*
X389624Y140246D03*
X407492Y164734D03*
X412000Y168200D03*
G54D96*
G01X192900Y110200D02*
X191968D01*
X189468Y112700D01*
X189000D01*
G01X194900Y124200D02*
X198100Y121000D01*
Y120200D01*
G01X233981Y59125D02*
X231760Y56904D01*
Y56180D01*
G01X237000Y57000D02*
X237925D01*
X240200Y59275D01*
G01X233981Y59125D02*
X235456Y60600D01*
X237000D01*
G01X257800Y90200D02*
X261300D01*
G01X258634Y95850D02*
Y95834D01*
X257800Y95000D01*
Y90200D01*
G01X277000Y52700D02*
Y54132D01*
X278868Y56000D01*
G01X268520Y137660D02*
X265080Y134220D01*
Y128720D01*
X267500Y126300D01*
X268700D01*
G01X303500Y195400D02*
X303100Y195800D01*
Y209832D01*
X294257Y218675D01*
X282434D01*
X279046Y222063D01*
G01D02*
X276611Y224498D01*
X273046D01*
X270774Y222226D01*
G01X393500Y84600D02*
X389500D01*
X387200Y86900D01*
G01X390000Y161800D02*
X387132D01*
X386777Y162155D01*
G01X386500Y171800D02*
X384069D01*
X383693Y171424D01*
G01X392200Y81000D02*
X393500Y82300D01*
Y84600D01*
G01X392196Y131063D02*
X392116Y130983D01*
X390263D01*
X389380Y130100D01*
G01X752500Y49007D02*
Y47407D01*
X751600Y46507D01*
G01X778700Y139000D02*
Y141700D01*
X779000Y142000D01*
G54D69*
X375079Y245020D03*
X384921D03*
X377047D03*
X379016D03*
X380984D03*
X382953D03*
X375079Y271980D03*
X384921D03*
X382953D03*
X380984D03*
X379016D03*
X377047D03*
G54D87*
X762000Y163331D03*
Y154669D03*
G36*
G01X508858Y3106D02*
X508983Y3116D01*
X509108Y3156D01*
X509218Y3216D01*
X509318Y3296D01*
X509398Y3396D01*
X509458Y3506D01*
X509498Y3631D01*
X509508Y3756D01*
Y6186D01*
X509538Y6216D01*
X509638Y6356D01*
X509658Y6396D01*
X509673Y6431D01*
X509693Y6471D01*
X509708Y6511D01*
X509718Y6551D01*
X509733Y6596D01*
X509738Y6636D01*
X509748Y6676D01*
X509753Y6721D01*
Y6761D01*
X509758Y6806D01*
X509753Y6851D01*
Y6891D01*
X509748Y6936D01*
X509738Y6976D01*
X509733Y7016D01*
X509718Y7061D01*
X509708Y7101D01*
X509693Y7141D01*
X509673Y7181D01*
X509658Y7216D01*
X509638Y7256D01*
X509538Y7396D01*
X509508Y7426D01*
Y9556D01*
X509498Y9681D01*
X509458Y9806D01*
X509398Y9916D01*
X509318Y10016D01*
X509218Y10096D01*
X509108Y10156D01*
X508983Y10196D01*
X508858Y10206D01*
X508733Y10196D01*
X508608Y10156D01*
X508498Y10096D01*
X508398Y10016D01*
X508318Y9916D01*
X508258Y9806D01*
X508218Y9681D01*
X508208Y9556D01*
Y7431D01*
X508178Y7401D01*
X508153Y7366D01*
X508123Y7331D01*
X508103Y7296D01*
X508078Y7261D01*
X508038Y7181D01*
X507993Y7061D01*
X507983Y7021D01*
X507973Y6976D01*
X507968Y6936D01*
X507958Y6891D01*
Y6721D01*
X507968Y6676D01*
X507973Y6636D01*
X507983Y6591D01*
X507993Y6551D01*
X508038Y6431D01*
X508078Y6351D01*
X508103Y6316D01*
X508123Y6281D01*
X508153Y6246D01*
X508178Y6211D01*
X508208Y6181D01*
Y3756D01*
X508218Y3631D01*
X508258Y3506D01*
X508318Y3396D01*
X508398Y3296D01*
X508498Y3216D01*
X508608Y3156D01*
X508733Y3116D01*
X508858Y3106D01*
G37*
G36*
G01X523031D02*
X523156Y3116D01*
X523281Y3156D01*
X523391Y3216D01*
X523491Y3296D01*
X523571Y3396D01*
X523631Y3506D01*
X523671Y3631D01*
X523681Y3756D01*
Y6186D01*
X523711Y6216D01*
X523811Y6356D01*
X523831Y6396D01*
X523846Y6431D01*
X523866Y6471D01*
X523881Y6511D01*
X523891Y6551D01*
X523906Y6596D01*
X523911Y6636D01*
X523921Y6676D01*
X523926Y6721D01*
Y6761D01*
X523931Y6806D01*
X523926Y6851D01*
Y6891D01*
X523921Y6936D01*
X523911Y6976D01*
X523906Y7016D01*
X523891Y7061D01*
X523881Y7101D01*
X523866Y7141D01*
X523846Y7181D01*
X523831Y7216D01*
X523811Y7256D01*
X523711Y7396D01*
X523681Y7426D01*
Y9556D01*
X523671Y9681D01*
X523631Y9806D01*
X523571Y9916D01*
X523491Y10016D01*
X523391Y10096D01*
X523281Y10156D01*
X523156Y10196D01*
X523031Y10206D01*
X522906Y10196D01*
X522781Y10156D01*
X522671Y10096D01*
X522571Y10016D01*
X522491Y9916D01*
X522431Y9806D01*
X522391Y9681D01*
X522381Y9556D01*
Y7431D01*
X522351Y7401D01*
X522326Y7366D01*
X522296Y7331D01*
X522276Y7296D01*
X522251Y7261D01*
X522211Y7181D01*
X522166Y7061D01*
X522156Y7021D01*
X522146Y6976D01*
X522141Y6936D01*
X522131Y6891D01*
Y6721D01*
X522141Y6676D01*
X522146Y6636D01*
X522156Y6591D01*
X522166Y6551D01*
X522211Y6431D01*
X522251Y6351D01*
X522276Y6316D01*
X522296Y6281D01*
X522326Y6246D01*
X522351Y6211D01*
X522381Y6181D01*
Y3756D01*
X522391Y3631D01*
X522431Y3506D01*
X522491Y3396D01*
X522571Y3296D01*
X522671Y3216D01*
X522781Y3156D01*
X522906Y3116D01*
X523031Y3106D01*
G37*
G36*
G01X518307D02*
X518432Y3116D01*
X518557Y3156D01*
X518667Y3216D01*
X518767Y3296D01*
X518847Y3396D01*
X518907Y3506D01*
X518947Y3631D01*
X518957Y3756D01*
Y6186D01*
X518987Y6216D01*
X519087Y6356D01*
X519107Y6396D01*
X519122Y6431D01*
X519142Y6471D01*
X519157Y6511D01*
X519167Y6551D01*
X519182Y6596D01*
X519187Y6636D01*
X519197Y6676D01*
X519202Y6721D01*
Y6761D01*
X519207Y6806D01*
X519202Y6851D01*
Y6891D01*
X519197Y6936D01*
X519187Y6976D01*
X519182Y7016D01*
X519167Y7061D01*
X519157Y7101D01*
X519142Y7141D01*
X519122Y7181D01*
X519107Y7216D01*
X519087Y7256D01*
X518987Y7396D01*
X518957Y7426D01*
Y9556D01*
X518947Y9681D01*
X518907Y9806D01*
X518847Y9916D01*
X518767Y10016D01*
X518667Y10096D01*
X518557Y10156D01*
X518432Y10196D01*
X518307Y10206D01*
X518182Y10196D01*
X518057Y10156D01*
X517947Y10096D01*
X517847Y10016D01*
X517767Y9916D01*
X517707Y9806D01*
X517667Y9681D01*
X517657Y9556D01*
Y7431D01*
X517627Y7401D01*
X517602Y7366D01*
X517572Y7331D01*
X517552Y7296D01*
X517527Y7261D01*
X517487Y7181D01*
X517442Y7061D01*
X517432Y7021D01*
X517422Y6976D01*
X517417Y6936D01*
X517407Y6891D01*
Y6721D01*
X517417Y6676D01*
X517422Y6636D01*
X517432Y6591D01*
X517442Y6551D01*
X517487Y6431D01*
X517527Y6351D01*
X517552Y6316D01*
X517572Y6281D01*
X517602Y6246D01*
X517627Y6211D01*
X517657Y6181D01*
Y3756D01*
X517667Y3631D01*
X517707Y3506D01*
X517767Y3396D01*
X517847Y3296D01*
X517947Y3216D01*
X518057Y3156D01*
X518182Y3116D01*
X518307Y3106D01*
G37*
G36*
G01X513582D02*
X513707Y3116D01*
X513832Y3156D01*
X513942Y3216D01*
X514042Y3296D01*
X514122Y3396D01*
X514182Y3506D01*
X514222Y3631D01*
X514232Y3756D01*
Y6186D01*
X514262Y6216D01*
X514362Y6356D01*
X514382Y6396D01*
X514397Y6431D01*
X514417Y6471D01*
X514432Y6511D01*
X514442Y6551D01*
X514457Y6596D01*
X514462Y6636D01*
X514472Y6676D01*
X514477Y6721D01*
Y6761D01*
X514482Y6806D01*
X514477Y6851D01*
Y6891D01*
X514472Y6936D01*
X514462Y6976D01*
X514457Y7016D01*
X514442Y7061D01*
X514432Y7101D01*
X514417Y7141D01*
X514397Y7181D01*
X514382Y7216D01*
X514362Y7256D01*
X514262Y7396D01*
X514232Y7426D01*
Y9556D01*
X514222Y9681D01*
X514182Y9806D01*
X514122Y9916D01*
X514042Y10016D01*
X513942Y10096D01*
X513832Y10156D01*
X513707Y10196D01*
X513582Y10206D01*
X513457Y10196D01*
X513332Y10156D01*
X513222Y10096D01*
X513122Y10016D01*
X513042Y9916D01*
X512982Y9806D01*
X512942Y9681D01*
X512932Y9556D01*
Y7431D01*
X512902Y7401D01*
X512877Y7366D01*
X512847Y7331D01*
X512827Y7296D01*
X512802Y7261D01*
X512762Y7181D01*
X512717Y7061D01*
X512707Y7021D01*
X512697Y6976D01*
X512692Y6936D01*
X512682Y6891D01*
Y6721D01*
X512692Y6676D01*
X512697Y6636D01*
X512707Y6591D01*
X512717Y6551D01*
X512762Y6431D01*
X512802Y6351D01*
X512827Y6316D01*
X512847Y6281D01*
X512877Y6246D01*
X512902Y6211D01*
X512932Y6181D01*
Y3756D01*
X512942Y3631D01*
X512982Y3506D01*
X513042Y3396D01*
X513122Y3296D01*
X513222Y3216D01*
X513332Y3156D01*
X513457Y3116D01*
X513582Y3106D01*
G37*
G36*
G01X541929D02*
X542054Y3116D01*
X542179Y3156D01*
X542289Y3216D01*
X542389Y3296D01*
X542469Y3396D01*
X542529Y3506D01*
X542569Y3631D01*
X542579Y3756D01*
Y6186D01*
X542609Y6216D01*
X542709Y6356D01*
X542729Y6396D01*
X542744Y6431D01*
X542764Y6471D01*
X542779Y6511D01*
X542789Y6551D01*
X542804Y6596D01*
X542809Y6636D01*
X542819Y6676D01*
X542824Y6721D01*
Y6761D01*
X542829Y6806D01*
X542824Y6851D01*
Y6891D01*
X542819Y6936D01*
X542809Y6976D01*
X542804Y7016D01*
X542789Y7061D01*
X542779Y7101D01*
X542764Y7141D01*
X542744Y7181D01*
X542729Y7216D01*
X542709Y7256D01*
X542609Y7396D01*
X542579Y7426D01*
Y9556D01*
X542569Y9681D01*
X542529Y9806D01*
X542469Y9916D01*
X542389Y10016D01*
X542289Y10096D01*
X542179Y10156D01*
X542054Y10196D01*
X541929Y10206D01*
X541804Y10196D01*
X541679Y10156D01*
X541569Y10096D01*
X541469Y10016D01*
X541389Y9916D01*
X541329Y9806D01*
X541289Y9681D01*
X541279Y9556D01*
Y7431D01*
X541249Y7401D01*
X541224Y7366D01*
X541194Y7331D01*
X541174Y7296D01*
X541149Y7261D01*
X541109Y7181D01*
X541064Y7061D01*
X541054Y7021D01*
X541044Y6976D01*
X541039Y6936D01*
X541029Y6891D01*
Y6721D01*
X541039Y6676D01*
X541044Y6636D01*
X541054Y6591D01*
X541064Y6551D01*
X541109Y6431D01*
X541149Y6351D01*
X541174Y6316D01*
X541194Y6281D01*
X541224Y6246D01*
X541249Y6211D01*
X541279Y6181D01*
Y3756D01*
X541289Y3631D01*
X541329Y3506D01*
X541389Y3396D01*
X541469Y3296D01*
X541569Y3216D01*
X541679Y3156D01*
X541804Y3116D01*
X541929Y3106D01*
G37*
G36*
G01X537204D02*
X537329Y3116D01*
X537454Y3156D01*
X537564Y3216D01*
X537664Y3296D01*
X537744Y3396D01*
X537804Y3506D01*
X537844Y3631D01*
X537854Y3756D01*
Y6186D01*
X537884Y6216D01*
X537984Y6356D01*
X538004Y6396D01*
X538019Y6431D01*
X538039Y6471D01*
X538054Y6511D01*
X538064Y6551D01*
X538079Y6596D01*
X538084Y6636D01*
X538094Y6676D01*
X538099Y6721D01*
Y6761D01*
X538104Y6806D01*
X538099Y6851D01*
Y6891D01*
X538094Y6936D01*
X538084Y6976D01*
X538079Y7016D01*
X538064Y7061D01*
X538054Y7101D01*
X538039Y7141D01*
X538019Y7181D01*
X538004Y7216D01*
X537984Y7256D01*
X537884Y7396D01*
X537854Y7426D01*
Y9556D01*
X537844Y9681D01*
X537804Y9806D01*
X537744Y9916D01*
X537664Y10016D01*
X537564Y10096D01*
X537454Y10156D01*
X537329Y10196D01*
X537204Y10206D01*
X537079Y10196D01*
X536954Y10156D01*
X536844Y10096D01*
X536744Y10016D01*
X536664Y9916D01*
X536604Y9806D01*
X536564Y9681D01*
X536554Y9556D01*
Y7431D01*
X536524Y7401D01*
X536499Y7366D01*
X536469Y7331D01*
X536449Y7296D01*
X536424Y7261D01*
X536384Y7181D01*
X536339Y7061D01*
X536329Y7021D01*
X536319Y6976D01*
X536314Y6936D01*
X536304Y6891D01*
Y6721D01*
X536314Y6676D01*
X536319Y6636D01*
X536329Y6591D01*
X536339Y6551D01*
X536384Y6431D01*
X536424Y6351D01*
X536449Y6316D01*
X536469Y6281D01*
X536499Y6246D01*
X536524Y6211D01*
X536554Y6181D01*
Y3756D01*
X536564Y3631D01*
X536604Y3506D01*
X536664Y3396D01*
X536744Y3296D01*
X536844Y3216D01*
X536954Y3156D01*
X537079Y3116D01*
X537204Y3106D01*
G37*
G36*
G01X532480D02*
X532605Y3116D01*
X532730Y3156D01*
X532840Y3216D01*
X532940Y3296D01*
X533020Y3396D01*
X533080Y3506D01*
X533120Y3631D01*
X533130Y3756D01*
Y6186D01*
X533160Y6216D01*
X533260Y6356D01*
X533280Y6396D01*
X533295Y6431D01*
X533315Y6471D01*
X533330Y6511D01*
X533340Y6551D01*
X533355Y6596D01*
X533360Y6636D01*
X533370Y6676D01*
X533375Y6721D01*
Y6761D01*
X533380Y6806D01*
X533375Y6851D01*
Y6891D01*
X533370Y6936D01*
X533360Y6976D01*
X533355Y7016D01*
X533340Y7061D01*
X533330Y7101D01*
X533315Y7141D01*
X533295Y7181D01*
X533280Y7216D01*
X533260Y7256D01*
X533160Y7396D01*
X533130Y7426D01*
Y9556D01*
X533120Y9681D01*
X533080Y9806D01*
X533020Y9916D01*
X532940Y10016D01*
X532840Y10096D01*
X532730Y10156D01*
X532605Y10196D01*
X532480Y10206D01*
X532355Y10196D01*
X532230Y10156D01*
X532120Y10096D01*
X532020Y10016D01*
X531940Y9916D01*
X531880Y9806D01*
X531840Y9681D01*
X531830Y9556D01*
Y7431D01*
X531800Y7401D01*
X531775Y7366D01*
X531745Y7331D01*
X531725Y7296D01*
X531700Y7261D01*
X531660Y7181D01*
X531615Y7061D01*
X531605Y7021D01*
X531595Y6976D01*
X531590Y6936D01*
X531580Y6891D01*
Y6721D01*
X531590Y6676D01*
X531595Y6636D01*
X531605Y6591D01*
X531615Y6551D01*
X531660Y6431D01*
X531700Y6351D01*
X531725Y6316D01*
X531745Y6281D01*
X531775Y6246D01*
X531800Y6211D01*
X531830Y6181D01*
Y3756D01*
X531840Y3631D01*
X531880Y3506D01*
X531940Y3396D01*
X532020Y3296D01*
X532120Y3216D01*
X532230Y3156D01*
X532355Y3116D01*
X532480Y3106D01*
G37*
G36*
G01X527756D02*
X527881Y3116D01*
X528006Y3156D01*
X528116Y3216D01*
X528216Y3296D01*
X528296Y3396D01*
X528356Y3506D01*
X528396Y3631D01*
X528406Y3756D01*
Y6186D01*
X528436Y6216D01*
X528536Y6356D01*
X528556Y6396D01*
X528571Y6431D01*
X528591Y6471D01*
X528606Y6511D01*
X528616Y6551D01*
X528631Y6596D01*
X528636Y6636D01*
X528646Y6676D01*
X528651Y6721D01*
Y6761D01*
X528656Y6806D01*
X528651Y6851D01*
Y6891D01*
X528646Y6936D01*
X528636Y6976D01*
X528631Y7016D01*
X528616Y7061D01*
X528606Y7101D01*
X528591Y7141D01*
X528571Y7181D01*
X528556Y7216D01*
X528536Y7256D01*
X528436Y7396D01*
X528406Y7426D01*
Y9556D01*
X528396Y9681D01*
X528356Y9806D01*
X528296Y9916D01*
X528216Y10016D01*
X528116Y10096D01*
X528006Y10156D01*
X527881Y10196D01*
X527756Y10206D01*
X527631Y10196D01*
X527506Y10156D01*
X527396Y10096D01*
X527296Y10016D01*
X527216Y9916D01*
X527156Y9806D01*
X527116Y9681D01*
X527106Y9556D01*
Y7431D01*
X527076Y7401D01*
X527051Y7366D01*
X527021Y7331D01*
X527001Y7296D01*
X526976Y7261D01*
X526936Y7181D01*
X526891Y7061D01*
X526881Y7021D01*
X526871Y6976D01*
X526866Y6936D01*
X526856Y6891D01*
Y6721D01*
X526866Y6676D01*
X526871Y6636D01*
X526881Y6591D01*
X526891Y6551D01*
X526936Y6431D01*
X526976Y6351D01*
X527001Y6316D01*
X527021Y6281D01*
X527051Y6246D01*
X527076Y6211D01*
X527106Y6181D01*
Y3756D01*
X527116Y3631D01*
X527156Y3506D01*
X527216Y3396D01*
X527296Y3296D01*
X527396Y3216D01*
X527506Y3156D01*
X527631Y3116D01*
X527756Y3106D01*
G37*
G36*
G01X556102D02*
X556227Y3116D01*
X556352Y3156D01*
X556462Y3216D01*
X556562Y3296D01*
X556642Y3396D01*
X556702Y3506D01*
X556742Y3631D01*
X556752Y3756D01*
Y6186D01*
X556782Y6216D01*
X556882Y6356D01*
X556902Y6396D01*
X556917Y6431D01*
X556937Y6471D01*
X556952Y6511D01*
X556962Y6551D01*
X556977Y6596D01*
X556982Y6636D01*
X556992Y6676D01*
X556997Y6721D01*
Y6761D01*
X557002Y6806D01*
X556997Y6851D01*
Y6891D01*
X556992Y6936D01*
X556982Y6976D01*
X556977Y7016D01*
X556962Y7061D01*
X556952Y7101D01*
X556937Y7141D01*
X556917Y7181D01*
X556902Y7216D01*
X556882Y7256D01*
X556782Y7396D01*
X556752Y7426D01*
Y9556D01*
X556742Y9681D01*
X556702Y9806D01*
X556642Y9916D01*
X556562Y10016D01*
X556462Y10096D01*
X556352Y10156D01*
X556227Y10196D01*
X556102Y10206D01*
X555977Y10196D01*
X555852Y10156D01*
X555742Y10096D01*
X555642Y10016D01*
X555562Y9916D01*
X555502Y9806D01*
X555462Y9681D01*
X555452Y9556D01*
Y7431D01*
X555422Y7401D01*
X555397Y7366D01*
X555367Y7331D01*
X555347Y7296D01*
X555322Y7261D01*
X555282Y7181D01*
X555237Y7061D01*
X555227Y7021D01*
X555217Y6976D01*
X555212Y6936D01*
X555202Y6891D01*
Y6721D01*
X555212Y6676D01*
X555217Y6636D01*
X555227Y6591D01*
X555237Y6551D01*
X555282Y6431D01*
X555322Y6351D01*
X555347Y6316D01*
X555367Y6281D01*
X555397Y6246D01*
X555422Y6211D01*
X555452Y6181D01*
Y3756D01*
X555462Y3631D01*
X555502Y3506D01*
X555562Y3396D01*
X555642Y3296D01*
X555742Y3216D01*
X555852Y3156D01*
X555977Y3116D01*
X556102Y3106D01*
G37*
G36*
G01X551378D02*
X551503Y3116D01*
X551628Y3156D01*
X551738Y3216D01*
X551838Y3296D01*
X551918Y3396D01*
X551978Y3506D01*
X552018Y3631D01*
X552028Y3756D01*
Y6186D01*
X552058Y6216D01*
X552158Y6356D01*
X552178Y6396D01*
X552193Y6431D01*
X552213Y6471D01*
X552228Y6511D01*
X552238Y6551D01*
X552253Y6596D01*
X552258Y6636D01*
X552268Y6676D01*
X552273Y6721D01*
Y6761D01*
X552278Y6806D01*
X552273Y6851D01*
Y6891D01*
X552268Y6936D01*
X552258Y6976D01*
X552253Y7016D01*
X552238Y7061D01*
X552228Y7101D01*
X552213Y7141D01*
X552193Y7181D01*
X552178Y7216D01*
X552158Y7256D01*
X552058Y7396D01*
X552028Y7426D01*
Y9556D01*
X552018Y9681D01*
X551978Y9806D01*
X551918Y9916D01*
X551838Y10016D01*
X551738Y10096D01*
X551628Y10156D01*
X551503Y10196D01*
X551378Y10206D01*
X551253Y10196D01*
X551128Y10156D01*
X551018Y10096D01*
X550918Y10016D01*
X550838Y9916D01*
X550778Y9806D01*
X550738Y9681D01*
X550728Y9556D01*
Y7431D01*
X550698Y7401D01*
X550673Y7366D01*
X550643Y7331D01*
X550623Y7296D01*
X550598Y7261D01*
X550558Y7181D01*
X550513Y7061D01*
X550503Y7021D01*
X550493Y6976D01*
X550488Y6936D01*
X550478Y6891D01*
Y6721D01*
X550488Y6676D01*
X550493Y6636D01*
X550503Y6591D01*
X550513Y6551D01*
X550558Y6431D01*
X550598Y6351D01*
X550623Y6316D01*
X550643Y6281D01*
X550673Y6246D01*
X550698Y6211D01*
X550728Y6181D01*
Y3756D01*
X550738Y3631D01*
X550778Y3506D01*
X550838Y3396D01*
X550918Y3296D01*
X551018Y3216D01*
X551128Y3156D01*
X551253Y3116D01*
X551378Y3106D01*
G37*
G36*
G01X546653D02*
X546778Y3116D01*
X546903Y3156D01*
X547013Y3216D01*
X547113Y3296D01*
X547193Y3396D01*
X547253Y3506D01*
X547293Y3631D01*
X547303Y3756D01*
Y6186D01*
X547333Y6216D01*
X547433Y6356D01*
X547453Y6396D01*
X547468Y6431D01*
X547488Y6471D01*
X547503Y6511D01*
X547513Y6551D01*
X547528Y6596D01*
X547533Y6636D01*
X547543Y6676D01*
X547548Y6721D01*
Y6761D01*
X547553Y6806D01*
X547548Y6851D01*
Y6891D01*
X547543Y6936D01*
X547533Y6976D01*
X547528Y7016D01*
X547513Y7061D01*
X547503Y7101D01*
X547488Y7141D01*
X547468Y7181D01*
X547453Y7216D01*
X547433Y7256D01*
X547333Y7396D01*
X547303Y7426D01*
Y9556D01*
X547293Y9681D01*
X547253Y9806D01*
X547193Y9916D01*
X547113Y10016D01*
X547013Y10096D01*
X546903Y10156D01*
X546778Y10196D01*
X546653Y10206D01*
X546528Y10196D01*
X546403Y10156D01*
X546293Y10096D01*
X546193Y10016D01*
X546113Y9916D01*
X546053Y9806D01*
X546013Y9681D01*
X546003Y9556D01*
Y7431D01*
X545973Y7401D01*
X545948Y7366D01*
X545918Y7331D01*
X545898Y7296D01*
X545873Y7261D01*
X545833Y7181D01*
X545788Y7061D01*
X545778Y7021D01*
X545768Y6976D01*
X545763Y6936D01*
X545753Y6891D01*
Y6721D01*
X545763Y6676D01*
X545768Y6636D01*
X545778Y6591D01*
X545788Y6551D01*
X545833Y6431D01*
X545873Y6351D01*
X545898Y6316D01*
X545918Y6281D01*
X545948Y6246D01*
X545973Y6211D01*
X546003Y6181D01*
Y3756D01*
X546013Y3631D01*
X546053Y3506D01*
X546113Y3396D01*
X546193Y3296D01*
X546293Y3216D01*
X546403Y3156D01*
X546528Y3116D01*
X546653Y3106D01*
G37*
G36*
G01X570275D02*
X570400Y3116D01*
X570525Y3156D01*
X570635Y3216D01*
X570735Y3296D01*
X570815Y3396D01*
X570875Y3506D01*
X570915Y3631D01*
X570925Y3756D01*
Y6186D01*
X570955Y6216D01*
X571055Y6356D01*
X571075Y6396D01*
X571090Y6431D01*
X571110Y6471D01*
X571125Y6511D01*
X571135Y6551D01*
X571150Y6596D01*
X571155Y6636D01*
X571165Y6676D01*
X571170Y6721D01*
Y6761D01*
X571175Y6806D01*
X571170Y6851D01*
Y6891D01*
X571165Y6936D01*
X571155Y6976D01*
X571150Y7016D01*
X571135Y7061D01*
X571125Y7101D01*
X571110Y7141D01*
X571090Y7181D01*
X571075Y7216D01*
X571055Y7256D01*
X570955Y7396D01*
X570925Y7426D01*
Y9556D01*
X570915Y9681D01*
X570875Y9806D01*
X570815Y9916D01*
X570735Y10016D01*
X570635Y10096D01*
X570525Y10156D01*
X570400Y10196D01*
X570275Y10206D01*
X570150Y10196D01*
X570025Y10156D01*
X569915Y10096D01*
X569815Y10016D01*
X569735Y9916D01*
X569675Y9806D01*
X569635Y9681D01*
X569625Y9556D01*
Y7431D01*
X569595Y7401D01*
X569570Y7366D01*
X569540Y7331D01*
X569520Y7296D01*
X569495Y7261D01*
X569455Y7181D01*
X569410Y7061D01*
X569400Y7021D01*
X569390Y6976D01*
X569385Y6936D01*
X569375Y6891D01*
Y6721D01*
X569385Y6676D01*
X569390Y6636D01*
X569400Y6591D01*
X569410Y6551D01*
X569455Y6431D01*
X569495Y6351D01*
X569520Y6316D01*
X569540Y6281D01*
X569570Y6246D01*
X569595Y6211D01*
X569625Y6181D01*
Y3756D01*
X569635Y3631D01*
X569675Y3506D01*
X569735Y3396D01*
X569815Y3296D01*
X569915Y3216D01*
X570025Y3156D01*
X570150Y3116D01*
X570275Y3106D01*
G37*
G36*
G01X565551D02*
X565676Y3116D01*
X565801Y3156D01*
X565911Y3216D01*
X566011Y3296D01*
X566091Y3396D01*
X566151Y3506D01*
X566191Y3631D01*
X566201Y3756D01*
Y6186D01*
X566231Y6216D01*
X566331Y6356D01*
X566351Y6396D01*
X566366Y6431D01*
X566386Y6471D01*
X566401Y6511D01*
X566411Y6551D01*
X566426Y6596D01*
X566431Y6636D01*
X566441Y6676D01*
X566446Y6721D01*
Y6761D01*
X566451Y6806D01*
X566446Y6851D01*
Y6891D01*
X566441Y6936D01*
X566431Y6976D01*
X566426Y7016D01*
X566411Y7061D01*
X566401Y7101D01*
X566386Y7141D01*
X566366Y7181D01*
X566351Y7216D01*
X566331Y7256D01*
X566231Y7396D01*
X566201Y7426D01*
Y9556D01*
X566191Y9681D01*
X566151Y9806D01*
X566091Y9916D01*
X566011Y10016D01*
X565911Y10096D01*
X565801Y10156D01*
X565676Y10196D01*
X565551Y10206D01*
X565426Y10196D01*
X565301Y10156D01*
X565191Y10096D01*
X565091Y10016D01*
X565011Y9916D01*
X564951Y9806D01*
X564911Y9681D01*
X564901Y9556D01*
Y7431D01*
X564871Y7401D01*
X564846Y7366D01*
X564816Y7331D01*
X564796Y7296D01*
X564771Y7261D01*
X564731Y7181D01*
X564686Y7061D01*
X564676Y7021D01*
X564666Y6976D01*
X564661Y6936D01*
X564651Y6891D01*
Y6721D01*
X564661Y6676D01*
X564666Y6636D01*
X564676Y6591D01*
X564686Y6551D01*
X564731Y6431D01*
X564771Y6351D01*
X564796Y6316D01*
X564816Y6281D01*
X564846Y6246D01*
X564871Y6211D01*
X564901Y6181D01*
Y3756D01*
X564911Y3631D01*
X564951Y3506D01*
X565011Y3396D01*
X565091Y3296D01*
X565191Y3216D01*
X565301Y3156D01*
X565426Y3116D01*
X565551Y3106D01*
G37*
G36*
G01X560827D02*
X560952Y3116D01*
X561077Y3156D01*
X561187Y3216D01*
X561287Y3296D01*
X561367Y3396D01*
X561427Y3506D01*
X561467Y3631D01*
X561477Y3756D01*
Y6186D01*
X561507Y6216D01*
X561607Y6356D01*
X561627Y6396D01*
X561642Y6431D01*
X561662Y6471D01*
X561677Y6511D01*
X561687Y6551D01*
X561702Y6596D01*
X561707Y6636D01*
X561717Y6676D01*
X561722Y6721D01*
Y6761D01*
X561727Y6806D01*
X561722Y6851D01*
Y6891D01*
X561717Y6936D01*
X561707Y6976D01*
X561702Y7016D01*
X561687Y7061D01*
X561677Y7101D01*
X561662Y7141D01*
X561642Y7181D01*
X561627Y7216D01*
X561607Y7256D01*
X561507Y7396D01*
X561477Y7426D01*
Y9556D01*
X561467Y9681D01*
X561427Y9806D01*
X561367Y9916D01*
X561287Y10016D01*
X561187Y10096D01*
X561077Y10156D01*
X560952Y10196D01*
X560827Y10206D01*
X560702Y10196D01*
X560577Y10156D01*
X560467Y10096D01*
X560367Y10016D01*
X560287Y9916D01*
X560227Y9806D01*
X560187Y9681D01*
X560177Y9556D01*
Y7431D01*
X560147Y7401D01*
X560122Y7366D01*
X560092Y7331D01*
X560072Y7296D01*
X560047Y7261D01*
X560007Y7181D01*
X559962Y7061D01*
X559952Y7021D01*
X559942Y6976D01*
X559937Y6936D01*
X559927Y6891D01*
Y6721D01*
X559937Y6676D01*
X559942Y6636D01*
X559952Y6591D01*
X559962Y6551D01*
X560007Y6431D01*
X560047Y6351D01*
X560072Y6316D01*
X560092Y6281D01*
X560122Y6246D01*
X560147Y6211D01*
X560177Y6181D01*
Y3756D01*
X560187Y3631D01*
X560227Y3506D01*
X560287Y3396D01*
X560367Y3296D01*
X560467Y3216D01*
X560577Y3156D01*
X560702Y3116D01*
X560827Y3106D01*
G37*
G36*
G01X584449D02*
X584574Y3116D01*
X584699Y3156D01*
X584809Y3216D01*
X584909Y3296D01*
X584989Y3396D01*
X585049Y3506D01*
X585089Y3631D01*
X585099Y3756D01*
Y6186D01*
X585129Y6216D01*
X585229Y6356D01*
X585249Y6396D01*
X585264Y6431D01*
X585284Y6471D01*
X585299Y6511D01*
X585309Y6551D01*
X585324Y6596D01*
X585329Y6636D01*
X585339Y6676D01*
X585344Y6721D01*
Y6761D01*
X585349Y6806D01*
X585344Y6851D01*
Y6891D01*
X585339Y6936D01*
X585329Y6976D01*
X585324Y7016D01*
X585309Y7061D01*
X585299Y7101D01*
X585284Y7141D01*
X585264Y7181D01*
X585249Y7216D01*
X585229Y7256D01*
X585129Y7396D01*
X585099Y7426D01*
Y9556D01*
X585089Y9681D01*
X585049Y9806D01*
X584989Y9916D01*
X584909Y10016D01*
X584809Y10096D01*
X584699Y10156D01*
X584574Y10196D01*
X584449Y10206D01*
X584324Y10196D01*
X584199Y10156D01*
X584089Y10096D01*
X583989Y10016D01*
X583909Y9916D01*
X583849Y9806D01*
X583809Y9681D01*
X583799Y9556D01*
Y7431D01*
X583769Y7401D01*
X583744Y7366D01*
X583714Y7331D01*
X583694Y7296D01*
X583669Y7261D01*
X583629Y7181D01*
X583584Y7061D01*
X583574Y7021D01*
X583564Y6976D01*
X583559Y6936D01*
X583549Y6891D01*
Y6721D01*
X583559Y6676D01*
X583564Y6636D01*
X583574Y6591D01*
X583584Y6551D01*
X583629Y6431D01*
X583669Y6351D01*
X583694Y6316D01*
X583714Y6281D01*
X583744Y6246D01*
X583769Y6211D01*
X583799Y6181D01*
Y3756D01*
X583809Y3631D01*
X583849Y3506D01*
X583909Y3396D01*
X583989Y3296D01*
X584089Y3216D01*
X584199Y3156D01*
X584324Y3116D01*
X584449Y3106D01*
G37*
G36*
G01X579724D02*
X579849Y3116D01*
X579974Y3156D01*
X580084Y3216D01*
X580184Y3296D01*
X580264Y3396D01*
X580324Y3506D01*
X580364Y3631D01*
X580374Y3756D01*
Y6186D01*
X580404Y6216D01*
X580504Y6356D01*
X580524Y6396D01*
X580539Y6431D01*
X580559Y6471D01*
X580574Y6511D01*
X580584Y6551D01*
X580599Y6596D01*
X580604Y6636D01*
X580614Y6676D01*
X580619Y6721D01*
Y6761D01*
X580624Y6806D01*
X580619Y6851D01*
Y6891D01*
X580614Y6936D01*
X580604Y6976D01*
X580599Y7016D01*
X580584Y7061D01*
X580574Y7101D01*
X580559Y7141D01*
X580539Y7181D01*
X580524Y7216D01*
X580504Y7256D01*
X580404Y7396D01*
X580374Y7426D01*
Y9556D01*
X580364Y9681D01*
X580324Y9806D01*
X580264Y9916D01*
X580184Y10016D01*
X580084Y10096D01*
X579974Y10156D01*
X579849Y10196D01*
X579724Y10206D01*
X579599Y10196D01*
X579474Y10156D01*
X579364Y10096D01*
X579264Y10016D01*
X579184Y9916D01*
X579124Y9806D01*
X579084Y9681D01*
X579074Y9556D01*
Y7431D01*
X579044Y7401D01*
X579019Y7366D01*
X578989Y7331D01*
X578969Y7296D01*
X578944Y7261D01*
X578904Y7181D01*
X578859Y7061D01*
X578849Y7021D01*
X578839Y6976D01*
X578834Y6936D01*
X578824Y6891D01*
Y6721D01*
X578834Y6676D01*
X578839Y6636D01*
X578849Y6591D01*
X578859Y6551D01*
X578904Y6431D01*
X578944Y6351D01*
X578969Y6316D01*
X578989Y6281D01*
X579019Y6246D01*
X579044Y6211D01*
X579074Y6181D01*
Y3756D01*
X579084Y3631D01*
X579124Y3506D01*
X579184Y3396D01*
X579264Y3296D01*
X579364Y3216D01*
X579474Y3156D01*
X579599Y3116D01*
X579724Y3106D01*
G37*
G36*
G01X575000D02*
X575125Y3116D01*
X575250Y3156D01*
X575360Y3216D01*
X575460Y3296D01*
X575540Y3396D01*
X575600Y3506D01*
X575640Y3631D01*
X575650Y3756D01*
Y6186D01*
X575680Y6216D01*
X575780Y6356D01*
X575800Y6396D01*
X575815Y6431D01*
X575835Y6471D01*
X575850Y6511D01*
X575860Y6551D01*
X575875Y6596D01*
X575880Y6636D01*
X575890Y6676D01*
X575895Y6721D01*
Y6761D01*
X575900Y6806D01*
X575895Y6851D01*
Y6891D01*
X575890Y6936D01*
X575880Y6976D01*
X575875Y7016D01*
X575860Y7061D01*
X575850Y7101D01*
X575835Y7141D01*
X575815Y7181D01*
X575800Y7216D01*
X575780Y7256D01*
X575680Y7396D01*
X575650Y7426D01*
Y9556D01*
X575640Y9681D01*
X575600Y9806D01*
X575540Y9916D01*
X575460Y10016D01*
X575360Y10096D01*
X575250Y10156D01*
X575125Y10196D01*
X575000Y10206D01*
X574875Y10196D01*
X574750Y10156D01*
X574640Y10096D01*
X574540Y10016D01*
X574460Y9916D01*
X574400Y9806D01*
X574360Y9681D01*
X574350Y9556D01*
Y7431D01*
X574320Y7401D01*
X574295Y7366D01*
X574265Y7331D01*
X574245Y7296D01*
X574220Y7261D01*
X574180Y7181D01*
X574135Y7061D01*
X574125Y7021D01*
X574115Y6976D01*
X574110Y6936D01*
X574100Y6891D01*
Y6721D01*
X574110Y6676D01*
X574115Y6636D01*
X574125Y6591D01*
X574135Y6551D01*
X574180Y6431D01*
X574220Y6351D01*
X574245Y6316D01*
X574265Y6281D01*
X574295Y6246D01*
X574320Y6211D01*
X574350Y6181D01*
Y3756D01*
X574360Y3631D01*
X574400Y3506D01*
X574460Y3396D01*
X574540Y3296D01*
X574640Y3216D01*
X574750Y3156D01*
X574875Y3116D01*
X575000Y3106D01*
G37*
G36*
G01X603346D02*
X603471Y3116D01*
X603596Y3156D01*
X603706Y3216D01*
X603806Y3296D01*
X603886Y3396D01*
X603946Y3506D01*
X603986Y3631D01*
X603996Y3756D01*
Y6186D01*
X604026Y6216D01*
X604126Y6356D01*
X604146Y6396D01*
X604161Y6431D01*
X604181Y6471D01*
X604196Y6511D01*
X604206Y6551D01*
X604221Y6596D01*
X604226Y6636D01*
X604236Y6676D01*
X604241Y6721D01*
Y6761D01*
X604246Y6806D01*
X604241Y6851D01*
Y6891D01*
X604236Y6936D01*
X604226Y6976D01*
X604221Y7016D01*
X604206Y7061D01*
X604196Y7101D01*
X604181Y7141D01*
X604161Y7181D01*
X604146Y7216D01*
X604126Y7256D01*
X604026Y7396D01*
X603996Y7426D01*
Y9556D01*
X603986Y9681D01*
X603946Y9806D01*
X603886Y9916D01*
X603806Y10016D01*
X603706Y10096D01*
X603596Y10156D01*
X603471Y10196D01*
X603346Y10206D01*
X603221Y10196D01*
X603096Y10156D01*
X602986Y10096D01*
X602886Y10016D01*
X602806Y9916D01*
X602746Y9806D01*
X602706Y9681D01*
X602696Y9556D01*
Y7431D01*
X602666Y7401D01*
X602641Y7366D01*
X602611Y7331D01*
X602591Y7296D01*
X602566Y7261D01*
X602526Y7181D01*
X602481Y7061D01*
X602471Y7021D01*
X602461Y6976D01*
X602456Y6936D01*
X602446Y6891D01*
Y6721D01*
X602456Y6676D01*
X602461Y6636D01*
X602471Y6591D01*
X602481Y6551D01*
X602526Y6431D01*
X602566Y6351D01*
X602591Y6316D01*
X602611Y6281D01*
X602641Y6246D01*
X602666Y6211D01*
X602696Y6181D01*
Y3756D01*
X602706Y3631D01*
X602746Y3506D01*
X602806Y3396D01*
X602886Y3296D01*
X602986Y3216D01*
X603096Y3156D01*
X603221Y3116D01*
X603346Y3106D01*
G37*
G36*
G01X589173D02*
X589298Y3116D01*
X589423Y3156D01*
X589533Y3216D01*
X589633Y3296D01*
X589713Y3396D01*
X589773Y3506D01*
X589813Y3631D01*
X589823Y3756D01*
Y6186D01*
X589853Y6216D01*
X589953Y6356D01*
X589973Y6396D01*
X589988Y6431D01*
X590008Y6471D01*
X590023Y6511D01*
X590033Y6551D01*
X590048Y6596D01*
X590053Y6636D01*
X590063Y6676D01*
X590068Y6721D01*
Y6761D01*
X590073Y6806D01*
X590068Y6851D01*
Y6891D01*
X590063Y6936D01*
X590053Y6976D01*
X590048Y7016D01*
X590033Y7061D01*
X590023Y7101D01*
X590008Y7141D01*
X589988Y7181D01*
X589973Y7216D01*
X589953Y7256D01*
X589853Y7396D01*
X589823Y7426D01*
Y9556D01*
X589813Y9681D01*
X589773Y9806D01*
X589713Y9916D01*
X589633Y10016D01*
X589533Y10096D01*
X589423Y10156D01*
X589298Y10196D01*
X589173Y10206D01*
X589048Y10196D01*
X588923Y10156D01*
X588813Y10096D01*
X588713Y10016D01*
X588633Y9916D01*
X588573Y9806D01*
X588533Y9681D01*
X588523Y9556D01*
Y7431D01*
X588493Y7401D01*
X588468Y7366D01*
X588438Y7331D01*
X588418Y7296D01*
X588393Y7261D01*
X588353Y7181D01*
X588308Y7061D01*
X588298Y7021D01*
X588288Y6976D01*
X588283Y6936D01*
X588273Y6891D01*
Y6721D01*
X588283Y6676D01*
X588288Y6636D01*
X588298Y6591D01*
X588308Y6551D01*
X588353Y6431D01*
X588393Y6351D01*
X588418Y6316D01*
X588438Y6281D01*
X588468Y6246D01*
X588493Y6211D01*
X588523Y6181D01*
Y3756D01*
X588533Y3631D01*
X588573Y3506D01*
X588633Y3396D01*
X588713Y3296D01*
X588813Y3216D01*
X588923Y3156D01*
X589048Y3116D01*
X589173Y3106D01*
G37*
G36*
G01X617519D02*
X617644Y3116D01*
X617769Y3156D01*
X617879Y3216D01*
X617979Y3296D01*
X618059Y3396D01*
X618119Y3506D01*
X618159Y3631D01*
X618169Y3756D01*
Y6186D01*
X618199Y6216D01*
X618299Y6356D01*
X618319Y6396D01*
X618334Y6431D01*
X618354Y6471D01*
X618369Y6511D01*
X618379Y6551D01*
X618394Y6596D01*
X618399Y6636D01*
X618409Y6676D01*
X618414Y6721D01*
Y6761D01*
X618419Y6806D01*
X618414Y6851D01*
Y6891D01*
X618409Y6936D01*
X618399Y6976D01*
X618394Y7016D01*
X618379Y7061D01*
X618369Y7101D01*
X618354Y7141D01*
X618334Y7181D01*
X618319Y7216D01*
X618299Y7256D01*
X618199Y7396D01*
X618169Y7426D01*
Y9556D01*
X618159Y9681D01*
X618119Y9806D01*
X618059Y9916D01*
X617979Y10016D01*
X617879Y10096D01*
X617769Y10156D01*
X617644Y10196D01*
X617519Y10206D01*
X617394Y10196D01*
X617269Y10156D01*
X617159Y10096D01*
X617059Y10016D01*
X616979Y9916D01*
X616919Y9806D01*
X616879Y9681D01*
X616869Y9556D01*
Y7431D01*
X616839Y7401D01*
X616814Y7366D01*
X616784Y7331D01*
X616764Y7296D01*
X616739Y7261D01*
X616699Y7181D01*
X616654Y7061D01*
X616644Y7021D01*
X616634Y6976D01*
X616629Y6936D01*
X616619Y6891D01*
Y6721D01*
X616629Y6676D01*
X616634Y6636D01*
X616644Y6591D01*
X616654Y6551D01*
X616699Y6431D01*
X616739Y6351D01*
X616764Y6316D01*
X616784Y6281D01*
X616814Y6246D01*
X616839Y6211D01*
X616869Y6181D01*
Y3756D01*
X616879Y3631D01*
X616919Y3506D01*
X616979Y3396D01*
X617059Y3296D01*
X617159Y3216D01*
X617269Y3156D01*
X617394Y3116D01*
X617519Y3106D01*
G37*
G36*
G01X612795D02*
X612920Y3116D01*
X613045Y3156D01*
X613155Y3216D01*
X613255Y3296D01*
X613335Y3396D01*
X613395Y3506D01*
X613435Y3631D01*
X613445Y3756D01*
Y6186D01*
X613475Y6216D01*
X613575Y6356D01*
X613595Y6396D01*
X613610Y6431D01*
X613630Y6471D01*
X613645Y6511D01*
X613655Y6551D01*
X613670Y6596D01*
X613675Y6636D01*
X613685Y6676D01*
X613690Y6721D01*
Y6761D01*
X613695Y6806D01*
X613690Y6851D01*
Y6891D01*
X613685Y6936D01*
X613675Y6976D01*
X613670Y7016D01*
X613655Y7061D01*
X613645Y7101D01*
X613630Y7141D01*
X613610Y7181D01*
X613595Y7216D01*
X613575Y7256D01*
X613475Y7396D01*
X613445Y7426D01*
Y9556D01*
X613435Y9681D01*
X613395Y9806D01*
X613335Y9916D01*
X613255Y10016D01*
X613155Y10096D01*
X613045Y10156D01*
X612920Y10196D01*
X612795Y10206D01*
X612670Y10196D01*
X612545Y10156D01*
X612435Y10096D01*
X612335Y10016D01*
X612255Y9916D01*
X612195Y9806D01*
X612155Y9681D01*
X612145Y9556D01*
Y7431D01*
X612115Y7401D01*
X612090Y7366D01*
X612060Y7331D01*
X612040Y7296D01*
X612015Y7261D01*
X611975Y7181D01*
X611930Y7061D01*
X611920Y7021D01*
X611910Y6976D01*
X611905Y6936D01*
X611895Y6891D01*
Y6721D01*
X611905Y6676D01*
X611910Y6636D01*
X611920Y6591D01*
X611930Y6551D01*
X611975Y6431D01*
X612015Y6351D01*
X612040Y6316D01*
X612060Y6281D01*
X612090Y6246D01*
X612115Y6211D01*
X612145Y6181D01*
Y3756D01*
X612155Y3631D01*
X612195Y3506D01*
X612255Y3396D01*
X612335Y3296D01*
X612435Y3216D01*
X612545Y3156D01*
X612670Y3116D01*
X612795Y3106D01*
G37*
G36*
G01X608071D02*
X608196Y3116D01*
X608321Y3156D01*
X608431Y3216D01*
X608531Y3296D01*
X608611Y3396D01*
X608671Y3506D01*
X608711Y3631D01*
X608721Y3756D01*
Y6186D01*
X608751Y6216D01*
X608851Y6356D01*
X608871Y6396D01*
X608886Y6431D01*
X608906Y6471D01*
X608921Y6511D01*
X608931Y6551D01*
X608946Y6596D01*
X608951Y6636D01*
X608961Y6676D01*
X608966Y6721D01*
Y6761D01*
X608971Y6806D01*
X608966Y6851D01*
Y6891D01*
X608961Y6936D01*
X608951Y6976D01*
X608946Y7016D01*
X608931Y7061D01*
X608921Y7101D01*
X608906Y7141D01*
X608886Y7181D01*
X608871Y7216D01*
X608851Y7256D01*
X608751Y7396D01*
X608721Y7426D01*
Y9556D01*
X608711Y9681D01*
X608671Y9806D01*
X608611Y9916D01*
X608531Y10016D01*
X608431Y10096D01*
X608321Y10156D01*
X608196Y10196D01*
X608071Y10206D01*
X607946Y10196D01*
X607821Y10156D01*
X607711Y10096D01*
X607611Y10016D01*
X607531Y9916D01*
X607471Y9806D01*
X607431Y9681D01*
X607421Y9556D01*
Y7431D01*
X607391Y7401D01*
X607366Y7366D01*
X607336Y7331D01*
X607316Y7296D01*
X607291Y7261D01*
X607251Y7181D01*
X607206Y7061D01*
X607196Y7021D01*
X607186Y6976D01*
X607181Y6936D01*
X607171Y6891D01*
Y6721D01*
X607181Y6676D01*
X607186Y6636D01*
X607196Y6591D01*
X607206Y6551D01*
X607251Y6431D01*
X607291Y6351D01*
X607316Y6316D01*
X607336Y6281D01*
X607366Y6246D01*
X607391Y6211D01*
X607421Y6181D01*
Y3756D01*
X607431Y3631D01*
X607471Y3506D01*
X607531Y3396D01*
X607611Y3296D01*
X607711Y3216D01*
X607821Y3156D01*
X607946Y3116D01*
X608071Y3106D01*
G37*
G36*
G01X631693D02*
X631818Y3116D01*
X631943Y3156D01*
X632053Y3216D01*
X632153Y3296D01*
X632233Y3396D01*
X632293Y3506D01*
X632333Y3631D01*
X632343Y3756D01*
Y6186D01*
X632373Y6216D01*
X632473Y6356D01*
X632493Y6396D01*
X632508Y6431D01*
X632528Y6471D01*
X632543Y6511D01*
X632553Y6551D01*
X632568Y6596D01*
X632573Y6636D01*
X632583Y6676D01*
X632588Y6721D01*
Y6761D01*
X632593Y6806D01*
X632588Y6851D01*
Y6891D01*
X632583Y6936D01*
X632573Y6976D01*
X632568Y7016D01*
X632553Y7061D01*
X632543Y7101D01*
X632528Y7141D01*
X632508Y7181D01*
X632493Y7216D01*
X632473Y7256D01*
X632373Y7396D01*
X632343Y7426D01*
Y9556D01*
X632333Y9681D01*
X632293Y9806D01*
X632233Y9916D01*
X632153Y10016D01*
X632053Y10096D01*
X631943Y10156D01*
X631818Y10196D01*
X631693Y10206D01*
X631568Y10196D01*
X631443Y10156D01*
X631333Y10096D01*
X631233Y10016D01*
X631153Y9916D01*
X631093Y9806D01*
X631053Y9681D01*
X631043Y9556D01*
Y7431D01*
X631013Y7401D01*
X630988Y7366D01*
X630958Y7331D01*
X630938Y7296D01*
X630913Y7261D01*
X630873Y7181D01*
X630828Y7061D01*
X630818Y7021D01*
X630808Y6976D01*
X630803Y6936D01*
X630793Y6891D01*
Y6721D01*
X630803Y6676D01*
X630808Y6636D01*
X630818Y6591D01*
X630828Y6551D01*
X630873Y6431D01*
X630913Y6351D01*
X630938Y6316D01*
X630958Y6281D01*
X630988Y6246D01*
X631013Y6211D01*
X631043Y6181D01*
Y3756D01*
X631053Y3631D01*
X631093Y3506D01*
X631153Y3396D01*
X631233Y3296D01*
X631333Y3216D01*
X631443Y3156D01*
X631568Y3116D01*
X631693Y3106D01*
G37*
G36*
G01X626968D02*
X627093Y3116D01*
X627218Y3156D01*
X627328Y3216D01*
X627428Y3296D01*
X627508Y3396D01*
X627568Y3506D01*
X627608Y3631D01*
X627618Y3756D01*
Y6186D01*
X627648Y6216D01*
X627748Y6356D01*
X627768Y6396D01*
X627783Y6431D01*
X627803Y6471D01*
X627818Y6511D01*
X627828Y6551D01*
X627843Y6596D01*
X627848Y6636D01*
X627858Y6676D01*
X627863Y6721D01*
Y6761D01*
X627868Y6806D01*
X627863Y6851D01*
Y6891D01*
X627858Y6936D01*
X627848Y6976D01*
X627843Y7016D01*
X627828Y7061D01*
X627818Y7101D01*
X627803Y7141D01*
X627783Y7181D01*
X627768Y7216D01*
X627748Y7256D01*
X627648Y7396D01*
X627618Y7426D01*
Y9556D01*
X627608Y9681D01*
X627568Y9806D01*
X627508Y9916D01*
X627428Y10016D01*
X627328Y10096D01*
X627218Y10156D01*
X627093Y10196D01*
X626968Y10206D01*
X626843Y10196D01*
X626718Y10156D01*
X626608Y10096D01*
X626508Y10016D01*
X626428Y9916D01*
X626368Y9806D01*
X626328Y9681D01*
X626318Y9556D01*
Y7431D01*
X626288Y7401D01*
X626263Y7366D01*
X626233Y7331D01*
X626213Y7296D01*
X626188Y7261D01*
X626148Y7181D01*
X626103Y7061D01*
X626093Y7021D01*
X626083Y6976D01*
X626078Y6936D01*
X626068Y6891D01*
Y6721D01*
X626078Y6676D01*
X626083Y6636D01*
X626093Y6591D01*
X626103Y6551D01*
X626148Y6431D01*
X626188Y6351D01*
X626213Y6316D01*
X626233Y6281D01*
X626263Y6246D01*
X626288Y6211D01*
X626318Y6181D01*
Y3756D01*
X626328Y3631D01*
X626368Y3506D01*
X626428Y3396D01*
X626508Y3296D01*
X626608Y3216D01*
X626718Y3156D01*
X626843Y3116D01*
X626968Y3106D01*
G37*
G36*
G01X622244D02*
X622369Y3116D01*
X622494Y3156D01*
X622604Y3216D01*
X622704Y3296D01*
X622784Y3396D01*
X622844Y3506D01*
X622884Y3631D01*
X622894Y3756D01*
Y6186D01*
X622924Y6216D01*
X623024Y6356D01*
X623044Y6396D01*
X623059Y6431D01*
X623079Y6471D01*
X623094Y6511D01*
X623104Y6551D01*
X623119Y6596D01*
X623124Y6636D01*
X623134Y6676D01*
X623139Y6721D01*
Y6761D01*
X623144Y6806D01*
X623139Y6851D01*
Y6891D01*
X623134Y6936D01*
X623124Y6976D01*
X623119Y7016D01*
X623104Y7061D01*
X623094Y7101D01*
X623079Y7141D01*
X623059Y7181D01*
X623044Y7216D01*
X623024Y7256D01*
X622924Y7396D01*
X622894Y7426D01*
Y9556D01*
X622884Y9681D01*
X622844Y9806D01*
X622784Y9916D01*
X622704Y10016D01*
X622604Y10096D01*
X622494Y10156D01*
X622369Y10196D01*
X622244Y10206D01*
X622119Y10196D01*
X621994Y10156D01*
X621884Y10096D01*
X621784Y10016D01*
X621704Y9916D01*
X621644Y9806D01*
X621604Y9681D01*
X621594Y9556D01*
Y7431D01*
X621564Y7401D01*
X621539Y7366D01*
X621509Y7331D01*
X621489Y7296D01*
X621464Y7261D01*
X621424Y7181D01*
X621379Y7061D01*
X621369Y7021D01*
X621359Y6976D01*
X621354Y6936D01*
X621344Y6891D01*
Y6721D01*
X621354Y6676D01*
X621359Y6636D01*
X621369Y6591D01*
X621379Y6551D01*
X621424Y6431D01*
X621464Y6351D01*
X621489Y6316D01*
X621509Y6281D01*
X621539Y6246D01*
X621564Y6211D01*
X621594Y6181D01*
Y3756D01*
X621604Y3631D01*
X621644Y3506D01*
X621704Y3396D01*
X621784Y3296D01*
X621884Y3216D01*
X621994Y3156D01*
X622119Y3116D01*
X622244Y3106D01*
G37*
G36*
G01X645866D02*
X645991Y3116D01*
X646116Y3156D01*
X646226Y3216D01*
X646326Y3296D01*
X646406Y3396D01*
X646466Y3506D01*
X646506Y3631D01*
X646516Y3756D01*
Y6186D01*
X646546Y6216D01*
X646646Y6356D01*
X646666Y6396D01*
X646681Y6431D01*
X646701Y6471D01*
X646716Y6511D01*
X646726Y6551D01*
X646741Y6596D01*
X646746Y6636D01*
X646756Y6676D01*
X646761Y6721D01*
Y6761D01*
X646766Y6806D01*
X646761Y6851D01*
Y6891D01*
X646756Y6936D01*
X646746Y6976D01*
X646741Y7016D01*
X646726Y7061D01*
X646716Y7101D01*
X646701Y7141D01*
X646681Y7181D01*
X646666Y7216D01*
X646646Y7256D01*
X646546Y7396D01*
X646516Y7426D01*
Y9556D01*
X646506Y9681D01*
X646466Y9806D01*
X646406Y9916D01*
X646326Y10016D01*
X646226Y10096D01*
X646116Y10156D01*
X645991Y10196D01*
X645866Y10206D01*
X645741Y10196D01*
X645616Y10156D01*
X645506Y10096D01*
X645406Y10016D01*
X645326Y9916D01*
X645266Y9806D01*
X645226Y9681D01*
X645216Y9556D01*
Y7431D01*
X645186Y7401D01*
X645161Y7366D01*
X645131Y7331D01*
X645111Y7296D01*
X645086Y7261D01*
X645046Y7181D01*
X645001Y7061D01*
X644991Y7021D01*
X644981Y6976D01*
X644976Y6936D01*
X644966Y6891D01*
Y6721D01*
X644976Y6676D01*
X644981Y6636D01*
X644991Y6591D01*
X645001Y6551D01*
X645046Y6431D01*
X645086Y6351D01*
X645111Y6316D01*
X645131Y6281D01*
X645161Y6246D01*
X645186Y6211D01*
X645216Y6181D01*
Y3756D01*
X645226Y3631D01*
X645266Y3506D01*
X645326Y3396D01*
X645406Y3296D01*
X645506Y3216D01*
X645616Y3156D01*
X645741Y3116D01*
X645866Y3106D01*
G37*
G36*
G01X641141D02*
X641266Y3116D01*
X641391Y3156D01*
X641501Y3216D01*
X641601Y3296D01*
X641681Y3396D01*
X641741Y3506D01*
X641781Y3631D01*
X641791Y3756D01*
Y6186D01*
X641821Y6216D01*
X641921Y6356D01*
X641941Y6396D01*
X641956Y6431D01*
X641976Y6471D01*
X641991Y6511D01*
X642001Y6551D01*
X642016Y6596D01*
X642021Y6636D01*
X642031Y6676D01*
X642036Y6721D01*
Y6761D01*
X642041Y6806D01*
X642036Y6851D01*
Y6891D01*
X642031Y6936D01*
X642021Y6976D01*
X642016Y7016D01*
X642001Y7061D01*
X641991Y7101D01*
X641976Y7141D01*
X641956Y7181D01*
X641941Y7216D01*
X641921Y7256D01*
X641821Y7396D01*
X641791Y7426D01*
Y9556D01*
X641781Y9681D01*
X641741Y9806D01*
X641681Y9916D01*
X641601Y10016D01*
X641501Y10096D01*
X641391Y10156D01*
X641266Y10196D01*
X641141Y10206D01*
X641016Y10196D01*
X640891Y10156D01*
X640781Y10096D01*
X640681Y10016D01*
X640601Y9916D01*
X640541Y9806D01*
X640501Y9681D01*
X640491Y9556D01*
Y7431D01*
X640461Y7401D01*
X640436Y7366D01*
X640406Y7331D01*
X640386Y7296D01*
X640361Y7261D01*
X640321Y7181D01*
X640276Y7061D01*
X640266Y7021D01*
X640256Y6976D01*
X640251Y6936D01*
X640241Y6891D01*
Y6721D01*
X640251Y6676D01*
X640256Y6636D01*
X640266Y6591D01*
X640276Y6551D01*
X640321Y6431D01*
X640361Y6351D01*
X640386Y6316D01*
X640406Y6281D01*
X640436Y6246D01*
X640461Y6211D01*
X640491Y6181D01*
Y3756D01*
X640501Y3631D01*
X640541Y3506D01*
X640601Y3396D01*
X640681Y3296D01*
X640781Y3216D01*
X640891Y3156D01*
X641016Y3116D01*
X641141Y3106D01*
G37*
G36*
G01X636417D02*
X636542Y3116D01*
X636667Y3156D01*
X636777Y3216D01*
X636877Y3296D01*
X636957Y3396D01*
X637017Y3506D01*
X637057Y3631D01*
X637067Y3756D01*
Y6186D01*
X637097Y6216D01*
X637197Y6356D01*
X637217Y6396D01*
X637232Y6431D01*
X637252Y6471D01*
X637267Y6511D01*
X637277Y6551D01*
X637292Y6596D01*
X637297Y6636D01*
X637307Y6676D01*
X637312Y6721D01*
Y6761D01*
X637317Y6806D01*
X637312Y6851D01*
Y6891D01*
X637307Y6936D01*
X637297Y6976D01*
X637292Y7016D01*
X637277Y7061D01*
X637267Y7101D01*
X637252Y7141D01*
X637232Y7181D01*
X637217Y7216D01*
X637197Y7256D01*
X637097Y7396D01*
X637067Y7426D01*
Y9556D01*
X637057Y9681D01*
X637017Y9806D01*
X636957Y9916D01*
X636877Y10016D01*
X636777Y10096D01*
X636667Y10156D01*
X636542Y10196D01*
X636417Y10206D01*
X636292Y10196D01*
X636167Y10156D01*
X636057Y10096D01*
X635957Y10016D01*
X635877Y9916D01*
X635817Y9806D01*
X635777Y9681D01*
X635767Y9556D01*
Y7431D01*
X635737Y7401D01*
X635712Y7366D01*
X635682Y7331D01*
X635662Y7296D01*
X635637Y7261D01*
X635597Y7181D01*
X635552Y7061D01*
X635542Y7021D01*
X635532Y6976D01*
X635527Y6936D01*
X635517Y6891D01*
Y6721D01*
X635527Y6676D01*
X635532Y6636D01*
X635542Y6591D01*
X635552Y6551D01*
X635597Y6431D01*
X635637Y6351D01*
X635662Y6316D01*
X635682Y6281D01*
X635712Y6246D01*
X635737Y6211D01*
X635767Y6181D01*
Y3756D01*
X635777Y3631D01*
X635817Y3506D01*
X635877Y3396D01*
X635957Y3296D01*
X636057Y3216D01*
X636167Y3156D01*
X636292Y3116D01*
X636417Y3106D01*
G37*
G36*
G01X664764D02*
X664889Y3116D01*
X665014Y3156D01*
X665124Y3216D01*
X665224Y3296D01*
X665304Y3396D01*
X665364Y3506D01*
X665404Y3631D01*
X665414Y3756D01*
Y6186D01*
X665444Y6216D01*
X665544Y6356D01*
X665564Y6396D01*
X665579Y6431D01*
X665599Y6471D01*
X665614Y6511D01*
X665624Y6551D01*
X665639Y6596D01*
X665644Y6636D01*
X665654Y6676D01*
X665659Y6721D01*
Y6761D01*
X665664Y6806D01*
X665659Y6851D01*
Y6891D01*
X665654Y6936D01*
X665644Y6976D01*
X665639Y7016D01*
X665624Y7061D01*
X665614Y7101D01*
X665599Y7141D01*
X665579Y7181D01*
X665564Y7216D01*
X665544Y7256D01*
X665444Y7396D01*
X665414Y7426D01*
Y9556D01*
X665404Y9681D01*
X665364Y9806D01*
X665304Y9916D01*
X665224Y10016D01*
X665124Y10096D01*
X665014Y10156D01*
X664889Y10196D01*
X664764Y10206D01*
X664639Y10196D01*
X664514Y10156D01*
X664404Y10096D01*
X664304Y10016D01*
X664224Y9916D01*
X664164Y9806D01*
X664124Y9681D01*
X664114Y9556D01*
Y7431D01*
X664084Y7401D01*
X664059Y7366D01*
X664029Y7331D01*
X664009Y7296D01*
X663984Y7261D01*
X663944Y7181D01*
X663899Y7061D01*
X663889Y7021D01*
X663879Y6976D01*
X663874Y6936D01*
X663864Y6891D01*
Y6721D01*
X663874Y6676D01*
X663879Y6636D01*
X663889Y6591D01*
X663899Y6551D01*
X663944Y6431D01*
X663984Y6351D01*
X664009Y6316D01*
X664029Y6281D01*
X664059Y6246D01*
X664084Y6211D01*
X664114Y6181D01*
Y3756D01*
X664124Y3631D01*
X664164Y3506D01*
X664224Y3396D01*
X664304Y3296D01*
X664404Y3216D01*
X664514Y3156D01*
X664639Y3116D01*
X664764Y3106D01*
G37*
G36*
G01X660039D02*
X660164Y3116D01*
X660289Y3156D01*
X660399Y3216D01*
X660499Y3296D01*
X660579Y3396D01*
X660639Y3506D01*
X660679Y3631D01*
X660689Y3756D01*
Y6186D01*
X660719Y6216D01*
X660819Y6356D01*
X660839Y6396D01*
X660854Y6431D01*
X660874Y6471D01*
X660889Y6511D01*
X660899Y6551D01*
X660914Y6596D01*
X660919Y6636D01*
X660929Y6676D01*
X660934Y6721D01*
Y6761D01*
X660939Y6806D01*
X660934Y6851D01*
Y6891D01*
X660929Y6936D01*
X660919Y6976D01*
X660914Y7016D01*
X660899Y7061D01*
X660889Y7101D01*
X660874Y7141D01*
X660854Y7181D01*
X660839Y7216D01*
X660819Y7256D01*
X660719Y7396D01*
X660689Y7426D01*
Y9556D01*
X660679Y9681D01*
X660639Y9806D01*
X660579Y9916D01*
X660499Y10016D01*
X660399Y10096D01*
X660289Y10156D01*
X660164Y10196D01*
X660039Y10206D01*
X659914Y10196D01*
X659789Y10156D01*
X659679Y10096D01*
X659579Y10016D01*
X659499Y9916D01*
X659439Y9806D01*
X659399Y9681D01*
X659389Y9556D01*
Y7431D01*
X659359Y7401D01*
X659334Y7366D01*
X659304Y7331D01*
X659284Y7296D01*
X659259Y7261D01*
X659219Y7181D01*
X659174Y7061D01*
X659164Y7021D01*
X659154Y6976D01*
X659149Y6936D01*
X659139Y6891D01*
Y6721D01*
X659149Y6676D01*
X659154Y6636D01*
X659164Y6591D01*
X659174Y6551D01*
X659219Y6431D01*
X659259Y6351D01*
X659284Y6316D01*
X659304Y6281D01*
X659334Y6246D01*
X659359Y6211D01*
X659389Y6181D01*
Y3756D01*
X659399Y3631D01*
X659439Y3506D01*
X659499Y3396D01*
X659579Y3296D01*
X659679Y3216D01*
X659789Y3156D01*
X659914Y3116D01*
X660039Y3106D01*
G37*
G36*
G01X655315D02*
X655440Y3116D01*
X655565Y3156D01*
X655675Y3216D01*
X655775Y3296D01*
X655855Y3396D01*
X655915Y3506D01*
X655955Y3631D01*
X655965Y3756D01*
Y6186D01*
X655995Y6216D01*
X656095Y6356D01*
X656115Y6396D01*
X656130Y6431D01*
X656150Y6471D01*
X656165Y6511D01*
X656175Y6551D01*
X656190Y6596D01*
X656195Y6636D01*
X656205Y6676D01*
X656210Y6721D01*
Y6761D01*
X656215Y6806D01*
X656210Y6851D01*
Y6891D01*
X656205Y6936D01*
X656195Y6976D01*
X656190Y7016D01*
X656175Y7061D01*
X656165Y7101D01*
X656150Y7141D01*
X656130Y7181D01*
X656115Y7216D01*
X656095Y7256D01*
X655995Y7396D01*
X655965Y7426D01*
Y9556D01*
X655955Y9681D01*
X655915Y9806D01*
X655855Y9916D01*
X655775Y10016D01*
X655675Y10096D01*
X655565Y10156D01*
X655440Y10196D01*
X655315Y10206D01*
X655190Y10196D01*
X655065Y10156D01*
X654955Y10096D01*
X654855Y10016D01*
X654775Y9916D01*
X654715Y9806D01*
X654675Y9681D01*
X654665Y9556D01*
Y7431D01*
X654635Y7401D01*
X654610Y7366D01*
X654580Y7331D01*
X654560Y7296D01*
X654535Y7261D01*
X654495Y7181D01*
X654450Y7061D01*
X654440Y7021D01*
X654430Y6976D01*
X654425Y6936D01*
X654415Y6891D01*
Y6721D01*
X654425Y6676D01*
X654430Y6636D01*
X654440Y6591D01*
X654450Y6551D01*
X654495Y6431D01*
X654535Y6351D01*
X654560Y6316D01*
X654580Y6281D01*
X654610Y6246D01*
X654635Y6211D01*
X654665Y6181D01*
Y3756D01*
X654675Y3631D01*
X654715Y3506D01*
X654775Y3396D01*
X654855Y3296D01*
X654955Y3216D01*
X655065Y3156D01*
X655190Y3116D01*
X655315Y3106D01*
G37*
G36*
G01X650590D02*
X650715Y3116D01*
X650840Y3156D01*
X650950Y3216D01*
X651050Y3296D01*
X651130Y3396D01*
X651190Y3506D01*
X651230Y3631D01*
X651240Y3756D01*
Y6186D01*
X651270Y6216D01*
X651370Y6356D01*
X651390Y6396D01*
X651405Y6431D01*
X651425Y6471D01*
X651440Y6511D01*
X651450Y6551D01*
X651465Y6596D01*
X651470Y6636D01*
X651480Y6676D01*
X651485Y6721D01*
Y6761D01*
X651490Y6806D01*
X651485Y6851D01*
Y6891D01*
X651480Y6936D01*
X651470Y6976D01*
X651465Y7016D01*
X651450Y7061D01*
X651440Y7101D01*
X651425Y7141D01*
X651405Y7181D01*
X651390Y7216D01*
X651370Y7256D01*
X651270Y7396D01*
X651240Y7426D01*
Y9556D01*
X651230Y9681D01*
X651190Y9806D01*
X651130Y9916D01*
X651050Y10016D01*
X650950Y10096D01*
X650840Y10156D01*
X650715Y10196D01*
X650590Y10206D01*
X650465Y10196D01*
X650340Y10156D01*
X650230Y10096D01*
X650130Y10016D01*
X650050Y9916D01*
X649990Y9806D01*
X649950Y9681D01*
X649940Y9556D01*
Y7431D01*
X649910Y7401D01*
X649885Y7366D01*
X649855Y7331D01*
X649835Y7296D01*
X649810Y7261D01*
X649770Y7181D01*
X649725Y7061D01*
X649715Y7021D01*
X649705Y6976D01*
X649700Y6936D01*
X649690Y6891D01*
Y6721D01*
X649700Y6676D01*
X649705Y6636D01*
X649715Y6591D01*
X649725Y6551D01*
X649770Y6431D01*
X649810Y6351D01*
X649835Y6316D01*
X649855Y6281D01*
X649885Y6246D01*
X649910Y6211D01*
X649940Y6181D01*
Y3756D01*
X649950Y3631D01*
X649990Y3506D01*
X650050Y3396D01*
X650130Y3296D01*
X650230Y3216D01*
X650340Y3156D01*
X650465Y3116D01*
X650590Y3106D01*
G37*
G36*
G01X678937D02*
X679062Y3116D01*
X679187Y3156D01*
X679297Y3216D01*
X679397Y3296D01*
X679477Y3396D01*
X679537Y3506D01*
X679577Y3631D01*
X679587Y3756D01*
Y6186D01*
X679617Y6216D01*
X679717Y6356D01*
X679737Y6396D01*
X679752Y6431D01*
X679772Y6471D01*
X679787Y6511D01*
X679797Y6551D01*
X679812Y6596D01*
X679817Y6636D01*
X679827Y6676D01*
X679832Y6721D01*
Y6761D01*
X679837Y6806D01*
X679832Y6851D01*
Y6891D01*
X679827Y6936D01*
X679817Y6976D01*
X679812Y7016D01*
X679797Y7061D01*
X679787Y7101D01*
X679772Y7141D01*
X679752Y7181D01*
X679737Y7216D01*
X679717Y7256D01*
X679617Y7396D01*
X679587Y7426D01*
Y9556D01*
X679577Y9681D01*
X679537Y9806D01*
X679477Y9916D01*
X679397Y10016D01*
X679297Y10096D01*
X679187Y10156D01*
X679062Y10196D01*
X678937Y10206D01*
X678812Y10196D01*
X678687Y10156D01*
X678577Y10096D01*
X678477Y10016D01*
X678397Y9916D01*
X678337Y9806D01*
X678297Y9681D01*
X678287Y9556D01*
Y7431D01*
X678257Y7401D01*
X678232Y7366D01*
X678202Y7331D01*
X678182Y7296D01*
X678157Y7261D01*
X678117Y7181D01*
X678072Y7061D01*
X678062Y7021D01*
X678052Y6976D01*
X678047Y6936D01*
X678037Y6891D01*
Y6721D01*
X678047Y6676D01*
X678052Y6636D01*
X678062Y6591D01*
X678072Y6551D01*
X678117Y6431D01*
X678157Y6351D01*
X678182Y6316D01*
X678202Y6281D01*
X678232Y6246D01*
X678257Y6211D01*
X678287Y6181D01*
Y3756D01*
X678297Y3631D01*
X678337Y3506D01*
X678397Y3396D01*
X678477Y3296D01*
X678577Y3216D01*
X678687Y3156D01*
X678812Y3116D01*
X678937Y3106D01*
G37*
G36*
G01X674212D02*
X674337Y3116D01*
X674462Y3156D01*
X674572Y3216D01*
X674672Y3296D01*
X674752Y3396D01*
X674812Y3506D01*
X674852Y3631D01*
X674862Y3756D01*
Y6186D01*
X674892Y6216D01*
X674992Y6356D01*
X675012Y6396D01*
X675027Y6431D01*
X675047Y6471D01*
X675062Y6511D01*
X675072Y6551D01*
X675087Y6596D01*
X675092Y6636D01*
X675102Y6676D01*
X675107Y6721D01*
Y6761D01*
X675112Y6806D01*
X675107Y6851D01*
Y6891D01*
X675102Y6936D01*
X675092Y6976D01*
X675087Y7016D01*
X675072Y7061D01*
X675062Y7101D01*
X675047Y7141D01*
X675027Y7181D01*
X675012Y7216D01*
X674992Y7256D01*
X674892Y7396D01*
X674862Y7426D01*
Y9556D01*
X674852Y9681D01*
X674812Y9806D01*
X674752Y9916D01*
X674672Y10016D01*
X674572Y10096D01*
X674462Y10156D01*
X674337Y10196D01*
X674212Y10206D01*
X674087Y10196D01*
X673962Y10156D01*
X673852Y10096D01*
X673752Y10016D01*
X673672Y9916D01*
X673612Y9806D01*
X673572Y9681D01*
X673562Y9556D01*
Y7431D01*
X673532Y7401D01*
X673507Y7366D01*
X673477Y7331D01*
X673457Y7296D01*
X673432Y7261D01*
X673392Y7181D01*
X673347Y7061D01*
X673337Y7021D01*
X673327Y6976D01*
X673322Y6936D01*
X673312Y6891D01*
Y6721D01*
X673322Y6676D01*
X673327Y6636D01*
X673337Y6591D01*
X673347Y6551D01*
X673392Y6431D01*
X673432Y6351D01*
X673457Y6316D01*
X673477Y6281D01*
X673507Y6246D01*
X673532Y6211D01*
X673562Y6181D01*
Y3756D01*
X673572Y3631D01*
X673612Y3506D01*
X673672Y3396D01*
X673752Y3296D01*
X673852Y3216D01*
X673962Y3156D01*
X674087Y3116D01*
X674212Y3106D01*
G37*
G36*
G01X669488D02*
X669613Y3116D01*
X669738Y3156D01*
X669848Y3216D01*
X669948Y3296D01*
X670028Y3396D01*
X670088Y3506D01*
X670128Y3631D01*
X670138Y3756D01*
Y6186D01*
X670168Y6216D01*
X670268Y6356D01*
X670288Y6396D01*
X670303Y6431D01*
X670323Y6471D01*
X670338Y6511D01*
X670348Y6551D01*
X670363Y6596D01*
X670368Y6636D01*
X670378Y6676D01*
X670383Y6721D01*
Y6761D01*
X670388Y6806D01*
X670383Y6851D01*
Y6891D01*
X670378Y6936D01*
X670368Y6976D01*
X670363Y7016D01*
X670348Y7061D01*
X670338Y7101D01*
X670323Y7141D01*
X670303Y7181D01*
X670288Y7216D01*
X670268Y7256D01*
X670168Y7396D01*
X670138Y7426D01*
Y9556D01*
X670128Y9681D01*
X670088Y9806D01*
X670028Y9916D01*
X669948Y10016D01*
X669848Y10096D01*
X669738Y10156D01*
X669613Y10196D01*
X669488Y10206D01*
X669363Y10196D01*
X669238Y10156D01*
X669128Y10096D01*
X669028Y10016D01*
X668948Y9916D01*
X668888Y9806D01*
X668848Y9681D01*
X668838Y9556D01*
Y7431D01*
X668808Y7401D01*
X668783Y7366D01*
X668753Y7331D01*
X668733Y7296D01*
X668708Y7261D01*
X668668Y7181D01*
X668623Y7061D01*
X668613Y7021D01*
X668603Y6976D01*
X668598Y6936D01*
X668588Y6891D01*
Y6721D01*
X668598Y6676D01*
X668603Y6636D01*
X668613Y6591D01*
X668623Y6551D01*
X668668Y6431D01*
X668708Y6351D01*
X668733Y6316D01*
X668753Y6281D01*
X668783Y6246D01*
X668808Y6211D01*
X668838Y6181D01*
Y3756D01*
X668848Y3631D01*
X668888Y3506D01*
X668948Y3396D01*
X669028Y3296D01*
X669128Y3216D01*
X669238Y3156D01*
X669363Y3116D01*
X669488Y3106D01*
G37*
G36*
G01X693110D02*
X693235Y3116D01*
X693360Y3156D01*
X693470Y3216D01*
X693570Y3296D01*
X693650Y3396D01*
X693710Y3506D01*
X693750Y3631D01*
X693760Y3756D01*
Y6186D01*
X693790Y6216D01*
X693890Y6356D01*
X693910Y6396D01*
X693925Y6431D01*
X693945Y6471D01*
X693960Y6511D01*
X693970Y6551D01*
X693985Y6596D01*
X693990Y6636D01*
X694000Y6676D01*
X694005Y6721D01*
Y6761D01*
X694010Y6806D01*
X694005Y6851D01*
Y6891D01*
X694000Y6936D01*
X693990Y6976D01*
X693985Y7016D01*
X693970Y7061D01*
X693960Y7101D01*
X693945Y7141D01*
X693925Y7181D01*
X693910Y7216D01*
X693890Y7256D01*
X693790Y7396D01*
X693760Y7426D01*
Y9556D01*
X693750Y9681D01*
X693710Y9806D01*
X693650Y9916D01*
X693570Y10016D01*
X693470Y10096D01*
X693360Y10156D01*
X693235Y10196D01*
X693110Y10206D01*
X692985Y10196D01*
X692860Y10156D01*
X692750Y10096D01*
X692650Y10016D01*
X692570Y9916D01*
X692510Y9806D01*
X692470Y9681D01*
X692460Y9556D01*
Y7431D01*
X692430Y7401D01*
X692405Y7366D01*
X692375Y7331D01*
X692355Y7296D01*
X692330Y7261D01*
X692290Y7181D01*
X692245Y7061D01*
X692235Y7021D01*
X692225Y6976D01*
X692220Y6936D01*
X692210Y6891D01*
Y6721D01*
X692220Y6676D01*
X692225Y6636D01*
X692235Y6591D01*
X692245Y6551D01*
X692290Y6431D01*
X692330Y6351D01*
X692355Y6316D01*
X692375Y6281D01*
X692405Y6246D01*
X692430Y6211D01*
X692460Y6181D01*
Y3756D01*
X692470Y3631D01*
X692510Y3506D01*
X692570Y3396D01*
X692650Y3296D01*
X692750Y3216D01*
X692860Y3156D01*
X692985Y3116D01*
X693110Y3106D01*
G37*
G36*
G01X688386D02*
X688511Y3116D01*
X688636Y3156D01*
X688746Y3216D01*
X688846Y3296D01*
X688926Y3396D01*
X688986Y3506D01*
X689026Y3631D01*
X689036Y3756D01*
Y6186D01*
X689066Y6216D01*
X689166Y6356D01*
X689186Y6396D01*
X689201Y6431D01*
X689221Y6471D01*
X689236Y6511D01*
X689246Y6551D01*
X689261Y6596D01*
X689266Y6636D01*
X689276Y6676D01*
X689281Y6721D01*
Y6761D01*
X689286Y6806D01*
X689281Y6851D01*
Y6891D01*
X689276Y6936D01*
X689266Y6976D01*
X689261Y7016D01*
X689246Y7061D01*
X689236Y7101D01*
X689221Y7141D01*
X689201Y7181D01*
X689186Y7216D01*
X689166Y7256D01*
X689066Y7396D01*
X689036Y7426D01*
Y9556D01*
X689026Y9681D01*
X688986Y9806D01*
X688926Y9916D01*
X688846Y10016D01*
X688746Y10096D01*
X688636Y10156D01*
X688511Y10196D01*
X688386Y10206D01*
X688261Y10196D01*
X688136Y10156D01*
X688026Y10096D01*
X687926Y10016D01*
X687846Y9916D01*
X687786Y9806D01*
X687746Y9681D01*
X687736Y9556D01*
Y7431D01*
X687706Y7401D01*
X687681Y7366D01*
X687651Y7331D01*
X687631Y7296D01*
X687606Y7261D01*
X687566Y7181D01*
X687521Y7061D01*
X687511Y7021D01*
X687501Y6976D01*
X687496Y6936D01*
X687486Y6891D01*
Y6721D01*
X687496Y6676D01*
X687501Y6636D01*
X687511Y6591D01*
X687521Y6551D01*
X687566Y6431D01*
X687606Y6351D01*
X687631Y6316D01*
X687651Y6281D01*
X687681Y6246D01*
X687706Y6211D01*
X687736Y6181D01*
Y3756D01*
X687746Y3631D01*
X687786Y3506D01*
X687846Y3396D01*
X687926Y3296D01*
X688026Y3216D01*
X688136Y3156D01*
X688261Y3116D01*
X688386Y3106D01*
G37*
G36*
G01X683661D02*
X683786Y3116D01*
X683911Y3156D01*
X684021Y3216D01*
X684121Y3296D01*
X684201Y3396D01*
X684261Y3506D01*
X684301Y3631D01*
X684311Y3756D01*
Y6186D01*
X684341Y6216D01*
X684441Y6356D01*
X684461Y6396D01*
X684476Y6431D01*
X684496Y6471D01*
X684511Y6511D01*
X684521Y6551D01*
X684536Y6596D01*
X684541Y6636D01*
X684551Y6676D01*
X684556Y6721D01*
Y6761D01*
X684561Y6806D01*
X684556Y6851D01*
Y6891D01*
X684551Y6936D01*
X684541Y6976D01*
X684536Y7016D01*
X684521Y7061D01*
X684511Y7101D01*
X684496Y7141D01*
X684476Y7181D01*
X684461Y7216D01*
X684441Y7256D01*
X684341Y7396D01*
X684311Y7426D01*
Y9556D01*
X684301Y9681D01*
X684261Y9806D01*
X684201Y9916D01*
X684121Y10016D01*
X684021Y10096D01*
X683911Y10156D01*
X683786Y10196D01*
X683661Y10206D01*
X683536Y10196D01*
X683411Y10156D01*
X683301Y10096D01*
X683201Y10016D01*
X683121Y9916D01*
X683061Y9806D01*
X683021Y9681D01*
X683011Y9556D01*
Y7431D01*
X682981Y7401D01*
X682956Y7366D01*
X682926Y7331D01*
X682906Y7296D01*
X682881Y7261D01*
X682841Y7181D01*
X682796Y7061D01*
X682786Y7021D01*
X682776Y6976D01*
X682771Y6936D01*
X682761Y6891D01*
Y6721D01*
X682771Y6676D01*
X682776Y6636D01*
X682786Y6591D01*
X682796Y6551D01*
X682841Y6431D01*
X682881Y6351D01*
X682906Y6316D01*
X682926Y6281D01*
X682956Y6246D01*
X682981Y6211D01*
X683011Y6181D01*
Y3756D01*
X683021Y3631D01*
X683061Y3506D01*
X683121Y3396D01*
X683201Y3296D01*
X683301Y3216D01*
X683411Y3156D01*
X683536Y3116D01*
X683661Y3106D01*
G37*
G36*
G01X707283D02*
X707408Y3116D01*
X707533Y3156D01*
X707643Y3216D01*
X707743Y3296D01*
X707823Y3396D01*
X707883Y3506D01*
X707923Y3631D01*
X707933Y3756D01*
Y6186D01*
X707963Y6216D01*
X708063Y6356D01*
X708083Y6396D01*
X708098Y6431D01*
X708118Y6471D01*
X708133Y6511D01*
X708143Y6551D01*
X708158Y6596D01*
X708163Y6636D01*
X708173Y6676D01*
X708178Y6721D01*
Y6761D01*
X708183Y6806D01*
X708178Y6851D01*
Y6891D01*
X708173Y6936D01*
X708163Y6976D01*
X708158Y7016D01*
X708143Y7061D01*
X708133Y7101D01*
X708118Y7141D01*
X708098Y7181D01*
X708083Y7216D01*
X708063Y7256D01*
X707963Y7396D01*
X707933Y7426D01*
Y9556D01*
X707923Y9681D01*
X707883Y9806D01*
X707823Y9916D01*
X707743Y10016D01*
X707643Y10096D01*
X707533Y10156D01*
X707408Y10196D01*
X707283Y10206D01*
X707158Y10196D01*
X707033Y10156D01*
X706923Y10096D01*
X706823Y10016D01*
X706743Y9916D01*
X706683Y9806D01*
X706643Y9681D01*
X706633Y9556D01*
Y7431D01*
X706603Y7401D01*
X706578Y7366D01*
X706548Y7331D01*
X706528Y7296D01*
X706503Y7261D01*
X706463Y7181D01*
X706418Y7061D01*
X706408Y7021D01*
X706398Y6976D01*
X706393Y6936D01*
X706383Y6891D01*
Y6721D01*
X706393Y6676D01*
X706398Y6636D01*
X706408Y6591D01*
X706418Y6551D01*
X706463Y6431D01*
X706503Y6351D01*
X706528Y6316D01*
X706548Y6281D01*
X706578Y6246D01*
X706603Y6211D01*
X706633Y6181D01*
Y3756D01*
X706643Y3631D01*
X706683Y3506D01*
X706743Y3396D01*
X706823Y3296D01*
X706923Y3216D01*
X707033Y3156D01*
X707158Y3116D01*
X707283Y3106D01*
G37*
G36*
G01X702559D02*
X702684Y3116D01*
X702809Y3156D01*
X702919Y3216D01*
X703019Y3296D01*
X703099Y3396D01*
X703159Y3506D01*
X703199Y3631D01*
X703209Y3756D01*
Y6186D01*
X703239Y6216D01*
X703339Y6356D01*
X703359Y6396D01*
X703374Y6431D01*
X703394Y6471D01*
X703409Y6511D01*
X703419Y6551D01*
X703434Y6596D01*
X703439Y6636D01*
X703449Y6676D01*
X703454Y6721D01*
Y6761D01*
X703459Y6806D01*
X703454Y6851D01*
Y6891D01*
X703449Y6936D01*
X703439Y6976D01*
X703434Y7016D01*
X703419Y7061D01*
X703409Y7101D01*
X703394Y7141D01*
X703374Y7181D01*
X703359Y7216D01*
X703339Y7256D01*
X703239Y7396D01*
X703209Y7426D01*
Y9556D01*
X703199Y9681D01*
X703159Y9806D01*
X703099Y9916D01*
X703019Y10016D01*
X702919Y10096D01*
X702809Y10156D01*
X702684Y10196D01*
X702559Y10206D01*
X702434Y10196D01*
X702309Y10156D01*
X702199Y10096D01*
X702099Y10016D01*
X702019Y9916D01*
X701959Y9806D01*
X701919Y9681D01*
X701909Y9556D01*
Y7431D01*
X701879Y7401D01*
X701854Y7366D01*
X701824Y7331D01*
X701804Y7296D01*
X701779Y7261D01*
X701739Y7181D01*
X701694Y7061D01*
X701684Y7021D01*
X701674Y6976D01*
X701669Y6936D01*
X701659Y6891D01*
Y6721D01*
X701669Y6676D01*
X701674Y6636D01*
X701684Y6591D01*
X701694Y6551D01*
X701739Y6431D01*
X701779Y6351D01*
X701804Y6316D01*
X701824Y6281D01*
X701854Y6246D01*
X701879Y6211D01*
X701909Y6181D01*
Y3756D01*
X701919Y3631D01*
X701959Y3506D01*
X702019Y3396D01*
X702099Y3296D01*
X702199Y3216D01*
X702309Y3156D01*
X702434Y3116D01*
X702559Y3106D01*
G37*
G36*
G01X697834D02*
X697959Y3116D01*
X698084Y3156D01*
X698194Y3216D01*
X698294Y3296D01*
X698374Y3396D01*
X698434Y3506D01*
X698474Y3631D01*
X698484Y3756D01*
Y6186D01*
X698514Y6216D01*
X698614Y6356D01*
X698634Y6396D01*
X698649Y6431D01*
X698669Y6471D01*
X698684Y6511D01*
X698694Y6551D01*
X698709Y6596D01*
X698714Y6636D01*
X698724Y6676D01*
X698729Y6721D01*
Y6761D01*
X698734Y6806D01*
X698729Y6851D01*
Y6891D01*
X698724Y6936D01*
X698714Y6976D01*
X698709Y7016D01*
X698694Y7061D01*
X698684Y7101D01*
X698669Y7141D01*
X698649Y7181D01*
X698634Y7216D01*
X698614Y7256D01*
X698514Y7396D01*
X698484Y7426D01*
Y9556D01*
X698474Y9681D01*
X698434Y9806D01*
X698374Y9916D01*
X698294Y10016D01*
X698194Y10096D01*
X698084Y10156D01*
X697959Y10196D01*
X697834Y10206D01*
X697709Y10196D01*
X697584Y10156D01*
X697474Y10096D01*
X697374Y10016D01*
X697294Y9916D01*
X697234Y9806D01*
X697194Y9681D01*
X697184Y9556D01*
Y7431D01*
X697154Y7401D01*
X697129Y7366D01*
X697099Y7331D01*
X697079Y7296D01*
X697054Y7261D01*
X697014Y7181D01*
X696969Y7061D01*
X696959Y7021D01*
X696949Y6976D01*
X696944Y6936D01*
X696934Y6891D01*
Y6721D01*
X696944Y6676D01*
X696949Y6636D01*
X696959Y6591D01*
X696969Y6551D01*
X697014Y6431D01*
X697054Y6351D01*
X697079Y6316D01*
X697099Y6281D01*
X697129Y6246D01*
X697154Y6211D01*
X697184Y6181D01*
Y3756D01*
X697194Y3631D01*
X697234Y3506D01*
X697294Y3396D01*
X697374Y3296D01*
X697474Y3216D01*
X697584Y3156D01*
X697709Y3116D01*
X697834Y3106D01*
G37*
G36*
G01X726181D02*
X726306Y3116D01*
X726431Y3156D01*
X726541Y3216D01*
X726641Y3296D01*
X726721Y3396D01*
X726781Y3506D01*
X726821Y3631D01*
X726831Y3756D01*
Y6186D01*
X726861Y6216D01*
X726961Y6356D01*
X726981Y6396D01*
X726996Y6431D01*
X727016Y6471D01*
X727031Y6511D01*
X727041Y6551D01*
X727056Y6596D01*
X727061Y6636D01*
X727071Y6676D01*
X727076Y6721D01*
Y6761D01*
X727081Y6806D01*
X727076Y6851D01*
Y6891D01*
X727071Y6936D01*
X727061Y6976D01*
X727056Y7016D01*
X727041Y7061D01*
X727031Y7101D01*
X727016Y7141D01*
X726996Y7181D01*
X726981Y7216D01*
X726961Y7256D01*
X726861Y7396D01*
X726831Y7426D01*
Y9556D01*
X726821Y9681D01*
X726781Y9806D01*
X726721Y9916D01*
X726641Y10016D01*
X726541Y10096D01*
X726431Y10156D01*
X726306Y10196D01*
X726181Y10206D01*
X726056Y10196D01*
X725931Y10156D01*
X725821Y10096D01*
X725721Y10016D01*
X725641Y9916D01*
X725581Y9806D01*
X725541Y9681D01*
X725531Y9556D01*
Y7431D01*
X725501Y7401D01*
X725476Y7366D01*
X725446Y7331D01*
X725426Y7296D01*
X725401Y7261D01*
X725361Y7181D01*
X725316Y7061D01*
X725306Y7021D01*
X725296Y6976D01*
X725291Y6936D01*
X725281Y6891D01*
Y6721D01*
X725291Y6676D01*
X725296Y6636D01*
X725306Y6591D01*
X725316Y6551D01*
X725361Y6431D01*
X725401Y6351D01*
X725426Y6316D01*
X725446Y6281D01*
X725476Y6246D01*
X725501Y6211D01*
X725531Y6181D01*
Y3756D01*
X725541Y3631D01*
X725581Y3506D01*
X725641Y3396D01*
X725721Y3296D01*
X725821Y3216D01*
X725931Y3156D01*
X726056Y3116D01*
X726181Y3106D01*
G37*
G36*
G01X721456D02*
X721581Y3116D01*
X721706Y3156D01*
X721816Y3216D01*
X721916Y3296D01*
X721996Y3396D01*
X722056Y3506D01*
X722096Y3631D01*
X722106Y3756D01*
Y6186D01*
X722136Y6216D01*
X722236Y6356D01*
X722256Y6396D01*
X722271Y6431D01*
X722291Y6471D01*
X722306Y6511D01*
X722316Y6551D01*
X722331Y6596D01*
X722336Y6636D01*
X722346Y6676D01*
X722351Y6721D01*
Y6761D01*
X722356Y6806D01*
X722351Y6851D01*
Y6891D01*
X722346Y6936D01*
X722336Y6976D01*
X722331Y7016D01*
X722316Y7061D01*
X722306Y7101D01*
X722291Y7141D01*
X722271Y7181D01*
X722256Y7216D01*
X722236Y7256D01*
X722136Y7396D01*
X722106Y7426D01*
Y9556D01*
X722096Y9681D01*
X722056Y9806D01*
X721996Y9916D01*
X721916Y10016D01*
X721816Y10096D01*
X721706Y10156D01*
X721581Y10196D01*
X721456Y10206D01*
X721331Y10196D01*
X721206Y10156D01*
X721096Y10096D01*
X720996Y10016D01*
X720916Y9916D01*
X720856Y9806D01*
X720816Y9681D01*
X720806Y9556D01*
Y7431D01*
X720776Y7401D01*
X720751Y7366D01*
X720721Y7331D01*
X720701Y7296D01*
X720676Y7261D01*
X720636Y7181D01*
X720591Y7061D01*
X720581Y7021D01*
X720571Y6976D01*
X720566Y6936D01*
X720556Y6891D01*
Y6721D01*
X720566Y6676D01*
X720571Y6636D01*
X720581Y6591D01*
X720591Y6551D01*
X720636Y6431D01*
X720676Y6351D01*
X720701Y6316D01*
X720721Y6281D01*
X720751Y6246D01*
X720776Y6211D01*
X720806Y6181D01*
Y3756D01*
X720816Y3631D01*
X720856Y3506D01*
X720916Y3396D01*
X720996Y3296D01*
X721096Y3216D01*
X721206Y3156D01*
X721331Y3116D01*
X721456Y3106D01*
G37*
G36*
G01X716732D02*
X716857Y3116D01*
X716982Y3156D01*
X717092Y3216D01*
X717192Y3296D01*
X717272Y3396D01*
X717332Y3506D01*
X717372Y3631D01*
X717382Y3756D01*
Y6186D01*
X717412Y6216D01*
X717512Y6356D01*
X717532Y6396D01*
X717547Y6431D01*
X717567Y6471D01*
X717582Y6511D01*
X717592Y6551D01*
X717607Y6596D01*
X717612Y6636D01*
X717622Y6676D01*
X717627Y6721D01*
Y6761D01*
X717632Y6806D01*
X717627Y6851D01*
Y6891D01*
X717622Y6936D01*
X717612Y6976D01*
X717607Y7016D01*
X717592Y7061D01*
X717582Y7101D01*
X717567Y7141D01*
X717547Y7181D01*
X717532Y7216D01*
X717512Y7256D01*
X717412Y7396D01*
X717382Y7426D01*
Y9556D01*
X717372Y9681D01*
X717332Y9806D01*
X717272Y9916D01*
X717192Y10016D01*
X717092Y10096D01*
X716982Y10156D01*
X716857Y10196D01*
X716732Y10206D01*
X716607Y10196D01*
X716482Y10156D01*
X716372Y10096D01*
X716272Y10016D01*
X716192Y9916D01*
X716132Y9806D01*
X716092Y9681D01*
X716082Y9556D01*
Y7431D01*
X716052Y7401D01*
X716027Y7366D01*
X715997Y7331D01*
X715977Y7296D01*
X715952Y7261D01*
X715912Y7181D01*
X715867Y7061D01*
X715857Y7021D01*
X715847Y6976D01*
X715842Y6936D01*
X715832Y6891D01*
Y6721D01*
X715842Y6676D01*
X715847Y6636D01*
X715857Y6591D01*
X715867Y6551D01*
X715912Y6431D01*
X715952Y6351D01*
X715977Y6316D01*
X715997Y6281D01*
X716027Y6246D01*
X716052Y6211D01*
X716082Y6181D01*
Y3756D01*
X716092Y3631D01*
X716132Y3506D01*
X716192Y3396D01*
X716272Y3296D01*
X716372Y3216D01*
X716482Y3156D01*
X716607Y3116D01*
X716732Y3106D01*
G37*
G36*
G01X712008D02*
X712133Y3116D01*
X712258Y3156D01*
X712368Y3216D01*
X712468Y3296D01*
X712548Y3396D01*
X712608Y3506D01*
X712648Y3631D01*
X712658Y3756D01*
Y6186D01*
X712688Y6216D01*
X712788Y6356D01*
X712808Y6396D01*
X712823Y6431D01*
X712843Y6471D01*
X712858Y6511D01*
X712868Y6551D01*
X712883Y6596D01*
X712888Y6636D01*
X712898Y6676D01*
X712903Y6721D01*
Y6761D01*
X712908Y6806D01*
X712903Y6851D01*
Y6891D01*
X712898Y6936D01*
X712888Y6976D01*
X712883Y7016D01*
X712868Y7061D01*
X712858Y7101D01*
X712843Y7141D01*
X712823Y7181D01*
X712808Y7216D01*
X712788Y7256D01*
X712688Y7396D01*
X712658Y7426D01*
Y9556D01*
X712648Y9681D01*
X712608Y9806D01*
X712548Y9916D01*
X712468Y10016D01*
X712368Y10096D01*
X712258Y10156D01*
X712133Y10196D01*
X712008Y10206D01*
X711883Y10196D01*
X711758Y10156D01*
X711648Y10096D01*
X711548Y10016D01*
X711468Y9916D01*
X711408Y9806D01*
X711368Y9681D01*
X711358Y9556D01*
Y7431D01*
X711328Y7401D01*
X711303Y7366D01*
X711273Y7331D01*
X711253Y7296D01*
X711228Y7261D01*
X711188Y7181D01*
X711143Y7061D01*
X711133Y7021D01*
X711123Y6976D01*
X711118Y6936D01*
X711108Y6891D01*
Y6721D01*
X711118Y6676D01*
X711123Y6636D01*
X711133Y6591D01*
X711143Y6551D01*
X711188Y6431D01*
X711228Y6351D01*
X711253Y6316D01*
X711273Y6281D01*
X711303Y6246D01*
X711328Y6211D01*
X711358Y6181D01*
Y3756D01*
X711368Y3631D01*
X711408Y3506D01*
X711468Y3396D01*
X711548Y3296D01*
X711648Y3216D01*
X711758Y3156D01*
X711883Y3116D01*
X712008Y3106D01*
G37*
G36*
G01X740354D02*
X740479Y3116D01*
X740604Y3156D01*
X740714Y3216D01*
X740814Y3296D01*
X740894Y3396D01*
X740954Y3506D01*
X740994Y3631D01*
X741004Y3756D01*
Y6186D01*
X741034Y6216D01*
X741134Y6356D01*
X741154Y6396D01*
X741169Y6431D01*
X741189Y6471D01*
X741204Y6511D01*
X741214Y6551D01*
X741229Y6596D01*
X741234Y6636D01*
X741244Y6676D01*
X741249Y6721D01*
Y6761D01*
X741254Y6806D01*
X741249Y6851D01*
Y6891D01*
X741244Y6936D01*
X741234Y6976D01*
X741229Y7016D01*
X741214Y7061D01*
X741204Y7101D01*
X741189Y7141D01*
X741169Y7181D01*
X741154Y7216D01*
X741134Y7256D01*
X741034Y7396D01*
X741004Y7426D01*
Y9556D01*
X740994Y9681D01*
X740954Y9806D01*
X740894Y9916D01*
X740814Y10016D01*
X740714Y10096D01*
X740604Y10156D01*
X740479Y10196D01*
X740354Y10206D01*
X740229Y10196D01*
X740104Y10156D01*
X739994Y10096D01*
X739894Y10016D01*
X739814Y9916D01*
X739754Y9806D01*
X739714Y9681D01*
X739704Y9556D01*
Y7431D01*
X739674Y7401D01*
X739649Y7366D01*
X739619Y7331D01*
X739599Y7296D01*
X739574Y7261D01*
X739534Y7181D01*
X739489Y7061D01*
X739479Y7021D01*
X739469Y6976D01*
X739464Y6936D01*
X739454Y6891D01*
Y6721D01*
X739464Y6676D01*
X739469Y6636D01*
X739479Y6591D01*
X739489Y6551D01*
X739534Y6431D01*
X739574Y6351D01*
X739599Y6316D01*
X739619Y6281D01*
X739649Y6246D01*
X739674Y6211D01*
X739704Y6181D01*
Y3756D01*
X739714Y3631D01*
X739754Y3506D01*
X739814Y3396D01*
X739894Y3296D01*
X739994Y3216D01*
X740104Y3156D01*
X740229Y3116D01*
X740354Y3106D01*
G37*
G36*
G01X735630D02*
X735755Y3116D01*
X735880Y3156D01*
X735990Y3216D01*
X736090Y3296D01*
X736170Y3396D01*
X736230Y3506D01*
X736270Y3631D01*
X736280Y3756D01*
Y6186D01*
X736310Y6216D01*
X736410Y6356D01*
X736430Y6396D01*
X736445Y6431D01*
X736465Y6471D01*
X736480Y6511D01*
X736490Y6551D01*
X736505Y6596D01*
X736510Y6636D01*
X736520Y6676D01*
X736525Y6721D01*
Y6761D01*
X736530Y6806D01*
X736525Y6851D01*
Y6891D01*
X736520Y6936D01*
X736510Y6976D01*
X736505Y7016D01*
X736490Y7061D01*
X736480Y7101D01*
X736465Y7141D01*
X736445Y7181D01*
X736430Y7216D01*
X736410Y7256D01*
X736310Y7396D01*
X736280Y7426D01*
Y9556D01*
X736270Y9681D01*
X736230Y9806D01*
X736170Y9916D01*
X736090Y10016D01*
X735990Y10096D01*
X735880Y10156D01*
X735755Y10196D01*
X735630Y10206D01*
X735505Y10196D01*
X735380Y10156D01*
X735270Y10096D01*
X735170Y10016D01*
X735090Y9916D01*
X735030Y9806D01*
X734990Y9681D01*
X734980Y9556D01*
Y7431D01*
X734950Y7401D01*
X734925Y7366D01*
X734895Y7331D01*
X734875Y7296D01*
X734850Y7261D01*
X734810Y7181D01*
X734765Y7061D01*
X734755Y7021D01*
X734745Y6976D01*
X734740Y6936D01*
X734730Y6891D01*
Y6721D01*
X734740Y6676D01*
X734745Y6636D01*
X734755Y6591D01*
X734765Y6551D01*
X734810Y6431D01*
X734850Y6351D01*
X734875Y6316D01*
X734895Y6281D01*
X734925Y6246D01*
X734950Y6211D01*
X734980Y6181D01*
Y3756D01*
X734990Y3631D01*
X735030Y3506D01*
X735090Y3396D01*
X735170Y3296D01*
X735270Y3216D01*
X735380Y3156D01*
X735505Y3116D01*
X735630Y3106D01*
G37*
G36*
G01X730905D02*
X731030Y3116D01*
X731155Y3156D01*
X731265Y3216D01*
X731365Y3296D01*
X731445Y3396D01*
X731505Y3506D01*
X731545Y3631D01*
X731555Y3756D01*
Y6186D01*
X731585Y6216D01*
X731685Y6356D01*
X731705Y6396D01*
X731720Y6431D01*
X731740Y6471D01*
X731755Y6511D01*
X731765Y6551D01*
X731780Y6596D01*
X731785Y6636D01*
X731795Y6676D01*
X731800Y6721D01*
Y6761D01*
X731805Y6806D01*
X731800Y6851D01*
Y6891D01*
X731795Y6936D01*
X731785Y6976D01*
X731780Y7016D01*
X731765Y7061D01*
X731755Y7101D01*
X731740Y7141D01*
X731720Y7181D01*
X731705Y7216D01*
X731685Y7256D01*
X731585Y7396D01*
X731555Y7426D01*
Y9556D01*
X731545Y9681D01*
X731505Y9806D01*
X731445Y9916D01*
X731365Y10016D01*
X731265Y10096D01*
X731155Y10156D01*
X731030Y10196D01*
X730905Y10206D01*
X730780Y10196D01*
X730655Y10156D01*
X730545Y10096D01*
X730445Y10016D01*
X730365Y9916D01*
X730305Y9806D01*
X730265Y9681D01*
X730255Y9556D01*
Y7431D01*
X730225Y7401D01*
X730200Y7366D01*
X730170Y7331D01*
X730150Y7296D01*
X730125Y7261D01*
X730085Y7181D01*
X730040Y7061D01*
X730030Y7021D01*
X730020Y6976D01*
X730015Y6936D01*
X730005Y6891D01*
Y6721D01*
X730015Y6676D01*
X730020Y6636D01*
X730030Y6591D01*
X730040Y6551D01*
X730085Y6431D01*
X730125Y6351D01*
X730150Y6316D01*
X730170Y6281D01*
X730200Y6246D01*
X730225Y6211D01*
X730255Y6181D01*
Y3756D01*
X730265Y3631D01*
X730305Y3506D01*
X730365Y3396D01*
X730445Y3296D01*
X730545Y3216D01*
X730655Y3156D01*
X730780Y3116D01*
X730905Y3106D01*
G37*
G36*
G01X754527D02*
X754652Y3116D01*
X754777Y3156D01*
X754887Y3216D01*
X754987Y3296D01*
X755067Y3396D01*
X755127Y3506D01*
X755167Y3631D01*
X755177Y3756D01*
Y6186D01*
X755207Y6216D01*
X755307Y6356D01*
X755327Y6396D01*
X755342Y6431D01*
X755362Y6471D01*
X755377Y6511D01*
X755387Y6551D01*
X755402Y6596D01*
X755407Y6636D01*
X755417Y6676D01*
X755422Y6721D01*
Y6761D01*
X755427Y6806D01*
X755422Y6851D01*
Y6891D01*
X755417Y6936D01*
X755407Y6976D01*
X755402Y7016D01*
X755387Y7061D01*
X755377Y7101D01*
X755362Y7141D01*
X755342Y7181D01*
X755327Y7216D01*
X755307Y7256D01*
X755207Y7396D01*
X755177Y7426D01*
Y9556D01*
X755167Y9681D01*
X755127Y9806D01*
X755067Y9916D01*
X754987Y10016D01*
X754887Y10096D01*
X754777Y10156D01*
X754652Y10196D01*
X754527Y10206D01*
X754402Y10196D01*
X754277Y10156D01*
X754167Y10096D01*
X754067Y10016D01*
X753987Y9916D01*
X753927Y9806D01*
X753887Y9681D01*
X753877Y9556D01*
Y7431D01*
X753847Y7401D01*
X753822Y7366D01*
X753792Y7331D01*
X753772Y7296D01*
X753747Y7261D01*
X753707Y7181D01*
X753662Y7061D01*
X753652Y7021D01*
X753642Y6976D01*
X753637Y6936D01*
X753627Y6891D01*
Y6721D01*
X753637Y6676D01*
X753642Y6636D01*
X753652Y6591D01*
X753662Y6551D01*
X753707Y6431D01*
X753747Y6351D01*
X753772Y6316D01*
X753792Y6281D01*
X753822Y6246D01*
X753847Y6211D01*
X753877Y6181D01*
Y3756D01*
X753887Y3631D01*
X753927Y3506D01*
X753987Y3396D01*
X754067Y3296D01*
X754167Y3216D01*
X754277Y3156D01*
X754402Y3116D01*
X754527Y3106D01*
G37*
G36*
G01X749803D02*
X749928Y3116D01*
X750053Y3156D01*
X750163Y3216D01*
X750263Y3296D01*
X750343Y3396D01*
X750403Y3506D01*
X750443Y3631D01*
X750453Y3756D01*
Y6186D01*
X750483Y6216D01*
X750583Y6356D01*
X750603Y6396D01*
X750618Y6431D01*
X750638Y6471D01*
X750653Y6511D01*
X750663Y6551D01*
X750678Y6596D01*
X750683Y6636D01*
X750693Y6676D01*
X750698Y6721D01*
Y6761D01*
X750703Y6806D01*
X750698Y6851D01*
Y6891D01*
X750693Y6936D01*
X750683Y6976D01*
X750678Y7016D01*
X750663Y7061D01*
X750653Y7101D01*
X750638Y7141D01*
X750618Y7181D01*
X750603Y7216D01*
X750583Y7256D01*
X750483Y7396D01*
X750453Y7426D01*
Y9556D01*
X750443Y9681D01*
X750403Y9806D01*
X750343Y9916D01*
X750263Y10016D01*
X750163Y10096D01*
X750053Y10156D01*
X749928Y10196D01*
X749803Y10206D01*
X749678Y10196D01*
X749553Y10156D01*
X749443Y10096D01*
X749343Y10016D01*
X749263Y9916D01*
X749203Y9806D01*
X749163Y9681D01*
X749153Y9556D01*
Y7431D01*
X749123Y7401D01*
X749098Y7366D01*
X749068Y7331D01*
X749048Y7296D01*
X749023Y7261D01*
X748983Y7181D01*
X748938Y7061D01*
X748928Y7021D01*
X748918Y6976D01*
X748913Y6936D01*
X748903Y6891D01*
Y6721D01*
X748913Y6676D01*
X748918Y6636D01*
X748928Y6591D01*
X748938Y6551D01*
X748983Y6431D01*
X749023Y6351D01*
X749048Y6316D01*
X749068Y6281D01*
X749098Y6246D01*
X749123Y6211D01*
X749153Y6181D01*
Y3756D01*
X749163Y3631D01*
X749203Y3506D01*
X749263Y3396D01*
X749343Y3296D01*
X749443Y3216D01*
X749553Y3156D01*
X749678Y3116D01*
X749803Y3106D01*
G37*
G36*
G01X745078D02*
X745203Y3116D01*
X745328Y3156D01*
X745438Y3216D01*
X745538Y3296D01*
X745618Y3396D01*
X745678Y3506D01*
X745718Y3631D01*
X745728Y3756D01*
Y6186D01*
X745758Y6216D01*
X745858Y6356D01*
X745878Y6396D01*
X745893Y6431D01*
X745913Y6471D01*
X745928Y6511D01*
X745938Y6551D01*
X745953Y6596D01*
X745958Y6636D01*
X745968Y6676D01*
X745973Y6721D01*
Y6761D01*
X745978Y6806D01*
X745973Y6851D01*
Y6891D01*
X745968Y6936D01*
X745958Y6976D01*
X745953Y7016D01*
X745938Y7061D01*
X745928Y7101D01*
X745913Y7141D01*
X745893Y7181D01*
X745878Y7216D01*
X745858Y7256D01*
X745758Y7396D01*
X745728Y7426D01*
Y9556D01*
X745718Y9681D01*
X745678Y9806D01*
X745618Y9916D01*
X745538Y10016D01*
X745438Y10096D01*
X745328Y10156D01*
X745203Y10196D01*
X745078Y10206D01*
X744953Y10196D01*
X744828Y10156D01*
X744718Y10096D01*
X744618Y10016D01*
X744538Y9916D01*
X744478Y9806D01*
X744438Y9681D01*
X744428Y9556D01*
Y7431D01*
X744398Y7401D01*
X744373Y7366D01*
X744343Y7331D01*
X744323Y7296D01*
X744298Y7261D01*
X744258Y7181D01*
X744213Y7061D01*
X744203Y7021D01*
X744193Y6976D01*
X744188Y6936D01*
X744178Y6891D01*
Y6721D01*
X744188Y6676D01*
X744193Y6636D01*
X744203Y6591D01*
X744213Y6551D01*
X744258Y6431D01*
X744298Y6351D01*
X744323Y6316D01*
X744343Y6281D01*
X744373Y6246D01*
X744398Y6211D01*
X744428Y6181D01*
Y3756D01*
X744438Y3631D01*
X744478Y3506D01*
X744538Y3396D01*
X744618Y3296D01*
X744718Y3216D01*
X744828Y3156D01*
X744953Y3116D01*
X745078Y3106D01*
G37*
G54D97*
G01X84722Y184222D02*
X82000Y181500D01*
Y177500D01*
G01X94900Y193000D02*
X93500D01*
X84722Y184222D01*
G01X146500Y236500D02*
X148551Y238551D01*
G01X166500Y241000D02*
X163200D01*
G54D88*
X771791Y272260D03*
Y279740D03*
X780209Y276000D03*
G36*
G01X506496Y3106D02*
X506621Y3116D01*
X506746Y3156D01*
X506856Y3216D01*
X506956Y3296D01*
X507036Y3396D01*
X507096Y3506D01*
X507136Y3631D01*
X507146Y3756D01*
Y7186D01*
X507176Y7216D01*
X507276Y7356D01*
X507296Y7396D01*
X507311Y7431D01*
X507331Y7471D01*
X507346Y7511D01*
X507356Y7551D01*
X507371Y7596D01*
X507376Y7636D01*
X507386Y7676D01*
X507391Y7721D01*
Y7761D01*
X507396Y7806D01*
X507391Y7851D01*
Y7891D01*
X507386Y7936D01*
X507376Y7976D01*
X507371Y8016D01*
X507356Y8061D01*
X507346Y8101D01*
X507331Y8141D01*
X507311Y8181D01*
X507296Y8216D01*
X507276Y8256D01*
X507176Y8396D01*
X507146Y8426D01*
Y9556D01*
X507136Y9681D01*
X507096Y9806D01*
X507036Y9916D01*
X506956Y10016D01*
X506856Y10096D01*
X506746Y10156D01*
X506621Y10196D01*
X506496Y10206D01*
X506371Y10196D01*
X506246Y10156D01*
X506136Y10096D01*
X506036Y10016D01*
X505956Y9916D01*
X505896Y9806D01*
X505856Y9681D01*
X505846Y9556D01*
Y8426D01*
X505816Y8396D01*
X505716Y8256D01*
X505696Y8216D01*
X505681Y8181D01*
X505661Y8141D01*
X505646Y8101D01*
X505636Y8061D01*
X505621Y8016D01*
X505616Y7976D01*
X505606Y7936D01*
X505601Y7891D01*
Y7851D01*
X505596Y7806D01*
X505601Y7761D01*
Y7721D01*
X505606Y7676D01*
X505616Y7636D01*
X505621Y7596D01*
X505636Y7551D01*
X505646Y7511D01*
X505661Y7471D01*
X505681Y7431D01*
X505696Y7396D01*
X505716Y7356D01*
X505816Y7216D01*
X505846Y7186D01*
Y3756D01*
X505856Y3631D01*
X505896Y3506D01*
X505956Y3396D01*
X506036Y3296D01*
X506136Y3216D01*
X506246Y3156D01*
X506371Y3116D01*
X506496Y3106D01*
G37*
G36*
G01X525393D02*
X525518Y3116D01*
X525643Y3156D01*
X525753Y3216D01*
X525853Y3296D01*
X525933Y3396D01*
X525993Y3506D01*
X526033Y3631D01*
X526043Y3756D01*
Y7186D01*
X526073Y7216D01*
X526173Y7356D01*
X526193Y7396D01*
X526208Y7431D01*
X526228Y7471D01*
X526243Y7511D01*
X526253Y7551D01*
X526268Y7596D01*
X526273Y7636D01*
X526283Y7676D01*
X526288Y7721D01*
Y7761D01*
X526293Y7806D01*
X526288Y7851D01*
Y7891D01*
X526283Y7936D01*
X526273Y7976D01*
X526268Y8016D01*
X526253Y8061D01*
X526243Y8101D01*
X526228Y8141D01*
X526208Y8181D01*
X526193Y8216D01*
X526173Y8256D01*
X526073Y8396D01*
X526043Y8426D01*
Y9556D01*
X526033Y9681D01*
X525993Y9806D01*
X525933Y9916D01*
X525853Y10016D01*
X525753Y10096D01*
X525643Y10156D01*
X525518Y10196D01*
X525393Y10206D01*
X525268Y10196D01*
X525143Y10156D01*
X525033Y10096D01*
X524933Y10016D01*
X524853Y9916D01*
X524793Y9806D01*
X524753Y9681D01*
X524743Y9556D01*
Y8426D01*
X524713Y8396D01*
X524613Y8256D01*
X524593Y8216D01*
X524578Y8181D01*
X524558Y8141D01*
X524543Y8101D01*
X524533Y8061D01*
X524518Y8016D01*
X524513Y7976D01*
X524503Y7936D01*
X524498Y7891D01*
Y7851D01*
X524493Y7806D01*
X524498Y7761D01*
Y7721D01*
X524503Y7676D01*
X524513Y7636D01*
X524518Y7596D01*
X524533Y7551D01*
X524543Y7511D01*
X524558Y7471D01*
X524578Y7431D01*
X524593Y7396D01*
X524613Y7356D01*
X524713Y7216D01*
X524743Y7186D01*
Y3756D01*
X524753Y3631D01*
X524793Y3506D01*
X524853Y3396D01*
X524933Y3296D01*
X525033Y3216D01*
X525143Y3156D01*
X525268Y3116D01*
X525393Y3106D01*
G37*
G36*
G01X520669D02*
X520794Y3116D01*
X520919Y3156D01*
X521029Y3216D01*
X521129Y3296D01*
X521209Y3396D01*
X521269Y3506D01*
X521309Y3631D01*
X521319Y3756D01*
Y7186D01*
X521349Y7216D01*
X521449Y7356D01*
X521469Y7396D01*
X521484Y7431D01*
X521504Y7471D01*
X521519Y7511D01*
X521529Y7551D01*
X521544Y7596D01*
X521549Y7636D01*
X521559Y7676D01*
X521564Y7721D01*
Y7761D01*
X521569Y7806D01*
X521564Y7851D01*
Y7891D01*
X521559Y7936D01*
X521549Y7976D01*
X521544Y8016D01*
X521529Y8061D01*
X521519Y8101D01*
X521504Y8141D01*
X521484Y8181D01*
X521469Y8216D01*
X521449Y8256D01*
X521349Y8396D01*
X521319Y8426D01*
Y9556D01*
X521309Y9681D01*
X521269Y9806D01*
X521209Y9916D01*
X521129Y10016D01*
X521029Y10096D01*
X520919Y10156D01*
X520794Y10196D01*
X520669Y10206D01*
X520544Y10196D01*
X520419Y10156D01*
X520309Y10096D01*
X520209Y10016D01*
X520129Y9916D01*
X520069Y9806D01*
X520029Y9681D01*
X520019Y9556D01*
Y8426D01*
X519989Y8396D01*
X519889Y8256D01*
X519869Y8216D01*
X519854Y8181D01*
X519834Y8141D01*
X519819Y8101D01*
X519809Y8061D01*
X519794Y8016D01*
X519789Y7976D01*
X519779Y7936D01*
X519774Y7891D01*
Y7851D01*
X519769Y7806D01*
X519774Y7761D01*
Y7721D01*
X519779Y7676D01*
X519789Y7636D01*
X519794Y7596D01*
X519809Y7551D01*
X519819Y7511D01*
X519834Y7471D01*
X519854Y7431D01*
X519869Y7396D01*
X519889Y7356D01*
X519989Y7216D01*
X520019Y7186D01*
Y3756D01*
X520029Y3631D01*
X520069Y3506D01*
X520129Y3396D01*
X520209Y3296D01*
X520309Y3216D01*
X520419Y3156D01*
X520544Y3116D01*
X520669Y3106D01*
G37*
G36*
G01X515945D02*
X516070Y3116D01*
X516195Y3156D01*
X516305Y3216D01*
X516405Y3296D01*
X516485Y3396D01*
X516545Y3506D01*
X516585Y3631D01*
X516595Y3756D01*
Y7186D01*
X516625Y7216D01*
X516725Y7356D01*
X516745Y7396D01*
X516760Y7431D01*
X516780Y7471D01*
X516795Y7511D01*
X516805Y7551D01*
X516820Y7596D01*
X516825Y7636D01*
X516835Y7676D01*
X516840Y7721D01*
Y7761D01*
X516845Y7806D01*
X516840Y7851D01*
Y7891D01*
X516835Y7936D01*
X516825Y7976D01*
X516820Y8016D01*
X516805Y8061D01*
X516795Y8101D01*
X516780Y8141D01*
X516760Y8181D01*
X516745Y8216D01*
X516725Y8256D01*
X516625Y8396D01*
X516595Y8426D01*
Y9556D01*
X516585Y9681D01*
X516545Y9806D01*
X516485Y9916D01*
X516405Y10016D01*
X516305Y10096D01*
X516195Y10156D01*
X516070Y10196D01*
X515945Y10206D01*
X515820Y10196D01*
X515695Y10156D01*
X515585Y10096D01*
X515485Y10016D01*
X515405Y9916D01*
X515345Y9806D01*
X515305Y9681D01*
X515295Y9556D01*
Y8426D01*
X515265Y8396D01*
X515165Y8256D01*
X515145Y8216D01*
X515130Y8181D01*
X515110Y8141D01*
X515095Y8101D01*
X515085Y8061D01*
X515070Y8016D01*
X515065Y7976D01*
X515055Y7936D01*
X515050Y7891D01*
Y7851D01*
X515045Y7806D01*
X515050Y7761D01*
Y7721D01*
X515055Y7676D01*
X515065Y7636D01*
X515070Y7596D01*
X515085Y7551D01*
X515095Y7511D01*
X515110Y7471D01*
X515130Y7431D01*
X515145Y7396D01*
X515165Y7356D01*
X515265Y7216D01*
X515295Y7186D01*
Y3756D01*
X515305Y3631D01*
X515345Y3506D01*
X515405Y3396D01*
X515485Y3296D01*
X515585Y3216D01*
X515695Y3156D01*
X515820Y3116D01*
X515945Y3106D01*
G37*
G36*
G01X511220D02*
X511345Y3116D01*
X511470Y3156D01*
X511580Y3216D01*
X511680Y3296D01*
X511760Y3396D01*
X511820Y3506D01*
X511860Y3631D01*
X511870Y3756D01*
Y7186D01*
X511900Y7216D01*
X512000Y7356D01*
X512020Y7396D01*
X512035Y7431D01*
X512055Y7471D01*
X512070Y7511D01*
X512080Y7551D01*
X512095Y7596D01*
X512100Y7636D01*
X512110Y7676D01*
X512115Y7721D01*
Y7761D01*
X512120Y7806D01*
X512115Y7851D01*
Y7891D01*
X512110Y7936D01*
X512100Y7976D01*
X512095Y8016D01*
X512080Y8061D01*
X512070Y8101D01*
X512055Y8141D01*
X512035Y8181D01*
X512020Y8216D01*
X512000Y8256D01*
X511900Y8396D01*
X511870Y8426D01*
Y9556D01*
X511860Y9681D01*
X511820Y9806D01*
X511760Y9916D01*
X511680Y10016D01*
X511580Y10096D01*
X511470Y10156D01*
X511345Y10196D01*
X511220Y10206D01*
X511095Y10196D01*
X510970Y10156D01*
X510860Y10096D01*
X510760Y10016D01*
X510680Y9916D01*
X510620Y9806D01*
X510580Y9681D01*
X510570Y9556D01*
Y8426D01*
X510540Y8396D01*
X510440Y8256D01*
X510420Y8216D01*
X510405Y8181D01*
X510385Y8141D01*
X510370Y8101D01*
X510360Y8061D01*
X510345Y8016D01*
X510340Y7976D01*
X510330Y7936D01*
X510325Y7891D01*
Y7851D01*
X510320Y7806D01*
X510325Y7761D01*
Y7721D01*
X510330Y7676D01*
X510340Y7636D01*
X510345Y7596D01*
X510360Y7551D01*
X510370Y7511D01*
X510385Y7471D01*
X510405Y7431D01*
X510420Y7396D01*
X510440Y7356D01*
X510540Y7216D01*
X510570Y7186D01*
Y3756D01*
X510580Y3631D01*
X510620Y3506D01*
X510680Y3396D01*
X510760Y3296D01*
X510860Y3216D01*
X510970Y3156D01*
X511095Y3116D01*
X511220Y3106D01*
G37*
G36*
G01X539567D02*
X539692Y3116D01*
X539817Y3156D01*
X539927Y3216D01*
X540027Y3296D01*
X540107Y3396D01*
X540167Y3506D01*
X540207Y3631D01*
X540217Y3756D01*
Y7186D01*
X540247Y7216D01*
X540347Y7356D01*
X540367Y7396D01*
X540382Y7431D01*
X540402Y7471D01*
X540417Y7511D01*
X540427Y7551D01*
X540442Y7596D01*
X540447Y7636D01*
X540457Y7676D01*
X540462Y7721D01*
Y7761D01*
X540467Y7806D01*
X540462Y7851D01*
Y7891D01*
X540457Y7936D01*
X540447Y7976D01*
X540442Y8016D01*
X540427Y8061D01*
X540417Y8101D01*
X540402Y8141D01*
X540382Y8181D01*
X540367Y8216D01*
X540347Y8256D01*
X540247Y8396D01*
X540217Y8426D01*
Y9556D01*
X540207Y9681D01*
X540167Y9806D01*
X540107Y9916D01*
X540027Y10016D01*
X539927Y10096D01*
X539817Y10156D01*
X539692Y10196D01*
X539567Y10206D01*
X539442Y10196D01*
X539317Y10156D01*
X539207Y10096D01*
X539107Y10016D01*
X539027Y9916D01*
X538967Y9806D01*
X538927Y9681D01*
X538917Y9556D01*
Y8426D01*
X538887Y8396D01*
X538787Y8256D01*
X538767Y8216D01*
X538752Y8181D01*
X538732Y8141D01*
X538717Y8101D01*
X538707Y8061D01*
X538692Y8016D01*
X538687Y7976D01*
X538677Y7936D01*
X538672Y7891D01*
Y7851D01*
X538667Y7806D01*
X538672Y7761D01*
Y7721D01*
X538677Y7676D01*
X538687Y7636D01*
X538692Y7596D01*
X538707Y7551D01*
X538717Y7511D01*
X538732Y7471D01*
X538752Y7431D01*
X538767Y7396D01*
X538787Y7356D01*
X538887Y7216D01*
X538917Y7186D01*
Y3756D01*
X538927Y3631D01*
X538967Y3506D01*
X539027Y3396D01*
X539107Y3296D01*
X539207Y3216D01*
X539317Y3156D01*
X539442Y3116D01*
X539567Y3106D01*
G37*
G36*
G01X534842D02*
X534967Y3116D01*
X535092Y3156D01*
X535202Y3216D01*
X535302Y3296D01*
X535382Y3396D01*
X535442Y3506D01*
X535482Y3631D01*
X535492Y3756D01*
Y7186D01*
X535522Y7216D01*
X535622Y7356D01*
X535642Y7396D01*
X535657Y7431D01*
X535677Y7471D01*
X535692Y7511D01*
X535702Y7551D01*
X535717Y7596D01*
X535722Y7636D01*
X535732Y7676D01*
X535737Y7721D01*
Y7761D01*
X535742Y7806D01*
X535737Y7851D01*
Y7891D01*
X535732Y7936D01*
X535722Y7976D01*
X535717Y8016D01*
X535702Y8061D01*
X535692Y8101D01*
X535677Y8141D01*
X535657Y8181D01*
X535642Y8216D01*
X535622Y8256D01*
X535522Y8396D01*
X535492Y8426D01*
Y9556D01*
X535482Y9681D01*
X535442Y9806D01*
X535382Y9916D01*
X535302Y10016D01*
X535202Y10096D01*
X535092Y10156D01*
X534967Y10196D01*
X534842Y10206D01*
X534717Y10196D01*
X534592Y10156D01*
X534482Y10096D01*
X534382Y10016D01*
X534302Y9916D01*
X534242Y9806D01*
X534202Y9681D01*
X534192Y9556D01*
Y8426D01*
X534162Y8396D01*
X534062Y8256D01*
X534042Y8216D01*
X534027Y8181D01*
X534007Y8141D01*
X533992Y8101D01*
X533982Y8061D01*
X533967Y8016D01*
X533962Y7976D01*
X533952Y7936D01*
X533947Y7891D01*
Y7851D01*
X533942Y7806D01*
X533947Y7761D01*
Y7721D01*
X533952Y7676D01*
X533962Y7636D01*
X533967Y7596D01*
X533982Y7551D01*
X533992Y7511D01*
X534007Y7471D01*
X534027Y7431D01*
X534042Y7396D01*
X534062Y7356D01*
X534162Y7216D01*
X534192Y7186D01*
Y3756D01*
X534202Y3631D01*
X534242Y3506D01*
X534302Y3396D01*
X534382Y3296D01*
X534482Y3216D01*
X534592Y3156D01*
X534717Y3116D01*
X534842Y3106D01*
G37*
G36*
G01X530118D02*
X530243Y3116D01*
X530368Y3156D01*
X530478Y3216D01*
X530578Y3296D01*
X530658Y3396D01*
X530718Y3506D01*
X530758Y3631D01*
X530768Y3756D01*
Y7186D01*
X530798Y7216D01*
X530898Y7356D01*
X530918Y7396D01*
X530933Y7431D01*
X530953Y7471D01*
X530968Y7511D01*
X530978Y7551D01*
X530993Y7596D01*
X530998Y7636D01*
X531008Y7676D01*
X531013Y7721D01*
Y7761D01*
X531018Y7806D01*
X531013Y7851D01*
Y7891D01*
X531008Y7936D01*
X530998Y7976D01*
X530993Y8016D01*
X530978Y8061D01*
X530968Y8101D01*
X530953Y8141D01*
X530933Y8181D01*
X530918Y8216D01*
X530898Y8256D01*
X530798Y8396D01*
X530768Y8426D01*
Y9556D01*
X530758Y9681D01*
X530718Y9806D01*
X530658Y9916D01*
X530578Y10016D01*
X530478Y10096D01*
X530368Y10156D01*
X530243Y10196D01*
X530118Y10206D01*
X529993Y10196D01*
X529868Y10156D01*
X529758Y10096D01*
X529658Y10016D01*
X529578Y9916D01*
X529518Y9806D01*
X529478Y9681D01*
X529468Y9556D01*
Y8426D01*
X529438Y8396D01*
X529338Y8256D01*
X529318Y8216D01*
X529303Y8181D01*
X529283Y8141D01*
X529268Y8101D01*
X529258Y8061D01*
X529243Y8016D01*
X529238Y7976D01*
X529228Y7936D01*
X529223Y7891D01*
Y7851D01*
X529218Y7806D01*
X529223Y7761D01*
Y7721D01*
X529228Y7676D01*
X529238Y7636D01*
X529243Y7596D01*
X529258Y7551D01*
X529268Y7511D01*
X529283Y7471D01*
X529303Y7431D01*
X529318Y7396D01*
X529338Y7356D01*
X529438Y7216D01*
X529468Y7186D01*
Y3756D01*
X529478Y3631D01*
X529518Y3506D01*
X529578Y3396D01*
X529658Y3296D01*
X529758Y3216D01*
X529868Y3156D01*
X529993Y3116D01*
X530118Y3106D01*
G37*
G36*
G01X553740D02*
X553865Y3116D01*
X553990Y3156D01*
X554100Y3216D01*
X554200Y3296D01*
X554280Y3396D01*
X554340Y3506D01*
X554380Y3631D01*
X554390Y3756D01*
Y7186D01*
X554420Y7216D01*
X554520Y7356D01*
X554540Y7396D01*
X554555Y7431D01*
X554575Y7471D01*
X554590Y7511D01*
X554600Y7551D01*
X554615Y7596D01*
X554620Y7636D01*
X554630Y7676D01*
X554635Y7721D01*
Y7761D01*
X554640Y7806D01*
X554635Y7851D01*
Y7891D01*
X554630Y7936D01*
X554620Y7976D01*
X554615Y8016D01*
X554600Y8061D01*
X554590Y8101D01*
X554575Y8141D01*
X554555Y8181D01*
X554540Y8216D01*
X554520Y8256D01*
X554420Y8396D01*
X554390Y8426D01*
Y9556D01*
X554380Y9681D01*
X554340Y9806D01*
X554280Y9916D01*
X554200Y10016D01*
X554100Y10096D01*
X553990Y10156D01*
X553865Y10196D01*
X553740Y10206D01*
X553615Y10196D01*
X553490Y10156D01*
X553380Y10096D01*
X553280Y10016D01*
X553200Y9916D01*
X553140Y9806D01*
X553100Y9681D01*
X553090Y9556D01*
Y8426D01*
X553060Y8396D01*
X552960Y8256D01*
X552940Y8216D01*
X552925Y8181D01*
X552905Y8141D01*
X552890Y8101D01*
X552880Y8061D01*
X552865Y8016D01*
X552860Y7976D01*
X552850Y7936D01*
X552845Y7891D01*
Y7851D01*
X552840Y7806D01*
X552845Y7761D01*
Y7721D01*
X552850Y7676D01*
X552860Y7636D01*
X552865Y7596D01*
X552880Y7551D01*
X552890Y7511D01*
X552905Y7471D01*
X552925Y7431D01*
X552940Y7396D01*
X552960Y7356D01*
X553060Y7216D01*
X553090Y7186D01*
Y3756D01*
X553100Y3631D01*
X553140Y3506D01*
X553200Y3396D01*
X553280Y3296D01*
X553380Y3216D01*
X553490Y3156D01*
X553615Y3116D01*
X553740Y3106D01*
G37*
G36*
G01X549015D02*
X549140Y3116D01*
X549265Y3156D01*
X549375Y3216D01*
X549475Y3296D01*
X549555Y3396D01*
X549615Y3506D01*
X549655Y3631D01*
X549665Y3756D01*
Y7186D01*
X549695Y7216D01*
X549795Y7356D01*
X549815Y7396D01*
X549830Y7431D01*
X549850Y7471D01*
X549865Y7511D01*
X549875Y7551D01*
X549890Y7596D01*
X549895Y7636D01*
X549905Y7676D01*
X549910Y7721D01*
Y7761D01*
X549915Y7806D01*
X549910Y7851D01*
Y7891D01*
X549905Y7936D01*
X549895Y7976D01*
X549890Y8016D01*
X549875Y8061D01*
X549865Y8101D01*
X549850Y8141D01*
X549830Y8181D01*
X549815Y8216D01*
X549795Y8256D01*
X549695Y8396D01*
X549665Y8426D01*
Y9556D01*
X549655Y9681D01*
X549615Y9806D01*
X549555Y9916D01*
X549475Y10016D01*
X549375Y10096D01*
X549265Y10156D01*
X549140Y10196D01*
X549015Y10206D01*
X548890Y10196D01*
X548765Y10156D01*
X548655Y10096D01*
X548555Y10016D01*
X548475Y9916D01*
X548415Y9806D01*
X548375Y9681D01*
X548365Y9556D01*
Y8426D01*
X548335Y8396D01*
X548235Y8256D01*
X548215Y8216D01*
X548200Y8181D01*
X548180Y8141D01*
X548165Y8101D01*
X548155Y8061D01*
X548140Y8016D01*
X548135Y7976D01*
X548125Y7936D01*
X548120Y7891D01*
Y7851D01*
X548115Y7806D01*
X548120Y7761D01*
Y7721D01*
X548125Y7676D01*
X548135Y7636D01*
X548140Y7596D01*
X548155Y7551D01*
X548165Y7511D01*
X548180Y7471D01*
X548200Y7431D01*
X548215Y7396D01*
X548235Y7356D01*
X548335Y7216D01*
X548365Y7186D01*
Y3756D01*
X548375Y3631D01*
X548415Y3506D01*
X548475Y3396D01*
X548555Y3296D01*
X548655Y3216D01*
X548765Y3156D01*
X548890Y3116D01*
X549015Y3106D01*
G37*
G36*
G01X544291D02*
X544416Y3116D01*
X544541Y3156D01*
X544651Y3216D01*
X544751Y3296D01*
X544831Y3396D01*
X544891Y3506D01*
X544931Y3631D01*
X544941Y3756D01*
Y7186D01*
X544971Y7216D01*
X545071Y7356D01*
X545091Y7396D01*
X545106Y7431D01*
X545126Y7471D01*
X545141Y7511D01*
X545151Y7551D01*
X545166Y7596D01*
X545171Y7636D01*
X545181Y7676D01*
X545186Y7721D01*
Y7761D01*
X545191Y7806D01*
X545186Y7851D01*
Y7891D01*
X545181Y7936D01*
X545171Y7976D01*
X545166Y8016D01*
X545151Y8061D01*
X545141Y8101D01*
X545126Y8141D01*
X545106Y8181D01*
X545091Y8216D01*
X545071Y8256D01*
X544971Y8396D01*
X544941Y8426D01*
Y9556D01*
X544931Y9681D01*
X544891Y9806D01*
X544831Y9916D01*
X544751Y10016D01*
X544651Y10096D01*
X544541Y10156D01*
X544416Y10196D01*
X544291Y10206D01*
X544166Y10196D01*
X544041Y10156D01*
X543931Y10096D01*
X543831Y10016D01*
X543751Y9916D01*
X543691Y9806D01*
X543651Y9681D01*
X543641Y9556D01*
Y8426D01*
X543611Y8396D01*
X543511Y8256D01*
X543491Y8216D01*
X543476Y8181D01*
X543456Y8141D01*
X543441Y8101D01*
X543431Y8061D01*
X543416Y8016D01*
X543411Y7976D01*
X543401Y7936D01*
X543396Y7891D01*
Y7851D01*
X543391Y7806D01*
X543396Y7761D01*
Y7721D01*
X543401Y7676D01*
X543411Y7636D01*
X543416Y7596D01*
X543431Y7551D01*
X543441Y7511D01*
X543456Y7471D01*
X543476Y7431D01*
X543491Y7396D01*
X543511Y7356D01*
X543611Y7216D01*
X543641Y7186D01*
Y3756D01*
X543651Y3631D01*
X543691Y3506D01*
X543751Y3396D01*
X543831Y3296D01*
X543931Y3216D01*
X544041Y3156D01*
X544166Y3116D01*
X544291Y3106D01*
G37*
G36*
G01X572638D02*
X572763Y3116D01*
X572888Y3156D01*
X572998Y3216D01*
X573098Y3296D01*
X573178Y3396D01*
X573238Y3506D01*
X573278Y3631D01*
X573288Y3756D01*
Y7186D01*
X573318Y7216D01*
X573418Y7356D01*
X573438Y7396D01*
X573453Y7431D01*
X573473Y7471D01*
X573488Y7511D01*
X573498Y7551D01*
X573513Y7596D01*
X573518Y7636D01*
X573528Y7676D01*
X573533Y7721D01*
Y7761D01*
X573538Y7806D01*
X573533Y7851D01*
Y7891D01*
X573528Y7936D01*
X573518Y7976D01*
X573513Y8016D01*
X573498Y8061D01*
X573488Y8101D01*
X573473Y8141D01*
X573453Y8181D01*
X573438Y8216D01*
X573418Y8256D01*
X573318Y8396D01*
X573288Y8426D01*
Y9556D01*
X573278Y9681D01*
X573238Y9806D01*
X573178Y9916D01*
X573098Y10016D01*
X572998Y10096D01*
X572888Y10156D01*
X572763Y10196D01*
X572638Y10206D01*
X572513Y10196D01*
X572388Y10156D01*
X572278Y10096D01*
X572178Y10016D01*
X572098Y9916D01*
X572038Y9806D01*
X571998Y9681D01*
X571988Y9556D01*
Y8426D01*
X571958Y8396D01*
X571858Y8256D01*
X571838Y8216D01*
X571823Y8181D01*
X571803Y8141D01*
X571788Y8101D01*
X571778Y8061D01*
X571763Y8016D01*
X571758Y7976D01*
X571748Y7936D01*
X571743Y7891D01*
Y7851D01*
X571738Y7806D01*
X571743Y7761D01*
Y7721D01*
X571748Y7676D01*
X571758Y7636D01*
X571763Y7596D01*
X571778Y7551D01*
X571788Y7511D01*
X571803Y7471D01*
X571823Y7431D01*
X571838Y7396D01*
X571858Y7356D01*
X571958Y7216D01*
X571988Y7186D01*
Y3756D01*
X571998Y3631D01*
X572038Y3506D01*
X572098Y3396D01*
X572178Y3296D01*
X572278Y3216D01*
X572388Y3156D01*
X572513Y3116D01*
X572638Y3106D01*
G37*
G36*
G01X567913D02*
X568038Y3116D01*
X568163Y3156D01*
X568273Y3216D01*
X568373Y3296D01*
X568453Y3396D01*
X568513Y3506D01*
X568553Y3631D01*
X568563Y3756D01*
Y7186D01*
X568593Y7216D01*
X568693Y7356D01*
X568713Y7396D01*
X568728Y7431D01*
X568748Y7471D01*
X568763Y7511D01*
X568773Y7551D01*
X568788Y7596D01*
X568793Y7636D01*
X568803Y7676D01*
X568808Y7721D01*
Y7761D01*
X568813Y7806D01*
X568808Y7851D01*
Y7891D01*
X568803Y7936D01*
X568793Y7976D01*
X568788Y8016D01*
X568773Y8061D01*
X568763Y8101D01*
X568748Y8141D01*
X568728Y8181D01*
X568713Y8216D01*
X568693Y8256D01*
X568593Y8396D01*
X568563Y8426D01*
Y9556D01*
X568553Y9681D01*
X568513Y9806D01*
X568453Y9916D01*
X568373Y10016D01*
X568273Y10096D01*
X568163Y10156D01*
X568038Y10196D01*
X567913Y10206D01*
X567788Y10196D01*
X567663Y10156D01*
X567553Y10096D01*
X567453Y10016D01*
X567373Y9916D01*
X567313Y9806D01*
X567273Y9681D01*
X567263Y9556D01*
Y8426D01*
X567233Y8396D01*
X567133Y8256D01*
X567113Y8216D01*
X567098Y8181D01*
X567078Y8141D01*
X567063Y8101D01*
X567053Y8061D01*
X567038Y8016D01*
X567033Y7976D01*
X567023Y7936D01*
X567018Y7891D01*
Y7851D01*
X567013Y7806D01*
X567018Y7761D01*
Y7721D01*
X567023Y7676D01*
X567033Y7636D01*
X567038Y7596D01*
X567053Y7551D01*
X567063Y7511D01*
X567078Y7471D01*
X567098Y7431D01*
X567113Y7396D01*
X567133Y7356D01*
X567233Y7216D01*
X567263Y7186D01*
Y3756D01*
X567273Y3631D01*
X567313Y3506D01*
X567373Y3396D01*
X567453Y3296D01*
X567553Y3216D01*
X567663Y3156D01*
X567788Y3116D01*
X567913Y3106D01*
G37*
G36*
G01X563189D02*
X563314Y3116D01*
X563439Y3156D01*
X563549Y3216D01*
X563649Y3296D01*
X563729Y3396D01*
X563789Y3506D01*
X563829Y3631D01*
X563839Y3756D01*
Y7186D01*
X563869Y7216D01*
X563969Y7356D01*
X563989Y7396D01*
X564004Y7431D01*
X564024Y7471D01*
X564039Y7511D01*
X564049Y7551D01*
X564064Y7596D01*
X564069Y7636D01*
X564079Y7676D01*
X564084Y7721D01*
Y7761D01*
X564089Y7806D01*
X564084Y7851D01*
Y7891D01*
X564079Y7936D01*
X564069Y7976D01*
X564064Y8016D01*
X564049Y8061D01*
X564039Y8101D01*
X564024Y8141D01*
X564004Y8181D01*
X563989Y8216D01*
X563969Y8256D01*
X563869Y8396D01*
X563839Y8426D01*
Y9556D01*
X563829Y9681D01*
X563789Y9806D01*
X563729Y9916D01*
X563649Y10016D01*
X563549Y10096D01*
X563439Y10156D01*
X563314Y10196D01*
X563189Y10206D01*
X563064Y10196D01*
X562939Y10156D01*
X562829Y10096D01*
X562729Y10016D01*
X562649Y9916D01*
X562589Y9806D01*
X562549Y9681D01*
X562539Y9556D01*
Y8426D01*
X562509Y8396D01*
X562409Y8256D01*
X562389Y8216D01*
X562374Y8181D01*
X562354Y8141D01*
X562339Y8101D01*
X562329Y8061D01*
X562314Y8016D01*
X562309Y7976D01*
X562299Y7936D01*
X562294Y7891D01*
Y7851D01*
X562289Y7806D01*
X562294Y7761D01*
Y7721D01*
X562299Y7676D01*
X562309Y7636D01*
X562314Y7596D01*
X562329Y7551D01*
X562339Y7511D01*
X562354Y7471D01*
X562374Y7431D01*
X562389Y7396D01*
X562409Y7356D01*
X562509Y7216D01*
X562539Y7186D01*
Y3756D01*
X562549Y3631D01*
X562589Y3506D01*
X562649Y3396D01*
X562729Y3296D01*
X562829Y3216D01*
X562939Y3156D01*
X563064Y3116D01*
X563189Y3106D01*
G37*
G36*
G01X558464D02*
X558589Y3116D01*
X558714Y3156D01*
X558824Y3216D01*
X558924Y3296D01*
X559004Y3396D01*
X559064Y3506D01*
X559104Y3631D01*
X559114Y3756D01*
Y7186D01*
X559144Y7216D01*
X559244Y7356D01*
X559264Y7396D01*
X559279Y7431D01*
X559299Y7471D01*
X559314Y7511D01*
X559324Y7551D01*
X559339Y7596D01*
X559344Y7636D01*
X559354Y7676D01*
X559359Y7721D01*
Y7761D01*
X559364Y7806D01*
X559359Y7851D01*
Y7891D01*
X559354Y7936D01*
X559344Y7976D01*
X559339Y8016D01*
X559324Y8061D01*
X559314Y8101D01*
X559299Y8141D01*
X559279Y8181D01*
X559264Y8216D01*
X559244Y8256D01*
X559144Y8396D01*
X559114Y8426D01*
Y9556D01*
X559104Y9681D01*
X559064Y9806D01*
X559004Y9916D01*
X558924Y10016D01*
X558824Y10096D01*
X558714Y10156D01*
X558589Y10196D01*
X558464Y10206D01*
X558339Y10196D01*
X558214Y10156D01*
X558104Y10096D01*
X558004Y10016D01*
X557924Y9916D01*
X557864Y9806D01*
X557824Y9681D01*
X557814Y9556D01*
Y8426D01*
X557784Y8396D01*
X557684Y8256D01*
X557664Y8216D01*
X557649Y8181D01*
X557629Y8141D01*
X557614Y8101D01*
X557604Y8061D01*
X557589Y8016D01*
X557584Y7976D01*
X557574Y7936D01*
X557569Y7891D01*
Y7851D01*
X557564Y7806D01*
X557569Y7761D01*
Y7721D01*
X557574Y7676D01*
X557584Y7636D01*
X557589Y7596D01*
X557604Y7551D01*
X557614Y7511D01*
X557629Y7471D01*
X557649Y7431D01*
X557664Y7396D01*
X557684Y7356D01*
X557784Y7216D01*
X557814Y7186D01*
Y3756D01*
X557824Y3631D01*
X557864Y3506D01*
X557924Y3396D01*
X558004Y3296D01*
X558104Y3216D01*
X558214Y3156D01*
X558339Y3116D01*
X558464Y3106D01*
G37*
G36*
G01X586811D02*
X586936Y3116D01*
X587061Y3156D01*
X587171Y3216D01*
X587271Y3296D01*
X587351Y3396D01*
X587411Y3506D01*
X587451Y3631D01*
X587461Y3756D01*
Y7186D01*
X587491Y7216D01*
X587591Y7356D01*
X587611Y7396D01*
X587626Y7431D01*
X587646Y7471D01*
X587661Y7511D01*
X587671Y7551D01*
X587686Y7596D01*
X587691Y7636D01*
X587701Y7676D01*
X587706Y7721D01*
Y7761D01*
X587711Y7806D01*
X587706Y7851D01*
Y7891D01*
X587701Y7936D01*
X587691Y7976D01*
X587686Y8016D01*
X587671Y8061D01*
X587661Y8101D01*
X587646Y8141D01*
X587626Y8181D01*
X587611Y8216D01*
X587591Y8256D01*
X587491Y8396D01*
X587461Y8426D01*
Y9556D01*
X587451Y9681D01*
X587411Y9806D01*
X587351Y9916D01*
X587271Y10016D01*
X587171Y10096D01*
X587061Y10156D01*
X586936Y10196D01*
X586811Y10206D01*
X586686Y10196D01*
X586561Y10156D01*
X586451Y10096D01*
X586351Y10016D01*
X586271Y9916D01*
X586211Y9806D01*
X586171Y9681D01*
X586161Y9556D01*
Y8426D01*
X586131Y8396D01*
X586031Y8256D01*
X586011Y8216D01*
X585996Y8181D01*
X585976Y8141D01*
X585961Y8101D01*
X585951Y8061D01*
X585936Y8016D01*
X585931Y7976D01*
X585921Y7936D01*
X585916Y7891D01*
Y7851D01*
X585911Y7806D01*
X585916Y7761D01*
Y7721D01*
X585921Y7676D01*
X585931Y7636D01*
X585936Y7596D01*
X585951Y7551D01*
X585961Y7511D01*
X585976Y7471D01*
X585996Y7431D01*
X586011Y7396D01*
X586031Y7356D01*
X586131Y7216D01*
X586161Y7186D01*
Y3756D01*
X586171Y3631D01*
X586211Y3506D01*
X586271Y3396D01*
X586351Y3296D01*
X586451Y3216D01*
X586561Y3156D01*
X586686Y3116D01*
X586811Y3106D01*
G37*
G36*
G01X582086D02*
X582211Y3116D01*
X582336Y3156D01*
X582446Y3216D01*
X582546Y3296D01*
X582626Y3396D01*
X582686Y3506D01*
X582726Y3631D01*
X582736Y3756D01*
Y7186D01*
X582766Y7216D01*
X582866Y7356D01*
X582886Y7396D01*
X582901Y7431D01*
X582921Y7471D01*
X582936Y7511D01*
X582946Y7551D01*
X582961Y7596D01*
X582966Y7636D01*
X582976Y7676D01*
X582981Y7721D01*
Y7761D01*
X582986Y7806D01*
X582981Y7851D01*
Y7891D01*
X582976Y7936D01*
X582966Y7976D01*
X582961Y8016D01*
X582946Y8061D01*
X582936Y8101D01*
X582921Y8141D01*
X582901Y8181D01*
X582886Y8216D01*
X582866Y8256D01*
X582766Y8396D01*
X582736Y8426D01*
Y9556D01*
X582726Y9681D01*
X582686Y9806D01*
X582626Y9916D01*
X582546Y10016D01*
X582446Y10096D01*
X582336Y10156D01*
X582211Y10196D01*
X582086Y10206D01*
X581961Y10196D01*
X581836Y10156D01*
X581726Y10096D01*
X581626Y10016D01*
X581546Y9916D01*
X581486Y9806D01*
X581446Y9681D01*
X581436Y9556D01*
Y8426D01*
X581406Y8396D01*
X581306Y8256D01*
X581286Y8216D01*
X581271Y8181D01*
X581251Y8141D01*
X581236Y8101D01*
X581226Y8061D01*
X581211Y8016D01*
X581206Y7976D01*
X581196Y7936D01*
X581191Y7891D01*
Y7851D01*
X581186Y7806D01*
X581191Y7761D01*
Y7721D01*
X581196Y7676D01*
X581206Y7636D01*
X581211Y7596D01*
X581226Y7551D01*
X581236Y7511D01*
X581251Y7471D01*
X581271Y7431D01*
X581286Y7396D01*
X581306Y7356D01*
X581406Y7216D01*
X581436Y7186D01*
Y3756D01*
X581446Y3631D01*
X581486Y3506D01*
X581546Y3396D01*
X581626Y3296D01*
X581726Y3216D01*
X581836Y3156D01*
X581961Y3116D01*
X582086Y3106D01*
G37*
G36*
G01X577362D02*
X577487Y3116D01*
X577612Y3156D01*
X577722Y3216D01*
X577822Y3296D01*
X577902Y3396D01*
X577962Y3506D01*
X578002Y3631D01*
X578012Y3756D01*
Y7186D01*
X578042Y7216D01*
X578142Y7356D01*
X578162Y7396D01*
X578177Y7431D01*
X578197Y7471D01*
X578212Y7511D01*
X578222Y7551D01*
X578237Y7596D01*
X578242Y7636D01*
X578252Y7676D01*
X578257Y7721D01*
Y7761D01*
X578262Y7806D01*
X578257Y7851D01*
Y7891D01*
X578252Y7936D01*
X578242Y7976D01*
X578237Y8016D01*
X578222Y8061D01*
X578212Y8101D01*
X578197Y8141D01*
X578177Y8181D01*
X578162Y8216D01*
X578142Y8256D01*
X578042Y8396D01*
X578012Y8426D01*
Y9556D01*
X578002Y9681D01*
X577962Y9806D01*
X577902Y9916D01*
X577822Y10016D01*
X577722Y10096D01*
X577612Y10156D01*
X577487Y10196D01*
X577362Y10206D01*
X577237Y10196D01*
X577112Y10156D01*
X577002Y10096D01*
X576902Y10016D01*
X576822Y9916D01*
X576762Y9806D01*
X576722Y9681D01*
X576712Y9556D01*
Y8426D01*
X576682Y8396D01*
X576582Y8256D01*
X576562Y8216D01*
X576547Y8181D01*
X576527Y8141D01*
X576512Y8101D01*
X576502Y8061D01*
X576487Y8016D01*
X576482Y7976D01*
X576472Y7936D01*
X576467Y7891D01*
Y7851D01*
X576462Y7806D01*
X576467Y7761D01*
Y7721D01*
X576472Y7676D01*
X576482Y7636D01*
X576487Y7596D01*
X576502Y7551D01*
X576512Y7511D01*
X576527Y7471D01*
X576547Y7431D01*
X576562Y7396D01*
X576582Y7356D01*
X576682Y7216D01*
X576712Y7186D01*
Y3756D01*
X576722Y3631D01*
X576762Y3506D01*
X576822Y3396D01*
X576902Y3296D01*
X577002Y3216D01*
X577112Y3156D01*
X577237Y3116D01*
X577362Y3106D01*
G37*
G36*
G01X600984D02*
X601109Y3116D01*
X601234Y3156D01*
X601344Y3216D01*
X601444Y3296D01*
X601524Y3396D01*
X601584Y3506D01*
X601624Y3631D01*
X601634Y3756D01*
Y7186D01*
X601664Y7216D01*
X601764Y7356D01*
X601784Y7396D01*
X601799Y7431D01*
X601819Y7471D01*
X601834Y7511D01*
X601844Y7551D01*
X601859Y7596D01*
X601864Y7636D01*
X601874Y7676D01*
X601879Y7721D01*
Y7761D01*
X601884Y7806D01*
X601879Y7851D01*
Y7891D01*
X601874Y7936D01*
X601864Y7976D01*
X601859Y8016D01*
X601844Y8061D01*
X601834Y8101D01*
X601819Y8141D01*
X601799Y8181D01*
X601784Y8216D01*
X601764Y8256D01*
X601664Y8396D01*
X601634Y8426D01*
Y9556D01*
X601624Y9681D01*
X601584Y9806D01*
X601524Y9916D01*
X601444Y10016D01*
X601344Y10096D01*
X601234Y10156D01*
X601109Y10196D01*
X600984Y10206D01*
X600859Y10196D01*
X600734Y10156D01*
X600624Y10096D01*
X600524Y10016D01*
X600444Y9916D01*
X600384Y9806D01*
X600344Y9681D01*
X600334Y9556D01*
Y8426D01*
X600304Y8396D01*
X600204Y8256D01*
X600184Y8216D01*
X600169Y8181D01*
X600149Y8141D01*
X600134Y8101D01*
X600124Y8061D01*
X600109Y8016D01*
X600104Y7976D01*
X600094Y7936D01*
X600089Y7891D01*
Y7851D01*
X600084Y7806D01*
X600089Y7761D01*
Y7721D01*
X600094Y7676D01*
X600104Y7636D01*
X600109Y7596D01*
X600124Y7551D01*
X600134Y7511D01*
X600149Y7471D01*
X600169Y7431D01*
X600184Y7396D01*
X600204Y7356D01*
X600304Y7216D01*
X600334Y7186D01*
Y3756D01*
X600344Y3631D01*
X600384Y3506D01*
X600444Y3396D01*
X600524Y3296D01*
X600624Y3216D01*
X600734Y3156D01*
X600859Y3116D01*
X600984Y3106D01*
G37*
G36*
G01X615157D02*
X615282Y3116D01*
X615407Y3156D01*
X615517Y3216D01*
X615617Y3296D01*
X615697Y3396D01*
X615757Y3506D01*
X615797Y3631D01*
X615807Y3756D01*
Y7186D01*
X615837Y7216D01*
X615937Y7356D01*
X615957Y7396D01*
X615972Y7431D01*
X615992Y7471D01*
X616007Y7511D01*
X616017Y7551D01*
X616032Y7596D01*
X616037Y7636D01*
X616047Y7676D01*
X616052Y7721D01*
Y7761D01*
X616057Y7806D01*
X616052Y7851D01*
Y7891D01*
X616047Y7936D01*
X616037Y7976D01*
X616032Y8016D01*
X616017Y8061D01*
X616007Y8101D01*
X615992Y8141D01*
X615972Y8181D01*
X615957Y8216D01*
X615937Y8256D01*
X615837Y8396D01*
X615807Y8426D01*
Y9556D01*
X615797Y9681D01*
X615757Y9806D01*
X615697Y9916D01*
X615617Y10016D01*
X615517Y10096D01*
X615407Y10156D01*
X615282Y10196D01*
X615157Y10206D01*
X615032Y10196D01*
X614907Y10156D01*
X614797Y10096D01*
X614697Y10016D01*
X614617Y9916D01*
X614557Y9806D01*
X614517Y9681D01*
X614507Y9556D01*
Y8426D01*
X614477Y8396D01*
X614377Y8256D01*
X614357Y8216D01*
X614342Y8181D01*
X614322Y8141D01*
X614307Y8101D01*
X614297Y8061D01*
X614282Y8016D01*
X614277Y7976D01*
X614267Y7936D01*
X614262Y7891D01*
Y7851D01*
X614257Y7806D01*
X614262Y7761D01*
Y7721D01*
X614267Y7676D01*
X614277Y7636D01*
X614282Y7596D01*
X614297Y7551D01*
X614307Y7511D01*
X614322Y7471D01*
X614342Y7431D01*
X614357Y7396D01*
X614377Y7356D01*
X614477Y7216D01*
X614507Y7186D01*
Y3756D01*
X614517Y3631D01*
X614557Y3506D01*
X614617Y3396D01*
X614697Y3296D01*
X614797Y3216D01*
X614907Y3156D01*
X615032Y3116D01*
X615157Y3106D01*
G37*
G36*
G01X610433D02*
X610558Y3116D01*
X610683Y3156D01*
X610793Y3216D01*
X610893Y3296D01*
X610973Y3396D01*
X611033Y3506D01*
X611073Y3631D01*
X611083Y3756D01*
Y7186D01*
X611113Y7216D01*
X611213Y7356D01*
X611233Y7396D01*
X611248Y7431D01*
X611268Y7471D01*
X611283Y7511D01*
X611293Y7551D01*
X611308Y7596D01*
X611313Y7636D01*
X611323Y7676D01*
X611328Y7721D01*
Y7761D01*
X611333Y7806D01*
X611328Y7851D01*
Y7891D01*
X611323Y7936D01*
X611313Y7976D01*
X611308Y8016D01*
X611293Y8061D01*
X611283Y8101D01*
X611268Y8141D01*
X611248Y8181D01*
X611233Y8216D01*
X611213Y8256D01*
X611113Y8396D01*
X611083Y8426D01*
Y9556D01*
X611073Y9681D01*
X611033Y9806D01*
X610973Y9916D01*
X610893Y10016D01*
X610793Y10096D01*
X610683Y10156D01*
X610558Y10196D01*
X610433Y10206D01*
X610308Y10196D01*
X610183Y10156D01*
X610073Y10096D01*
X609973Y10016D01*
X609893Y9916D01*
X609833Y9806D01*
X609793Y9681D01*
X609783Y9556D01*
Y8426D01*
X609753Y8396D01*
X609653Y8256D01*
X609633Y8216D01*
X609618Y8181D01*
X609598Y8141D01*
X609583Y8101D01*
X609573Y8061D01*
X609558Y8016D01*
X609553Y7976D01*
X609543Y7936D01*
X609538Y7891D01*
Y7851D01*
X609533Y7806D01*
X609538Y7761D01*
Y7721D01*
X609543Y7676D01*
X609553Y7636D01*
X609558Y7596D01*
X609573Y7551D01*
X609583Y7511D01*
X609598Y7471D01*
X609618Y7431D01*
X609633Y7396D01*
X609653Y7356D01*
X609753Y7216D01*
X609783Y7186D01*
Y3756D01*
X609793Y3631D01*
X609833Y3506D01*
X609893Y3396D01*
X609973Y3296D01*
X610073Y3216D01*
X610183Y3156D01*
X610308Y3116D01*
X610433Y3106D01*
G37*
G36*
G01X605708D02*
X605833Y3116D01*
X605958Y3156D01*
X606068Y3216D01*
X606168Y3296D01*
X606248Y3396D01*
X606308Y3506D01*
X606348Y3631D01*
X606358Y3756D01*
Y7186D01*
X606388Y7216D01*
X606488Y7356D01*
X606508Y7396D01*
X606523Y7431D01*
X606543Y7471D01*
X606558Y7511D01*
X606568Y7551D01*
X606583Y7596D01*
X606588Y7636D01*
X606598Y7676D01*
X606603Y7721D01*
Y7761D01*
X606608Y7806D01*
X606603Y7851D01*
Y7891D01*
X606598Y7936D01*
X606588Y7976D01*
X606583Y8016D01*
X606568Y8061D01*
X606558Y8101D01*
X606543Y8141D01*
X606523Y8181D01*
X606508Y8216D01*
X606488Y8256D01*
X606388Y8396D01*
X606358Y8426D01*
Y9556D01*
X606348Y9681D01*
X606308Y9806D01*
X606248Y9916D01*
X606168Y10016D01*
X606068Y10096D01*
X605958Y10156D01*
X605833Y10196D01*
X605708Y10206D01*
X605583Y10196D01*
X605458Y10156D01*
X605348Y10096D01*
X605248Y10016D01*
X605168Y9916D01*
X605108Y9806D01*
X605068Y9681D01*
X605058Y9556D01*
Y8426D01*
X605028Y8396D01*
X604928Y8256D01*
X604908Y8216D01*
X604893Y8181D01*
X604873Y8141D01*
X604858Y8101D01*
X604848Y8061D01*
X604833Y8016D01*
X604828Y7976D01*
X604818Y7936D01*
X604813Y7891D01*
Y7851D01*
X604808Y7806D01*
X604813Y7761D01*
Y7721D01*
X604818Y7676D01*
X604828Y7636D01*
X604833Y7596D01*
X604848Y7551D01*
X604858Y7511D01*
X604873Y7471D01*
X604893Y7431D01*
X604908Y7396D01*
X604928Y7356D01*
X605028Y7216D01*
X605058Y7186D01*
Y3756D01*
X605068Y3631D01*
X605108Y3506D01*
X605168Y3396D01*
X605248Y3296D01*
X605348Y3216D01*
X605458Y3156D01*
X605583Y3116D01*
X605708Y3106D01*
G37*
G36*
G01X634055D02*
X634180Y3116D01*
X634305Y3156D01*
X634415Y3216D01*
X634515Y3296D01*
X634595Y3396D01*
X634655Y3506D01*
X634695Y3631D01*
X634705Y3756D01*
Y7186D01*
X634735Y7216D01*
X634835Y7356D01*
X634855Y7396D01*
X634870Y7431D01*
X634890Y7471D01*
X634905Y7511D01*
X634915Y7551D01*
X634930Y7596D01*
X634935Y7636D01*
X634945Y7676D01*
X634950Y7721D01*
Y7761D01*
X634955Y7806D01*
X634950Y7851D01*
Y7891D01*
X634945Y7936D01*
X634935Y7976D01*
X634930Y8016D01*
X634915Y8061D01*
X634905Y8101D01*
X634890Y8141D01*
X634870Y8181D01*
X634855Y8216D01*
X634835Y8256D01*
X634735Y8396D01*
X634705Y8426D01*
Y9556D01*
X634695Y9681D01*
X634655Y9806D01*
X634595Y9916D01*
X634515Y10016D01*
X634415Y10096D01*
X634305Y10156D01*
X634180Y10196D01*
X634055Y10206D01*
X633930Y10196D01*
X633805Y10156D01*
X633695Y10096D01*
X633595Y10016D01*
X633515Y9916D01*
X633455Y9806D01*
X633415Y9681D01*
X633405Y9556D01*
Y8426D01*
X633375Y8396D01*
X633275Y8256D01*
X633255Y8216D01*
X633240Y8181D01*
X633220Y8141D01*
X633205Y8101D01*
X633195Y8061D01*
X633180Y8016D01*
X633175Y7976D01*
X633165Y7936D01*
X633160Y7891D01*
Y7851D01*
X633155Y7806D01*
X633160Y7761D01*
Y7721D01*
X633165Y7676D01*
X633175Y7636D01*
X633180Y7596D01*
X633195Y7551D01*
X633205Y7511D01*
X633220Y7471D01*
X633240Y7431D01*
X633255Y7396D01*
X633275Y7356D01*
X633375Y7216D01*
X633405Y7186D01*
Y3756D01*
X633415Y3631D01*
X633455Y3506D01*
X633515Y3396D01*
X633595Y3296D01*
X633695Y3216D01*
X633805Y3156D01*
X633930Y3116D01*
X634055Y3106D01*
G37*
G36*
G01X629330D02*
X629455Y3116D01*
X629580Y3156D01*
X629690Y3216D01*
X629790Y3296D01*
X629870Y3396D01*
X629930Y3506D01*
X629970Y3631D01*
X629980Y3756D01*
Y7186D01*
X630010Y7216D01*
X630110Y7356D01*
X630130Y7396D01*
X630145Y7431D01*
X630165Y7471D01*
X630180Y7511D01*
X630190Y7551D01*
X630205Y7596D01*
X630210Y7636D01*
X630220Y7676D01*
X630225Y7721D01*
Y7761D01*
X630230Y7806D01*
X630225Y7851D01*
Y7891D01*
X630220Y7936D01*
X630210Y7976D01*
X630205Y8016D01*
X630190Y8061D01*
X630180Y8101D01*
X630165Y8141D01*
X630145Y8181D01*
X630130Y8216D01*
X630110Y8256D01*
X630010Y8396D01*
X629980Y8426D01*
Y9556D01*
X629970Y9681D01*
X629930Y9806D01*
X629870Y9916D01*
X629790Y10016D01*
X629690Y10096D01*
X629580Y10156D01*
X629455Y10196D01*
X629330Y10206D01*
X629205Y10196D01*
X629080Y10156D01*
X628970Y10096D01*
X628870Y10016D01*
X628790Y9916D01*
X628730Y9806D01*
X628690Y9681D01*
X628680Y9556D01*
Y8426D01*
X628650Y8396D01*
X628550Y8256D01*
X628530Y8216D01*
X628515Y8181D01*
X628495Y8141D01*
X628480Y8101D01*
X628470Y8061D01*
X628455Y8016D01*
X628450Y7976D01*
X628440Y7936D01*
X628435Y7891D01*
Y7851D01*
X628430Y7806D01*
X628435Y7761D01*
Y7721D01*
X628440Y7676D01*
X628450Y7636D01*
X628455Y7596D01*
X628470Y7551D01*
X628480Y7511D01*
X628495Y7471D01*
X628515Y7431D01*
X628530Y7396D01*
X628550Y7356D01*
X628650Y7216D01*
X628680Y7186D01*
Y3756D01*
X628690Y3631D01*
X628730Y3506D01*
X628790Y3396D01*
X628870Y3296D01*
X628970Y3216D01*
X629080Y3156D01*
X629205Y3116D01*
X629330Y3106D01*
G37*
G36*
G01X624606D02*
X624731Y3116D01*
X624856Y3156D01*
X624966Y3216D01*
X625066Y3296D01*
X625146Y3396D01*
X625206Y3506D01*
X625246Y3631D01*
X625256Y3756D01*
Y7186D01*
X625286Y7216D01*
X625386Y7356D01*
X625406Y7396D01*
X625421Y7431D01*
X625441Y7471D01*
X625456Y7511D01*
X625466Y7551D01*
X625481Y7596D01*
X625486Y7636D01*
X625496Y7676D01*
X625501Y7721D01*
Y7761D01*
X625506Y7806D01*
X625501Y7851D01*
Y7891D01*
X625496Y7936D01*
X625486Y7976D01*
X625481Y8016D01*
X625466Y8061D01*
X625456Y8101D01*
X625441Y8141D01*
X625421Y8181D01*
X625406Y8216D01*
X625386Y8256D01*
X625286Y8396D01*
X625256Y8426D01*
Y9556D01*
X625246Y9681D01*
X625206Y9806D01*
X625146Y9916D01*
X625066Y10016D01*
X624966Y10096D01*
X624856Y10156D01*
X624731Y10196D01*
X624606Y10206D01*
X624481Y10196D01*
X624356Y10156D01*
X624246Y10096D01*
X624146Y10016D01*
X624066Y9916D01*
X624006Y9806D01*
X623966Y9681D01*
X623956Y9556D01*
Y8426D01*
X623926Y8396D01*
X623826Y8256D01*
X623806Y8216D01*
X623791Y8181D01*
X623771Y8141D01*
X623756Y8101D01*
X623746Y8061D01*
X623731Y8016D01*
X623726Y7976D01*
X623716Y7936D01*
X623711Y7891D01*
Y7851D01*
X623706Y7806D01*
X623711Y7761D01*
Y7721D01*
X623716Y7676D01*
X623726Y7636D01*
X623731Y7596D01*
X623746Y7551D01*
X623756Y7511D01*
X623771Y7471D01*
X623791Y7431D01*
X623806Y7396D01*
X623826Y7356D01*
X623926Y7216D01*
X623956Y7186D01*
Y3756D01*
X623966Y3631D01*
X624006Y3506D01*
X624066Y3396D01*
X624146Y3296D01*
X624246Y3216D01*
X624356Y3156D01*
X624481Y3116D01*
X624606Y3106D01*
G37*
G36*
G01X619882D02*
X620007Y3116D01*
X620132Y3156D01*
X620242Y3216D01*
X620342Y3296D01*
X620422Y3396D01*
X620482Y3506D01*
X620522Y3631D01*
X620532Y3756D01*
Y7186D01*
X620562Y7216D01*
X620662Y7356D01*
X620682Y7396D01*
X620697Y7431D01*
X620717Y7471D01*
X620732Y7511D01*
X620742Y7551D01*
X620757Y7596D01*
X620762Y7636D01*
X620772Y7676D01*
X620777Y7721D01*
Y7761D01*
X620782Y7806D01*
X620777Y7851D01*
Y7891D01*
X620772Y7936D01*
X620762Y7976D01*
X620757Y8016D01*
X620742Y8061D01*
X620732Y8101D01*
X620717Y8141D01*
X620697Y8181D01*
X620682Y8216D01*
X620662Y8256D01*
X620562Y8396D01*
X620532Y8426D01*
Y9556D01*
X620522Y9681D01*
X620482Y9806D01*
X620422Y9916D01*
X620342Y10016D01*
X620242Y10096D01*
X620132Y10156D01*
X620007Y10196D01*
X619882Y10206D01*
X619757Y10196D01*
X619632Y10156D01*
X619522Y10096D01*
X619422Y10016D01*
X619342Y9916D01*
X619282Y9806D01*
X619242Y9681D01*
X619232Y9556D01*
Y8426D01*
X619202Y8396D01*
X619102Y8256D01*
X619082Y8216D01*
X619067Y8181D01*
X619047Y8141D01*
X619032Y8101D01*
X619022Y8061D01*
X619007Y8016D01*
X619002Y7976D01*
X618992Y7936D01*
X618987Y7891D01*
Y7851D01*
X618982Y7806D01*
X618987Y7761D01*
Y7721D01*
X618992Y7676D01*
X619002Y7636D01*
X619007Y7596D01*
X619022Y7551D01*
X619032Y7511D01*
X619047Y7471D01*
X619067Y7431D01*
X619082Y7396D01*
X619102Y7356D01*
X619202Y7216D01*
X619232Y7186D01*
Y3756D01*
X619242Y3631D01*
X619282Y3506D01*
X619342Y3396D01*
X619422Y3296D01*
X619522Y3216D01*
X619632Y3156D01*
X619757Y3116D01*
X619882Y3106D01*
G37*
G36*
G01X648228D02*
X648353Y3116D01*
X648478Y3156D01*
X648588Y3216D01*
X648688Y3296D01*
X648768Y3396D01*
X648828Y3506D01*
X648868Y3631D01*
X648878Y3756D01*
Y7186D01*
X648908Y7216D01*
X649008Y7356D01*
X649028Y7396D01*
X649043Y7431D01*
X649063Y7471D01*
X649078Y7511D01*
X649088Y7551D01*
X649103Y7596D01*
X649108Y7636D01*
X649118Y7676D01*
X649123Y7721D01*
Y7761D01*
X649128Y7806D01*
X649123Y7851D01*
Y7891D01*
X649118Y7936D01*
X649108Y7976D01*
X649103Y8016D01*
X649088Y8061D01*
X649078Y8101D01*
X649063Y8141D01*
X649043Y8181D01*
X649028Y8216D01*
X649008Y8256D01*
X648908Y8396D01*
X648878Y8426D01*
Y9556D01*
X648868Y9681D01*
X648828Y9806D01*
X648768Y9916D01*
X648688Y10016D01*
X648588Y10096D01*
X648478Y10156D01*
X648353Y10196D01*
X648228Y10206D01*
X648103Y10196D01*
X647978Y10156D01*
X647868Y10096D01*
X647768Y10016D01*
X647688Y9916D01*
X647628Y9806D01*
X647588Y9681D01*
X647578Y9556D01*
Y8426D01*
X647548Y8396D01*
X647448Y8256D01*
X647428Y8216D01*
X647413Y8181D01*
X647393Y8141D01*
X647378Y8101D01*
X647368Y8061D01*
X647353Y8016D01*
X647348Y7976D01*
X647338Y7936D01*
X647333Y7891D01*
Y7851D01*
X647328Y7806D01*
X647333Y7761D01*
Y7721D01*
X647338Y7676D01*
X647348Y7636D01*
X647353Y7596D01*
X647368Y7551D01*
X647378Y7511D01*
X647393Y7471D01*
X647413Y7431D01*
X647428Y7396D01*
X647448Y7356D01*
X647548Y7216D01*
X647578Y7186D01*
Y3756D01*
X647588Y3631D01*
X647628Y3506D01*
X647688Y3396D01*
X647768Y3296D01*
X647868Y3216D01*
X647978Y3156D01*
X648103Y3116D01*
X648228Y3106D01*
G37*
G36*
G01X643504D02*
X643629Y3116D01*
X643754Y3156D01*
X643864Y3216D01*
X643964Y3296D01*
X644044Y3396D01*
X644104Y3506D01*
X644144Y3631D01*
X644154Y3756D01*
Y7186D01*
X644184Y7216D01*
X644284Y7356D01*
X644304Y7396D01*
X644319Y7431D01*
X644339Y7471D01*
X644354Y7511D01*
X644364Y7551D01*
X644379Y7596D01*
X644384Y7636D01*
X644394Y7676D01*
X644399Y7721D01*
Y7761D01*
X644404Y7806D01*
X644399Y7851D01*
Y7891D01*
X644394Y7936D01*
X644384Y7976D01*
X644379Y8016D01*
X644364Y8061D01*
X644354Y8101D01*
X644339Y8141D01*
X644319Y8181D01*
X644304Y8216D01*
X644284Y8256D01*
X644184Y8396D01*
X644154Y8426D01*
Y9556D01*
X644144Y9681D01*
X644104Y9806D01*
X644044Y9916D01*
X643964Y10016D01*
X643864Y10096D01*
X643754Y10156D01*
X643629Y10196D01*
X643504Y10206D01*
X643379Y10196D01*
X643254Y10156D01*
X643144Y10096D01*
X643044Y10016D01*
X642964Y9916D01*
X642904Y9806D01*
X642864Y9681D01*
X642854Y9556D01*
Y8426D01*
X642824Y8396D01*
X642724Y8256D01*
X642704Y8216D01*
X642689Y8181D01*
X642669Y8141D01*
X642654Y8101D01*
X642644Y8061D01*
X642629Y8016D01*
X642624Y7976D01*
X642614Y7936D01*
X642609Y7891D01*
Y7851D01*
X642604Y7806D01*
X642609Y7761D01*
Y7721D01*
X642614Y7676D01*
X642624Y7636D01*
X642629Y7596D01*
X642644Y7551D01*
X642654Y7511D01*
X642669Y7471D01*
X642689Y7431D01*
X642704Y7396D01*
X642724Y7356D01*
X642824Y7216D01*
X642854Y7186D01*
Y3756D01*
X642864Y3631D01*
X642904Y3506D01*
X642964Y3396D01*
X643044Y3296D01*
X643144Y3216D01*
X643254Y3156D01*
X643379Y3116D01*
X643504Y3106D01*
G37*
G36*
G01X638779D02*
X638904Y3116D01*
X639029Y3156D01*
X639139Y3216D01*
X639239Y3296D01*
X639319Y3396D01*
X639379Y3506D01*
X639419Y3631D01*
X639429Y3756D01*
Y7186D01*
X639459Y7216D01*
X639559Y7356D01*
X639579Y7396D01*
X639594Y7431D01*
X639614Y7471D01*
X639629Y7511D01*
X639639Y7551D01*
X639654Y7596D01*
X639659Y7636D01*
X639669Y7676D01*
X639674Y7721D01*
Y7761D01*
X639679Y7806D01*
X639674Y7851D01*
Y7891D01*
X639669Y7936D01*
X639659Y7976D01*
X639654Y8016D01*
X639639Y8061D01*
X639629Y8101D01*
X639614Y8141D01*
X639594Y8181D01*
X639579Y8216D01*
X639559Y8256D01*
X639459Y8396D01*
X639429Y8426D01*
Y9556D01*
X639419Y9681D01*
X639379Y9806D01*
X639319Y9916D01*
X639239Y10016D01*
X639139Y10096D01*
X639029Y10156D01*
X638904Y10196D01*
X638779Y10206D01*
X638654Y10196D01*
X638529Y10156D01*
X638419Y10096D01*
X638319Y10016D01*
X638239Y9916D01*
X638179Y9806D01*
X638139Y9681D01*
X638129Y9556D01*
Y8426D01*
X638099Y8396D01*
X637999Y8256D01*
X637979Y8216D01*
X637964Y8181D01*
X637944Y8141D01*
X637929Y8101D01*
X637919Y8061D01*
X637904Y8016D01*
X637899Y7976D01*
X637889Y7936D01*
X637884Y7891D01*
Y7851D01*
X637879Y7806D01*
X637884Y7761D01*
Y7721D01*
X637889Y7676D01*
X637899Y7636D01*
X637904Y7596D01*
X637919Y7551D01*
X637929Y7511D01*
X637944Y7471D01*
X637964Y7431D01*
X637979Y7396D01*
X637999Y7356D01*
X638099Y7216D01*
X638129Y7186D01*
Y3756D01*
X638139Y3631D01*
X638179Y3506D01*
X638239Y3396D01*
X638319Y3296D01*
X638419Y3216D01*
X638529Y3156D01*
X638654Y3116D01*
X638779Y3106D01*
G37*
G36*
G01X662401D02*
X662526Y3116D01*
X662651Y3156D01*
X662761Y3216D01*
X662861Y3296D01*
X662941Y3396D01*
X663001Y3506D01*
X663041Y3631D01*
X663051Y3756D01*
Y7186D01*
X663081Y7216D01*
X663181Y7356D01*
X663201Y7396D01*
X663216Y7431D01*
X663236Y7471D01*
X663251Y7511D01*
X663261Y7551D01*
X663276Y7596D01*
X663281Y7636D01*
X663291Y7676D01*
X663296Y7721D01*
Y7761D01*
X663301Y7806D01*
X663296Y7851D01*
Y7891D01*
X663291Y7936D01*
X663281Y7976D01*
X663276Y8016D01*
X663261Y8061D01*
X663251Y8101D01*
X663236Y8141D01*
X663216Y8181D01*
X663201Y8216D01*
X663181Y8256D01*
X663081Y8396D01*
X663051Y8426D01*
Y9556D01*
X663041Y9681D01*
X663001Y9806D01*
X662941Y9916D01*
X662861Y10016D01*
X662761Y10096D01*
X662651Y10156D01*
X662526Y10196D01*
X662401Y10206D01*
X662276Y10196D01*
X662151Y10156D01*
X662041Y10096D01*
X661941Y10016D01*
X661861Y9916D01*
X661801Y9806D01*
X661761Y9681D01*
X661751Y9556D01*
Y8426D01*
X661721Y8396D01*
X661621Y8256D01*
X661601Y8216D01*
X661586Y8181D01*
X661566Y8141D01*
X661551Y8101D01*
X661541Y8061D01*
X661526Y8016D01*
X661521Y7976D01*
X661511Y7936D01*
X661506Y7891D01*
Y7851D01*
X661501Y7806D01*
X661506Y7761D01*
Y7721D01*
X661511Y7676D01*
X661521Y7636D01*
X661526Y7596D01*
X661541Y7551D01*
X661551Y7511D01*
X661566Y7471D01*
X661586Y7431D01*
X661601Y7396D01*
X661621Y7356D01*
X661721Y7216D01*
X661751Y7186D01*
Y3756D01*
X661761Y3631D01*
X661801Y3506D01*
X661861Y3396D01*
X661941Y3296D01*
X662041Y3216D01*
X662151Y3156D01*
X662276Y3116D01*
X662401Y3106D01*
G37*
G36*
G01X657677D02*
X657802Y3116D01*
X657927Y3156D01*
X658037Y3216D01*
X658137Y3296D01*
X658217Y3396D01*
X658277Y3506D01*
X658317Y3631D01*
X658327Y3756D01*
Y7186D01*
X658357Y7216D01*
X658457Y7356D01*
X658477Y7396D01*
X658492Y7431D01*
X658512Y7471D01*
X658527Y7511D01*
X658537Y7551D01*
X658552Y7596D01*
X658557Y7636D01*
X658567Y7676D01*
X658572Y7721D01*
Y7761D01*
X658577Y7806D01*
X658572Y7851D01*
Y7891D01*
X658567Y7936D01*
X658557Y7976D01*
X658552Y8016D01*
X658537Y8061D01*
X658527Y8101D01*
X658512Y8141D01*
X658492Y8181D01*
X658477Y8216D01*
X658457Y8256D01*
X658357Y8396D01*
X658327Y8426D01*
Y9556D01*
X658317Y9681D01*
X658277Y9806D01*
X658217Y9916D01*
X658137Y10016D01*
X658037Y10096D01*
X657927Y10156D01*
X657802Y10196D01*
X657677Y10206D01*
X657552Y10196D01*
X657427Y10156D01*
X657317Y10096D01*
X657217Y10016D01*
X657137Y9916D01*
X657077Y9806D01*
X657037Y9681D01*
X657027Y9556D01*
Y8426D01*
X656997Y8396D01*
X656897Y8256D01*
X656877Y8216D01*
X656862Y8181D01*
X656842Y8141D01*
X656827Y8101D01*
X656817Y8061D01*
X656802Y8016D01*
X656797Y7976D01*
X656787Y7936D01*
X656782Y7891D01*
Y7851D01*
X656777Y7806D01*
X656782Y7761D01*
Y7721D01*
X656787Y7676D01*
X656797Y7636D01*
X656802Y7596D01*
X656817Y7551D01*
X656827Y7511D01*
X656842Y7471D01*
X656862Y7431D01*
X656877Y7396D01*
X656897Y7356D01*
X656997Y7216D01*
X657027Y7186D01*
Y3756D01*
X657037Y3631D01*
X657077Y3506D01*
X657137Y3396D01*
X657217Y3296D01*
X657317Y3216D01*
X657427Y3156D01*
X657552Y3116D01*
X657677Y3106D01*
G37*
G36*
G01X652952D02*
X653077Y3116D01*
X653202Y3156D01*
X653312Y3216D01*
X653412Y3296D01*
X653492Y3396D01*
X653552Y3506D01*
X653592Y3631D01*
X653602Y3756D01*
Y7186D01*
X653632Y7216D01*
X653732Y7356D01*
X653752Y7396D01*
X653767Y7431D01*
X653787Y7471D01*
X653802Y7511D01*
X653812Y7551D01*
X653827Y7596D01*
X653832Y7636D01*
X653842Y7676D01*
X653847Y7721D01*
Y7761D01*
X653852Y7806D01*
X653847Y7851D01*
Y7891D01*
X653842Y7936D01*
X653832Y7976D01*
X653827Y8016D01*
X653812Y8061D01*
X653802Y8101D01*
X653787Y8141D01*
X653767Y8181D01*
X653752Y8216D01*
X653732Y8256D01*
X653632Y8396D01*
X653602Y8426D01*
Y9556D01*
X653592Y9681D01*
X653552Y9806D01*
X653492Y9916D01*
X653412Y10016D01*
X653312Y10096D01*
X653202Y10156D01*
X653077Y10196D01*
X652952Y10206D01*
X652827Y10196D01*
X652702Y10156D01*
X652592Y10096D01*
X652492Y10016D01*
X652412Y9916D01*
X652352Y9806D01*
X652312Y9681D01*
X652302Y9556D01*
Y8426D01*
X652272Y8396D01*
X652172Y8256D01*
X652152Y8216D01*
X652137Y8181D01*
X652117Y8141D01*
X652102Y8101D01*
X652092Y8061D01*
X652077Y8016D01*
X652072Y7976D01*
X652062Y7936D01*
X652057Y7891D01*
Y7851D01*
X652052Y7806D01*
X652057Y7761D01*
Y7721D01*
X652062Y7676D01*
X652072Y7636D01*
X652077Y7596D01*
X652092Y7551D01*
X652102Y7511D01*
X652117Y7471D01*
X652137Y7431D01*
X652152Y7396D01*
X652172Y7356D01*
X652272Y7216D01*
X652302Y7186D01*
Y3756D01*
X652312Y3631D01*
X652352Y3506D01*
X652412Y3396D01*
X652492Y3296D01*
X652592Y3216D01*
X652702Y3156D01*
X652827Y3116D01*
X652952Y3106D01*
G37*
G36*
G01X676575D02*
X676700Y3116D01*
X676825Y3156D01*
X676935Y3216D01*
X677035Y3296D01*
X677115Y3396D01*
X677175Y3506D01*
X677215Y3631D01*
X677225Y3756D01*
Y7186D01*
X677255Y7216D01*
X677355Y7356D01*
X677375Y7396D01*
X677390Y7431D01*
X677410Y7471D01*
X677425Y7511D01*
X677435Y7551D01*
X677450Y7596D01*
X677455Y7636D01*
X677465Y7676D01*
X677470Y7721D01*
Y7761D01*
X677475Y7806D01*
X677470Y7851D01*
Y7891D01*
X677465Y7936D01*
X677455Y7976D01*
X677450Y8016D01*
X677435Y8061D01*
X677425Y8101D01*
X677410Y8141D01*
X677390Y8181D01*
X677375Y8216D01*
X677355Y8256D01*
X677255Y8396D01*
X677225Y8426D01*
Y9556D01*
X677215Y9681D01*
X677175Y9806D01*
X677115Y9916D01*
X677035Y10016D01*
X676935Y10096D01*
X676825Y10156D01*
X676700Y10196D01*
X676575Y10206D01*
X676450Y10196D01*
X676325Y10156D01*
X676215Y10096D01*
X676115Y10016D01*
X676035Y9916D01*
X675975Y9806D01*
X675935Y9681D01*
X675925Y9556D01*
Y8426D01*
X675895Y8396D01*
X675795Y8256D01*
X675775Y8216D01*
X675760Y8181D01*
X675740Y8141D01*
X675725Y8101D01*
X675715Y8061D01*
X675700Y8016D01*
X675695Y7976D01*
X675685Y7936D01*
X675680Y7891D01*
Y7851D01*
X675675Y7806D01*
X675680Y7761D01*
Y7721D01*
X675685Y7676D01*
X675695Y7636D01*
X675700Y7596D01*
X675715Y7551D01*
X675725Y7511D01*
X675740Y7471D01*
X675760Y7431D01*
X675775Y7396D01*
X675795Y7356D01*
X675895Y7216D01*
X675925Y7186D01*
Y3756D01*
X675935Y3631D01*
X675975Y3506D01*
X676035Y3396D01*
X676115Y3296D01*
X676215Y3216D01*
X676325Y3156D01*
X676450Y3116D01*
X676575Y3106D01*
G37*
G36*
G01X671850D02*
X671975Y3116D01*
X672100Y3156D01*
X672210Y3216D01*
X672310Y3296D01*
X672390Y3396D01*
X672450Y3506D01*
X672490Y3631D01*
X672500Y3756D01*
Y7186D01*
X672530Y7216D01*
X672630Y7356D01*
X672650Y7396D01*
X672665Y7431D01*
X672685Y7471D01*
X672700Y7511D01*
X672710Y7551D01*
X672725Y7596D01*
X672730Y7636D01*
X672740Y7676D01*
X672745Y7721D01*
Y7761D01*
X672750Y7806D01*
X672745Y7851D01*
Y7891D01*
X672740Y7936D01*
X672730Y7976D01*
X672725Y8016D01*
X672710Y8061D01*
X672700Y8101D01*
X672685Y8141D01*
X672665Y8181D01*
X672650Y8216D01*
X672630Y8256D01*
X672530Y8396D01*
X672500Y8426D01*
Y9556D01*
X672490Y9681D01*
X672450Y9806D01*
X672390Y9916D01*
X672310Y10016D01*
X672210Y10096D01*
X672100Y10156D01*
X671975Y10196D01*
X671850Y10206D01*
X671725Y10196D01*
X671600Y10156D01*
X671490Y10096D01*
X671390Y10016D01*
X671310Y9916D01*
X671250Y9806D01*
X671210Y9681D01*
X671200Y9556D01*
Y8426D01*
X671170Y8396D01*
X671070Y8256D01*
X671050Y8216D01*
X671035Y8181D01*
X671015Y8141D01*
X671000Y8101D01*
X670990Y8061D01*
X670975Y8016D01*
X670970Y7976D01*
X670960Y7936D01*
X670955Y7891D01*
Y7851D01*
X670950Y7806D01*
X670955Y7761D01*
Y7721D01*
X670960Y7676D01*
X670970Y7636D01*
X670975Y7596D01*
X670990Y7551D01*
X671000Y7511D01*
X671015Y7471D01*
X671035Y7431D01*
X671050Y7396D01*
X671070Y7356D01*
X671170Y7216D01*
X671200Y7186D01*
Y3756D01*
X671210Y3631D01*
X671250Y3506D01*
X671310Y3396D01*
X671390Y3296D01*
X671490Y3216D01*
X671600Y3156D01*
X671725Y3116D01*
X671850Y3106D01*
G37*
G36*
G01X667126D02*
X667251Y3116D01*
X667376Y3156D01*
X667486Y3216D01*
X667586Y3296D01*
X667666Y3396D01*
X667726Y3506D01*
X667766Y3631D01*
X667776Y3756D01*
Y7186D01*
X667806Y7216D01*
X667906Y7356D01*
X667926Y7396D01*
X667941Y7431D01*
X667961Y7471D01*
X667976Y7511D01*
X667986Y7551D01*
X668001Y7596D01*
X668006Y7636D01*
X668016Y7676D01*
X668021Y7721D01*
Y7761D01*
X668026Y7806D01*
X668021Y7851D01*
Y7891D01*
X668016Y7936D01*
X668006Y7976D01*
X668001Y8016D01*
X667986Y8061D01*
X667976Y8101D01*
X667961Y8141D01*
X667941Y8181D01*
X667926Y8216D01*
X667906Y8256D01*
X667806Y8396D01*
X667776Y8426D01*
Y9556D01*
X667766Y9681D01*
X667726Y9806D01*
X667666Y9916D01*
X667586Y10016D01*
X667486Y10096D01*
X667376Y10156D01*
X667251Y10196D01*
X667126Y10206D01*
X667001Y10196D01*
X666876Y10156D01*
X666766Y10096D01*
X666666Y10016D01*
X666586Y9916D01*
X666526Y9806D01*
X666486Y9681D01*
X666476Y9556D01*
Y8426D01*
X666446Y8396D01*
X666346Y8256D01*
X666326Y8216D01*
X666311Y8181D01*
X666291Y8141D01*
X666276Y8101D01*
X666266Y8061D01*
X666251Y8016D01*
X666246Y7976D01*
X666236Y7936D01*
X666231Y7891D01*
Y7851D01*
X666226Y7806D01*
X666231Y7761D01*
Y7721D01*
X666236Y7676D01*
X666246Y7636D01*
X666251Y7596D01*
X666266Y7551D01*
X666276Y7511D01*
X666291Y7471D01*
X666311Y7431D01*
X666326Y7396D01*
X666346Y7356D01*
X666446Y7216D01*
X666476Y7186D01*
Y3756D01*
X666486Y3631D01*
X666526Y3506D01*
X666586Y3396D01*
X666666Y3296D01*
X666766Y3216D01*
X666876Y3156D01*
X667001Y3116D01*
X667126Y3106D01*
G37*
G36*
G01X695472D02*
X695597Y3116D01*
X695722Y3156D01*
X695832Y3216D01*
X695932Y3296D01*
X696012Y3396D01*
X696072Y3506D01*
X696112Y3631D01*
X696122Y3756D01*
Y7186D01*
X696152Y7216D01*
X696252Y7356D01*
X696272Y7396D01*
X696287Y7431D01*
X696307Y7471D01*
X696322Y7511D01*
X696332Y7551D01*
X696347Y7596D01*
X696352Y7636D01*
X696362Y7676D01*
X696367Y7721D01*
Y7761D01*
X696372Y7806D01*
X696367Y7851D01*
Y7891D01*
X696362Y7936D01*
X696352Y7976D01*
X696347Y8016D01*
X696332Y8061D01*
X696322Y8101D01*
X696307Y8141D01*
X696287Y8181D01*
X696272Y8216D01*
X696252Y8256D01*
X696152Y8396D01*
X696122Y8426D01*
Y9556D01*
X696112Y9681D01*
X696072Y9806D01*
X696012Y9916D01*
X695932Y10016D01*
X695832Y10096D01*
X695722Y10156D01*
X695597Y10196D01*
X695472Y10206D01*
X695347Y10196D01*
X695222Y10156D01*
X695112Y10096D01*
X695012Y10016D01*
X694932Y9916D01*
X694872Y9806D01*
X694832Y9681D01*
X694822Y9556D01*
Y8426D01*
X694792Y8396D01*
X694692Y8256D01*
X694672Y8216D01*
X694657Y8181D01*
X694637Y8141D01*
X694622Y8101D01*
X694612Y8061D01*
X694597Y8016D01*
X694592Y7976D01*
X694582Y7936D01*
X694577Y7891D01*
Y7851D01*
X694572Y7806D01*
X694577Y7761D01*
Y7721D01*
X694582Y7676D01*
X694592Y7636D01*
X694597Y7596D01*
X694612Y7551D01*
X694622Y7511D01*
X694637Y7471D01*
X694657Y7431D01*
X694672Y7396D01*
X694692Y7356D01*
X694792Y7216D01*
X694822Y7186D01*
Y3756D01*
X694832Y3631D01*
X694872Y3506D01*
X694932Y3396D01*
X695012Y3296D01*
X695112Y3216D01*
X695222Y3156D01*
X695347Y3116D01*
X695472Y3106D01*
G37*
G36*
G01X690748D02*
X690873Y3116D01*
X690998Y3156D01*
X691108Y3216D01*
X691208Y3296D01*
X691288Y3396D01*
X691348Y3506D01*
X691388Y3631D01*
X691398Y3756D01*
Y7186D01*
X691428Y7216D01*
X691528Y7356D01*
X691548Y7396D01*
X691563Y7431D01*
X691583Y7471D01*
X691598Y7511D01*
X691608Y7551D01*
X691623Y7596D01*
X691628Y7636D01*
X691638Y7676D01*
X691643Y7721D01*
Y7761D01*
X691648Y7806D01*
X691643Y7851D01*
Y7891D01*
X691638Y7936D01*
X691628Y7976D01*
X691623Y8016D01*
X691608Y8061D01*
X691598Y8101D01*
X691583Y8141D01*
X691563Y8181D01*
X691548Y8216D01*
X691528Y8256D01*
X691428Y8396D01*
X691398Y8426D01*
Y9556D01*
X691388Y9681D01*
X691348Y9806D01*
X691288Y9916D01*
X691208Y10016D01*
X691108Y10096D01*
X690998Y10156D01*
X690873Y10196D01*
X690748Y10206D01*
X690623Y10196D01*
X690498Y10156D01*
X690388Y10096D01*
X690288Y10016D01*
X690208Y9916D01*
X690148Y9806D01*
X690108Y9681D01*
X690098Y9556D01*
Y8426D01*
X690068Y8396D01*
X689968Y8256D01*
X689948Y8216D01*
X689933Y8181D01*
X689913Y8141D01*
X689898Y8101D01*
X689888Y8061D01*
X689873Y8016D01*
X689868Y7976D01*
X689858Y7936D01*
X689853Y7891D01*
Y7851D01*
X689848Y7806D01*
X689853Y7761D01*
Y7721D01*
X689858Y7676D01*
X689868Y7636D01*
X689873Y7596D01*
X689888Y7551D01*
X689898Y7511D01*
X689913Y7471D01*
X689933Y7431D01*
X689948Y7396D01*
X689968Y7356D01*
X690068Y7216D01*
X690098Y7186D01*
Y3756D01*
X690108Y3631D01*
X690148Y3506D01*
X690208Y3396D01*
X690288Y3296D01*
X690388Y3216D01*
X690498Y3156D01*
X690623Y3116D01*
X690748Y3106D01*
G37*
G36*
G01X686023D02*
X686148Y3116D01*
X686273Y3156D01*
X686383Y3216D01*
X686483Y3296D01*
X686563Y3396D01*
X686623Y3506D01*
X686663Y3631D01*
X686673Y3756D01*
Y7186D01*
X686703Y7216D01*
X686803Y7356D01*
X686823Y7396D01*
X686838Y7431D01*
X686858Y7471D01*
X686873Y7511D01*
X686883Y7551D01*
X686898Y7596D01*
X686903Y7636D01*
X686913Y7676D01*
X686918Y7721D01*
Y7761D01*
X686923Y7806D01*
X686918Y7851D01*
Y7891D01*
X686913Y7936D01*
X686903Y7976D01*
X686898Y8016D01*
X686883Y8061D01*
X686873Y8101D01*
X686858Y8141D01*
X686838Y8181D01*
X686823Y8216D01*
X686803Y8256D01*
X686703Y8396D01*
X686673Y8426D01*
Y9556D01*
X686663Y9681D01*
X686623Y9806D01*
X686563Y9916D01*
X686483Y10016D01*
X686383Y10096D01*
X686273Y10156D01*
X686148Y10196D01*
X686023Y10206D01*
X685898Y10196D01*
X685773Y10156D01*
X685663Y10096D01*
X685563Y10016D01*
X685483Y9916D01*
X685423Y9806D01*
X685383Y9681D01*
X685373Y9556D01*
Y8426D01*
X685343Y8396D01*
X685243Y8256D01*
X685223Y8216D01*
X685208Y8181D01*
X685188Y8141D01*
X685173Y8101D01*
X685163Y8061D01*
X685148Y8016D01*
X685143Y7976D01*
X685133Y7936D01*
X685128Y7891D01*
Y7851D01*
X685123Y7806D01*
X685128Y7761D01*
Y7721D01*
X685133Y7676D01*
X685143Y7636D01*
X685148Y7596D01*
X685163Y7551D01*
X685173Y7511D01*
X685188Y7471D01*
X685208Y7431D01*
X685223Y7396D01*
X685243Y7356D01*
X685343Y7216D01*
X685373Y7186D01*
Y3756D01*
X685383Y3631D01*
X685423Y3506D01*
X685483Y3396D01*
X685563Y3296D01*
X685663Y3216D01*
X685773Y3156D01*
X685898Y3116D01*
X686023Y3106D01*
G37*
G36*
G01X681299D02*
X681424Y3116D01*
X681549Y3156D01*
X681659Y3216D01*
X681759Y3296D01*
X681839Y3396D01*
X681899Y3506D01*
X681939Y3631D01*
X681949Y3756D01*
Y7186D01*
X681979Y7216D01*
X682079Y7356D01*
X682099Y7396D01*
X682114Y7431D01*
X682134Y7471D01*
X682149Y7511D01*
X682159Y7551D01*
X682174Y7596D01*
X682179Y7636D01*
X682189Y7676D01*
X682194Y7721D01*
Y7761D01*
X682199Y7806D01*
X682194Y7851D01*
Y7891D01*
X682189Y7936D01*
X682179Y7976D01*
X682174Y8016D01*
X682159Y8061D01*
X682149Y8101D01*
X682134Y8141D01*
X682114Y8181D01*
X682099Y8216D01*
X682079Y8256D01*
X681979Y8396D01*
X681949Y8426D01*
Y9556D01*
X681939Y9681D01*
X681899Y9806D01*
X681839Y9916D01*
X681759Y10016D01*
X681659Y10096D01*
X681549Y10156D01*
X681424Y10196D01*
X681299Y10206D01*
X681174Y10196D01*
X681049Y10156D01*
X680939Y10096D01*
X680839Y10016D01*
X680759Y9916D01*
X680699Y9806D01*
X680659Y9681D01*
X680649Y9556D01*
Y8426D01*
X680619Y8396D01*
X680519Y8256D01*
X680499Y8216D01*
X680484Y8181D01*
X680464Y8141D01*
X680449Y8101D01*
X680439Y8061D01*
X680424Y8016D01*
X680419Y7976D01*
X680409Y7936D01*
X680404Y7891D01*
Y7851D01*
X680399Y7806D01*
X680404Y7761D01*
Y7721D01*
X680409Y7676D01*
X680419Y7636D01*
X680424Y7596D01*
X680439Y7551D01*
X680449Y7511D01*
X680464Y7471D01*
X680484Y7431D01*
X680499Y7396D01*
X680519Y7356D01*
X680619Y7216D01*
X680649Y7186D01*
Y3756D01*
X680659Y3631D01*
X680699Y3506D01*
X680759Y3396D01*
X680839Y3296D01*
X680939Y3216D01*
X681049Y3156D01*
X681174Y3116D01*
X681299Y3106D01*
G37*
G36*
G01X709645D02*
X709770Y3116D01*
X709895Y3156D01*
X710005Y3216D01*
X710105Y3296D01*
X710185Y3396D01*
X710245Y3506D01*
X710285Y3631D01*
X710295Y3756D01*
Y7186D01*
X710325Y7216D01*
X710425Y7356D01*
X710445Y7396D01*
X710460Y7431D01*
X710480Y7471D01*
X710495Y7511D01*
X710505Y7551D01*
X710520Y7596D01*
X710525Y7636D01*
X710535Y7676D01*
X710540Y7721D01*
Y7761D01*
X710545Y7806D01*
X710540Y7851D01*
Y7891D01*
X710535Y7936D01*
X710525Y7976D01*
X710520Y8016D01*
X710505Y8061D01*
X710495Y8101D01*
X710480Y8141D01*
X710460Y8181D01*
X710445Y8216D01*
X710425Y8256D01*
X710325Y8396D01*
X710295Y8426D01*
Y9556D01*
X710285Y9681D01*
X710245Y9806D01*
X710185Y9916D01*
X710105Y10016D01*
X710005Y10096D01*
X709895Y10156D01*
X709770Y10196D01*
X709645Y10206D01*
X709520Y10196D01*
X709395Y10156D01*
X709285Y10096D01*
X709185Y10016D01*
X709105Y9916D01*
X709045Y9806D01*
X709005Y9681D01*
X708995Y9556D01*
Y8426D01*
X708965Y8396D01*
X708865Y8256D01*
X708845Y8216D01*
X708830Y8181D01*
X708810Y8141D01*
X708795Y8101D01*
X708785Y8061D01*
X708770Y8016D01*
X708765Y7976D01*
X708755Y7936D01*
X708750Y7891D01*
Y7851D01*
X708745Y7806D01*
X708750Y7761D01*
Y7721D01*
X708755Y7676D01*
X708765Y7636D01*
X708770Y7596D01*
X708785Y7551D01*
X708795Y7511D01*
X708810Y7471D01*
X708830Y7431D01*
X708845Y7396D01*
X708865Y7356D01*
X708965Y7216D01*
X708995Y7186D01*
Y3756D01*
X709005Y3631D01*
X709045Y3506D01*
X709105Y3396D01*
X709185Y3296D01*
X709285Y3216D01*
X709395Y3156D01*
X709520Y3116D01*
X709645Y3106D01*
G37*
G36*
G01X704921D02*
X705046Y3116D01*
X705171Y3156D01*
X705281Y3216D01*
X705381Y3296D01*
X705461Y3396D01*
X705521Y3506D01*
X705561Y3631D01*
X705571Y3756D01*
Y7186D01*
X705601Y7216D01*
X705701Y7356D01*
X705721Y7396D01*
X705736Y7431D01*
X705756Y7471D01*
X705771Y7511D01*
X705781Y7551D01*
X705796Y7596D01*
X705801Y7636D01*
X705811Y7676D01*
X705816Y7721D01*
Y7761D01*
X705821Y7806D01*
X705816Y7851D01*
Y7891D01*
X705811Y7936D01*
X705801Y7976D01*
X705796Y8016D01*
X705781Y8061D01*
X705771Y8101D01*
X705756Y8141D01*
X705736Y8181D01*
X705721Y8216D01*
X705701Y8256D01*
X705601Y8396D01*
X705571Y8426D01*
Y9556D01*
X705561Y9681D01*
X705521Y9806D01*
X705461Y9916D01*
X705381Y10016D01*
X705281Y10096D01*
X705171Y10156D01*
X705046Y10196D01*
X704921Y10206D01*
X704796Y10196D01*
X704671Y10156D01*
X704561Y10096D01*
X704461Y10016D01*
X704381Y9916D01*
X704321Y9806D01*
X704281Y9681D01*
X704271Y9556D01*
Y8426D01*
X704241Y8396D01*
X704141Y8256D01*
X704121Y8216D01*
X704106Y8181D01*
X704086Y8141D01*
X704071Y8101D01*
X704061Y8061D01*
X704046Y8016D01*
X704041Y7976D01*
X704031Y7936D01*
X704026Y7891D01*
Y7851D01*
X704021Y7806D01*
X704026Y7761D01*
Y7721D01*
X704031Y7676D01*
X704041Y7636D01*
X704046Y7596D01*
X704061Y7551D01*
X704071Y7511D01*
X704086Y7471D01*
X704106Y7431D01*
X704121Y7396D01*
X704141Y7356D01*
X704241Y7216D01*
X704271Y7186D01*
Y3756D01*
X704281Y3631D01*
X704321Y3506D01*
X704381Y3396D01*
X704461Y3296D01*
X704561Y3216D01*
X704671Y3156D01*
X704796Y3116D01*
X704921Y3106D01*
G37*
G36*
G01X700197D02*
X700322Y3116D01*
X700447Y3156D01*
X700557Y3216D01*
X700657Y3296D01*
X700737Y3396D01*
X700797Y3506D01*
X700837Y3631D01*
X700847Y3756D01*
Y7186D01*
X700877Y7216D01*
X700977Y7356D01*
X700997Y7396D01*
X701012Y7431D01*
X701032Y7471D01*
X701047Y7511D01*
X701057Y7551D01*
X701072Y7596D01*
X701077Y7636D01*
X701087Y7676D01*
X701092Y7721D01*
Y7761D01*
X701097Y7806D01*
X701092Y7851D01*
Y7891D01*
X701087Y7936D01*
X701077Y7976D01*
X701072Y8016D01*
X701057Y8061D01*
X701047Y8101D01*
X701032Y8141D01*
X701012Y8181D01*
X700997Y8216D01*
X700977Y8256D01*
X700877Y8396D01*
X700847Y8426D01*
Y9556D01*
X700837Y9681D01*
X700797Y9806D01*
X700737Y9916D01*
X700657Y10016D01*
X700557Y10096D01*
X700447Y10156D01*
X700322Y10196D01*
X700197Y10206D01*
X700072Y10196D01*
X699947Y10156D01*
X699837Y10096D01*
X699737Y10016D01*
X699657Y9916D01*
X699597Y9806D01*
X699557Y9681D01*
X699547Y9556D01*
Y8426D01*
X699517Y8396D01*
X699417Y8256D01*
X699397Y8216D01*
X699382Y8181D01*
X699362Y8141D01*
X699347Y8101D01*
X699337Y8061D01*
X699322Y8016D01*
X699317Y7976D01*
X699307Y7936D01*
X699302Y7891D01*
Y7851D01*
X699297Y7806D01*
X699302Y7761D01*
Y7721D01*
X699307Y7676D01*
X699317Y7636D01*
X699322Y7596D01*
X699337Y7551D01*
X699347Y7511D01*
X699362Y7471D01*
X699382Y7431D01*
X699397Y7396D01*
X699417Y7356D01*
X699517Y7216D01*
X699547Y7186D01*
Y3756D01*
X699557Y3631D01*
X699597Y3506D01*
X699657Y3396D01*
X699737Y3296D01*
X699837Y3216D01*
X699947Y3156D01*
X700072Y3116D01*
X700197Y3106D01*
G37*
G36*
G01X723819D02*
X723944Y3116D01*
X724069Y3156D01*
X724179Y3216D01*
X724279Y3296D01*
X724359Y3396D01*
X724419Y3506D01*
X724459Y3631D01*
X724469Y3756D01*
Y7186D01*
X724499Y7216D01*
X724599Y7356D01*
X724619Y7396D01*
X724634Y7431D01*
X724654Y7471D01*
X724669Y7511D01*
X724679Y7551D01*
X724694Y7596D01*
X724699Y7636D01*
X724709Y7676D01*
X724714Y7721D01*
Y7761D01*
X724719Y7806D01*
X724714Y7851D01*
Y7891D01*
X724709Y7936D01*
X724699Y7976D01*
X724694Y8016D01*
X724679Y8061D01*
X724669Y8101D01*
X724654Y8141D01*
X724634Y8181D01*
X724619Y8216D01*
X724599Y8256D01*
X724499Y8396D01*
X724469Y8426D01*
Y9556D01*
X724459Y9681D01*
X724419Y9806D01*
X724359Y9916D01*
X724279Y10016D01*
X724179Y10096D01*
X724069Y10156D01*
X723944Y10196D01*
X723819Y10206D01*
X723694Y10196D01*
X723569Y10156D01*
X723459Y10096D01*
X723359Y10016D01*
X723279Y9916D01*
X723219Y9806D01*
X723179Y9681D01*
X723169Y9556D01*
Y8426D01*
X723139Y8396D01*
X723039Y8256D01*
X723019Y8216D01*
X723004Y8181D01*
X722984Y8141D01*
X722969Y8101D01*
X722959Y8061D01*
X722944Y8016D01*
X722939Y7976D01*
X722929Y7936D01*
X722924Y7891D01*
Y7851D01*
X722919Y7806D01*
X722924Y7761D01*
Y7721D01*
X722929Y7676D01*
X722939Y7636D01*
X722944Y7596D01*
X722959Y7551D01*
X722969Y7511D01*
X722984Y7471D01*
X723004Y7431D01*
X723019Y7396D01*
X723039Y7356D01*
X723139Y7216D01*
X723169Y7186D01*
Y3756D01*
X723179Y3631D01*
X723219Y3506D01*
X723279Y3396D01*
X723359Y3296D01*
X723459Y3216D01*
X723569Y3156D01*
X723694Y3116D01*
X723819Y3106D01*
G37*
G36*
G01X719094D02*
X719219Y3116D01*
X719344Y3156D01*
X719454Y3216D01*
X719554Y3296D01*
X719634Y3396D01*
X719694Y3506D01*
X719734Y3631D01*
X719744Y3756D01*
Y7186D01*
X719774Y7216D01*
X719874Y7356D01*
X719894Y7396D01*
X719909Y7431D01*
X719929Y7471D01*
X719944Y7511D01*
X719954Y7551D01*
X719969Y7596D01*
X719974Y7636D01*
X719984Y7676D01*
X719989Y7721D01*
Y7761D01*
X719994Y7806D01*
X719989Y7851D01*
Y7891D01*
X719984Y7936D01*
X719974Y7976D01*
X719969Y8016D01*
X719954Y8061D01*
X719944Y8101D01*
X719929Y8141D01*
X719909Y8181D01*
X719894Y8216D01*
X719874Y8256D01*
X719774Y8396D01*
X719744Y8426D01*
Y9556D01*
X719734Y9681D01*
X719694Y9806D01*
X719634Y9916D01*
X719554Y10016D01*
X719454Y10096D01*
X719344Y10156D01*
X719219Y10196D01*
X719094Y10206D01*
X718969Y10196D01*
X718844Y10156D01*
X718734Y10096D01*
X718634Y10016D01*
X718554Y9916D01*
X718494Y9806D01*
X718454Y9681D01*
X718444Y9556D01*
Y8426D01*
X718414Y8396D01*
X718314Y8256D01*
X718294Y8216D01*
X718279Y8181D01*
X718259Y8141D01*
X718244Y8101D01*
X718234Y8061D01*
X718219Y8016D01*
X718214Y7976D01*
X718204Y7936D01*
X718199Y7891D01*
Y7851D01*
X718194Y7806D01*
X718199Y7761D01*
Y7721D01*
X718204Y7676D01*
X718214Y7636D01*
X718219Y7596D01*
X718234Y7551D01*
X718244Y7511D01*
X718259Y7471D01*
X718279Y7431D01*
X718294Y7396D01*
X718314Y7356D01*
X718414Y7216D01*
X718444Y7186D01*
Y3756D01*
X718454Y3631D01*
X718494Y3506D01*
X718554Y3396D01*
X718634Y3296D01*
X718734Y3216D01*
X718844Y3156D01*
X718969Y3116D01*
X719094Y3106D01*
G37*
G36*
G01X714370D02*
X714495Y3116D01*
X714620Y3156D01*
X714730Y3216D01*
X714830Y3296D01*
X714910Y3396D01*
X714970Y3506D01*
X715010Y3631D01*
X715020Y3756D01*
Y7186D01*
X715050Y7216D01*
X715150Y7356D01*
X715170Y7396D01*
X715185Y7431D01*
X715205Y7471D01*
X715220Y7511D01*
X715230Y7551D01*
X715245Y7596D01*
X715250Y7636D01*
X715260Y7676D01*
X715265Y7721D01*
Y7761D01*
X715270Y7806D01*
X715265Y7851D01*
Y7891D01*
X715260Y7936D01*
X715250Y7976D01*
X715245Y8016D01*
X715230Y8061D01*
X715220Y8101D01*
X715205Y8141D01*
X715185Y8181D01*
X715170Y8216D01*
X715150Y8256D01*
X715050Y8396D01*
X715020Y8426D01*
Y9556D01*
X715010Y9681D01*
X714970Y9806D01*
X714910Y9916D01*
X714830Y10016D01*
X714730Y10096D01*
X714620Y10156D01*
X714495Y10196D01*
X714370Y10206D01*
X714245Y10196D01*
X714120Y10156D01*
X714010Y10096D01*
X713910Y10016D01*
X713830Y9916D01*
X713770Y9806D01*
X713730Y9681D01*
X713720Y9556D01*
Y8426D01*
X713690Y8396D01*
X713590Y8256D01*
X713570Y8216D01*
X713555Y8181D01*
X713535Y8141D01*
X713520Y8101D01*
X713510Y8061D01*
X713495Y8016D01*
X713490Y7976D01*
X713480Y7936D01*
X713475Y7891D01*
Y7851D01*
X713470Y7806D01*
X713475Y7761D01*
Y7721D01*
X713480Y7676D01*
X713490Y7636D01*
X713495Y7596D01*
X713510Y7551D01*
X713520Y7511D01*
X713535Y7471D01*
X713555Y7431D01*
X713570Y7396D01*
X713590Y7356D01*
X713690Y7216D01*
X713720Y7186D01*
Y3756D01*
X713730Y3631D01*
X713770Y3506D01*
X713830Y3396D01*
X713910Y3296D01*
X714010Y3216D01*
X714120Y3156D01*
X714245Y3116D01*
X714370Y3106D01*
G37*
G36*
G01X737992D02*
X738117Y3116D01*
X738242Y3156D01*
X738352Y3216D01*
X738452Y3296D01*
X738532Y3396D01*
X738592Y3506D01*
X738632Y3631D01*
X738642Y3756D01*
Y7186D01*
X738672Y7216D01*
X738772Y7356D01*
X738792Y7396D01*
X738807Y7431D01*
X738827Y7471D01*
X738842Y7511D01*
X738852Y7551D01*
X738867Y7596D01*
X738872Y7636D01*
X738882Y7676D01*
X738887Y7721D01*
Y7761D01*
X738892Y7806D01*
X738887Y7851D01*
Y7891D01*
X738882Y7936D01*
X738872Y7976D01*
X738867Y8016D01*
X738852Y8061D01*
X738842Y8101D01*
X738827Y8141D01*
X738807Y8181D01*
X738792Y8216D01*
X738772Y8256D01*
X738672Y8396D01*
X738642Y8426D01*
Y9556D01*
X738632Y9681D01*
X738592Y9806D01*
X738532Y9916D01*
X738452Y10016D01*
X738352Y10096D01*
X738242Y10156D01*
X738117Y10196D01*
X737992Y10206D01*
X737867Y10196D01*
X737742Y10156D01*
X737632Y10096D01*
X737532Y10016D01*
X737452Y9916D01*
X737392Y9806D01*
X737352Y9681D01*
X737342Y9556D01*
Y8426D01*
X737312Y8396D01*
X737212Y8256D01*
X737192Y8216D01*
X737177Y8181D01*
X737157Y8141D01*
X737142Y8101D01*
X737132Y8061D01*
X737117Y8016D01*
X737112Y7976D01*
X737102Y7936D01*
X737097Y7891D01*
Y7851D01*
X737092Y7806D01*
X737097Y7761D01*
Y7721D01*
X737102Y7676D01*
X737112Y7636D01*
X737117Y7596D01*
X737132Y7551D01*
X737142Y7511D01*
X737157Y7471D01*
X737177Y7431D01*
X737192Y7396D01*
X737212Y7356D01*
X737312Y7216D01*
X737342Y7186D01*
Y3756D01*
X737352Y3631D01*
X737392Y3506D01*
X737452Y3396D01*
X737532Y3296D01*
X737632Y3216D01*
X737742Y3156D01*
X737867Y3116D01*
X737992Y3106D01*
G37*
G36*
G01X733267D02*
X733392Y3116D01*
X733517Y3156D01*
X733627Y3216D01*
X733727Y3296D01*
X733807Y3396D01*
X733867Y3506D01*
X733907Y3631D01*
X733917Y3756D01*
Y7186D01*
X733947Y7216D01*
X734047Y7356D01*
X734067Y7396D01*
X734082Y7431D01*
X734102Y7471D01*
X734117Y7511D01*
X734127Y7551D01*
X734142Y7596D01*
X734147Y7636D01*
X734157Y7676D01*
X734162Y7721D01*
Y7761D01*
X734167Y7806D01*
X734162Y7851D01*
Y7891D01*
X734157Y7936D01*
X734147Y7976D01*
X734142Y8016D01*
X734127Y8061D01*
X734117Y8101D01*
X734102Y8141D01*
X734082Y8181D01*
X734067Y8216D01*
X734047Y8256D01*
X733947Y8396D01*
X733917Y8426D01*
Y9556D01*
X733907Y9681D01*
X733867Y9806D01*
X733807Y9916D01*
X733727Y10016D01*
X733627Y10096D01*
X733517Y10156D01*
X733392Y10196D01*
X733267Y10206D01*
X733142Y10196D01*
X733017Y10156D01*
X732907Y10096D01*
X732807Y10016D01*
X732727Y9916D01*
X732667Y9806D01*
X732627Y9681D01*
X732617Y9556D01*
Y8426D01*
X732587Y8396D01*
X732487Y8256D01*
X732467Y8216D01*
X732452Y8181D01*
X732432Y8141D01*
X732417Y8101D01*
X732407Y8061D01*
X732392Y8016D01*
X732387Y7976D01*
X732377Y7936D01*
X732372Y7891D01*
Y7851D01*
X732367Y7806D01*
X732372Y7761D01*
Y7721D01*
X732377Y7676D01*
X732387Y7636D01*
X732392Y7596D01*
X732407Y7551D01*
X732417Y7511D01*
X732432Y7471D01*
X732452Y7431D01*
X732467Y7396D01*
X732487Y7356D01*
X732587Y7216D01*
X732617Y7186D01*
Y3756D01*
X732627Y3631D01*
X732667Y3506D01*
X732727Y3396D01*
X732807Y3296D01*
X732907Y3216D01*
X733017Y3156D01*
X733142Y3116D01*
X733267Y3106D01*
G37*
G36*
G01X728543D02*
X728668Y3116D01*
X728793Y3156D01*
X728903Y3216D01*
X729003Y3296D01*
X729083Y3396D01*
X729143Y3506D01*
X729183Y3631D01*
X729193Y3756D01*
Y7186D01*
X729223Y7216D01*
X729323Y7356D01*
X729343Y7396D01*
X729358Y7431D01*
X729378Y7471D01*
X729393Y7511D01*
X729403Y7551D01*
X729418Y7596D01*
X729423Y7636D01*
X729433Y7676D01*
X729438Y7721D01*
Y7761D01*
X729443Y7806D01*
X729438Y7851D01*
Y7891D01*
X729433Y7936D01*
X729423Y7976D01*
X729418Y8016D01*
X729403Y8061D01*
X729393Y8101D01*
X729378Y8141D01*
X729358Y8181D01*
X729343Y8216D01*
X729323Y8256D01*
X729223Y8396D01*
X729193Y8426D01*
Y9556D01*
X729183Y9681D01*
X729143Y9806D01*
X729083Y9916D01*
X729003Y10016D01*
X728903Y10096D01*
X728793Y10156D01*
X728668Y10196D01*
X728543Y10206D01*
X728418Y10196D01*
X728293Y10156D01*
X728183Y10096D01*
X728083Y10016D01*
X728003Y9916D01*
X727943Y9806D01*
X727903Y9681D01*
X727893Y9556D01*
Y8426D01*
X727863Y8396D01*
X727763Y8256D01*
X727743Y8216D01*
X727728Y8181D01*
X727708Y8141D01*
X727693Y8101D01*
X727683Y8061D01*
X727668Y8016D01*
X727663Y7976D01*
X727653Y7936D01*
X727648Y7891D01*
Y7851D01*
X727643Y7806D01*
X727648Y7761D01*
Y7721D01*
X727653Y7676D01*
X727663Y7636D01*
X727668Y7596D01*
X727683Y7551D01*
X727693Y7511D01*
X727708Y7471D01*
X727728Y7431D01*
X727743Y7396D01*
X727763Y7356D01*
X727863Y7216D01*
X727893Y7186D01*
Y3756D01*
X727903Y3631D01*
X727943Y3506D01*
X728003Y3396D01*
X728083Y3296D01*
X728183Y3216D01*
X728293Y3156D01*
X728418Y3116D01*
X728543Y3106D01*
G37*
G36*
G01X752165D02*
X752290Y3116D01*
X752415Y3156D01*
X752525Y3216D01*
X752625Y3296D01*
X752705Y3396D01*
X752765Y3506D01*
X752805Y3631D01*
X752815Y3756D01*
Y7186D01*
X752845Y7216D01*
X752945Y7356D01*
X752965Y7396D01*
X752980Y7431D01*
X753000Y7471D01*
X753015Y7511D01*
X753025Y7551D01*
X753040Y7596D01*
X753045Y7636D01*
X753055Y7676D01*
X753060Y7721D01*
Y7761D01*
X753065Y7806D01*
X753060Y7851D01*
Y7891D01*
X753055Y7936D01*
X753045Y7976D01*
X753040Y8016D01*
X753025Y8061D01*
X753015Y8101D01*
X753000Y8141D01*
X752980Y8181D01*
X752965Y8216D01*
X752945Y8256D01*
X752845Y8396D01*
X752815Y8426D01*
Y9556D01*
X752805Y9681D01*
X752765Y9806D01*
X752705Y9916D01*
X752625Y10016D01*
X752525Y10096D01*
X752415Y10156D01*
X752290Y10196D01*
X752165Y10206D01*
X752040Y10196D01*
X751915Y10156D01*
X751805Y10096D01*
X751705Y10016D01*
X751625Y9916D01*
X751565Y9806D01*
X751525Y9681D01*
X751515Y9556D01*
Y8426D01*
X751485Y8396D01*
X751385Y8256D01*
X751365Y8216D01*
X751350Y8181D01*
X751330Y8141D01*
X751315Y8101D01*
X751305Y8061D01*
X751290Y8016D01*
X751285Y7976D01*
X751275Y7936D01*
X751270Y7891D01*
Y7851D01*
X751265Y7806D01*
X751270Y7761D01*
Y7721D01*
X751275Y7676D01*
X751285Y7636D01*
X751290Y7596D01*
X751305Y7551D01*
X751315Y7511D01*
X751330Y7471D01*
X751350Y7431D01*
X751365Y7396D01*
X751385Y7356D01*
X751485Y7216D01*
X751515Y7186D01*
Y3756D01*
X751525Y3631D01*
X751565Y3506D01*
X751625Y3396D01*
X751705Y3296D01*
X751805Y3216D01*
X751915Y3156D01*
X752040Y3116D01*
X752165Y3106D01*
G37*
G36*
G01X747441D02*
X747566Y3116D01*
X747691Y3156D01*
X747801Y3216D01*
X747901Y3296D01*
X747981Y3396D01*
X748041Y3506D01*
X748081Y3631D01*
X748091Y3756D01*
Y7186D01*
X748121Y7216D01*
X748221Y7356D01*
X748241Y7396D01*
X748256Y7431D01*
X748276Y7471D01*
X748291Y7511D01*
X748301Y7551D01*
X748316Y7596D01*
X748321Y7636D01*
X748331Y7676D01*
X748336Y7721D01*
Y7761D01*
X748341Y7806D01*
X748336Y7851D01*
Y7891D01*
X748331Y7936D01*
X748321Y7976D01*
X748316Y8016D01*
X748301Y8061D01*
X748291Y8101D01*
X748276Y8141D01*
X748256Y8181D01*
X748241Y8216D01*
X748221Y8256D01*
X748121Y8396D01*
X748091Y8426D01*
Y9556D01*
X748081Y9681D01*
X748041Y9806D01*
X747981Y9916D01*
X747901Y10016D01*
X747801Y10096D01*
X747691Y10156D01*
X747566Y10196D01*
X747441Y10206D01*
X747316Y10196D01*
X747191Y10156D01*
X747081Y10096D01*
X746981Y10016D01*
X746901Y9916D01*
X746841Y9806D01*
X746801Y9681D01*
X746791Y9556D01*
Y8426D01*
X746761Y8396D01*
X746661Y8256D01*
X746641Y8216D01*
X746626Y8181D01*
X746606Y8141D01*
X746591Y8101D01*
X746581Y8061D01*
X746566Y8016D01*
X746561Y7976D01*
X746551Y7936D01*
X746546Y7891D01*
Y7851D01*
X746541Y7806D01*
X746546Y7761D01*
Y7721D01*
X746551Y7676D01*
X746561Y7636D01*
X746566Y7596D01*
X746581Y7551D01*
X746591Y7511D01*
X746606Y7471D01*
X746626Y7431D01*
X746641Y7396D01*
X746661Y7356D01*
X746761Y7216D01*
X746791Y7186D01*
Y3756D01*
X746801Y3631D01*
X746841Y3506D01*
X746901Y3396D01*
X746981Y3296D01*
X747081Y3216D01*
X747191Y3156D01*
X747316Y3116D01*
X747441Y3106D01*
G37*
G36*
G01X742716D02*
X742841Y3116D01*
X742966Y3156D01*
X743076Y3216D01*
X743176Y3296D01*
X743256Y3396D01*
X743316Y3506D01*
X743356Y3631D01*
X743366Y3756D01*
Y7186D01*
X743396Y7216D01*
X743496Y7356D01*
X743516Y7396D01*
X743531Y7431D01*
X743551Y7471D01*
X743566Y7511D01*
X743576Y7551D01*
X743591Y7596D01*
X743596Y7636D01*
X743606Y7676D01*
X743611Y7721D01*
Y7761D01*
X743616Y7806D01*
X743611Y7851D01*
Y7891D01*
X743606Y7936D01*
X743596Y7976D01*
X743591Y8016D01*
X743576Y8061D01*
X743566Y8101D01*
X743551Y8141D01*
X743531Y8181D01*
X743516Y8216D01*
X743496Y8256D01*
X743396Y8396D01*
X743366Y8426D01*
Y9556D01*
X743356Y9681D01*
X743316Y9806D01*
X743256Y9916D01*
X743176Y10016D01*
X743076Y10096D01*
X742966Y10156D01*
X742841Y10196D01*
X742716Y10206D01*
X742591Y10196D01*
X742466Y10156D01*
X742356Y10096D01*
X742256Y10016D01*
X742176Y9916D01*
X742116Y9806D01*
X742076Y9681D01*
X742066Y9556D01*
Y8426D01*
X742036Y8396D01*
X741936Y8256D01*
X741916Y8216D01*
X741901Y8181D01*
X741881Y8141D01*
X741866Y8101D01*
X741856Y8061D01*
X741841Y8016D01*
X741836Y7976D01*
X741826Y7936D01*
X741821Y7891D01*
Y7851D01*
X741816Y7806D01*
X741821Y7761D01*
Y7721D01*
X741826Y7676D01*
X741836Y7636D01*
X741841Y7596D01*
X741856Y7551D01*
X741866Y7511D01*
X741881Y7471D01*
X741901Y7431D01*
X741916Y7396D01*
X741936Y7356D01*
X742036Y7216D01*
X742066Y7186D01*
Y3756D01*
X742076Y3631D01*
X742116Y3506D01*
X742176Y3396D01*
X742256Y3296D01*
X742356Y3216D01*
X742466Y3156D01*
X742591Y3116D01*
X742716Y3106D01*
G37*
G54D98*
G01X285200Y95000D02*
X285801Y94399D01*
Y87499D01*
G01D02*
X286700Y86600D01*
G54D89*
X787215Y261024D03*
X782077D03*
X787215Y270866D03*
X782077D03*
X794969Y134600D03*
X789831D03*
X794969Y129300D03*
X789831D03*
X794969Y124000D03*
X789831D03*
X795069Y152300D03*
X789931D03*
X794969Y139900D03*
X789831D03*
X795069Y157500D03*
X789931D03*
X795069Y162700D03*
X789931D03*
X795069Y167900D03*
X789931D03*
G54D99*
G01X315451Y123219D02*
X316552D01*
X317031Y123698D01*
Y124900D01*
X315931Y126000D01*
X313932D01*
X312732Y124800D01*
X307000D01*
X303800Y121600D01*
Y120400D01*
X304190Y120010D01*
Y118810D01*
X303800Y118420D01*
Y116275D01*
X304075Y116000D01*
Y115900D01*
G01X319418Y123225D02*
X318376D01*
X317831Y123770D01*
Y125232D01*
X316263Y126800D01*
X313600D01*
X312400Y125600D01*
X306668D01*
X303000Y121932D01*
Y116275D01*
X302725Y116000D01*
Y115900D01*
G01X332000Y150800D02*
X330525Y149325D01*
X329222D01*
X327753Y150794D01*
X324588D01*
M02*
